G04*
G04 #@! TF.GenerationSoftware,Altium Limited,Altium Designer,23.7.1 (13)*
G04*
G04 Layer_Color=8388736*
%FSLAX25Y25*%
%MOIN*%
G70*
G04*
G04 #@! TF.SameCoordinates,AF00DCEB-AC48-4C7C-91EA-99F42E284231*
G04*
G04*
G04 #@! TF.FilePolarity,Positive*
G04*
G01*
G75*
%ADD15C,0.00787*%
G36*
X588988Y4611D02*
X589013Y4608D01*
X589046Y4604D01*
X589082Y4597D01*
X589122Y4586D01*
X589206Y4560D01*
X589253Y4542D01*
X589297Y4517D01*
X589344Y4491D01*
X589388Y4462D01*
X589432Y4425D01*
X589475Y4386D01*
X589479Y4382D01*
X589486Y4375D01*
X589497Y4364D01*
X589508Y4346D01*
X589526Y4320D01*
X589545Y4295D01*
X589563Y4262D01*
X589585Y4225D01*
X589607Y4185D01*
X589625Y4138D01*
X589643Y4087D01*
X589661Y4036D01*
X589672Y3978D01*
X589683Y3916D01*
X589690Y3854D01*
X589694Y3785D01*
Y3748D01*
X589690Y3723D01*
X589687Y3690D01*
X589683Y3654D01*
X589676Y3614D01*
X589665Y3570D01*
X589639Y3472D01*
X589621Y3421D01*
X589603Y3374D01*
X589577Y3323D01*
X589548Y3272D01*
X589515Y3224D01*
X589475Y3181D01*
X589472Y3177D01*
X589465Y3170D01*
X589454Y3159D01*
X589435Y3144D01*
X589414Y3130D01*
X589388Y3108D01*
X589359Y3090D01*
X589323Y3068D01*
X589286Y3046D01*
X589243Y3028D01*
X589151Y2991D01*
X589097Y2977D01*
X589042Y2966D01*
X588984Y2959D01*
X588926Y2955D01*
X588922D01*
X588915D01*
X588900D01*
X588886Y2959D01*
X588864D01*
X588838Y2962D01*
X588780Y2970D01*
X588715Y2984D01*
X588649Y3006D01*
X588580Y3039D01*
X588515Y3079D01*
X588511D01*
X588507Y3086D01*
X588489Y3101D01*
X588460Y3130D01*
X588423Y3170D01*
X588387Y3221D01*
X588347Y3283D01*
X588314Y3352D01*
X588289Y3435D01*
Y3432D01*
X588285Y3428D01*
X588281Y3417D01*
X588274Y3403D01*
X588260Y3370D01*
X588238Y3326D01*
X588209Y3279D01*
X588172Y3232D01*
X588132Y3188D01*
X588089Y3148D01*
X588081Y3144D01*
X588067Y3133D01*
X588038Y3119D01*
X588001Y3104D01*
X587954Y3086D01*
X587899Y3071D01*
X587838Y3060D01*
X587772Y3057D01*
X587768D01*
X587761D01*
X587746D01*
X587725Y3060D01*
X587703Y3064D01*
X587674Y3068D01*
X587612Y3082D01*
X587539Y3104D01*
X587463Y3141D01*
X587423Y3162D01*
X587383Y3188D01*
X587346Y3221D01*
X587310Y3254D01*
X587306Y3257D01*
X587302Y3264D01*
X587291Y3275D01*
X587281Y3290D01*
X587266Y3308D01*
X587251Y3334D01*
X587233Y3363D01*
X587215Y3392D01*
X587197Y3428D01*
X587179Y3468D01*
X587164Y3512D01*
X587149Y3559D01*
X587128Y3661D01*
X587124Y3719D01*
X587120Y3778D01*
Y3810D01*
X587124Y3832D01*
X587128Y3861D01*
X587131Y3894D01*
X587135Y3931D01*
X587146Y3967D01*
X587168Y4054D01*
X587200Y4142D01*
X587222Y4185D01*
X587248Y4229D01*
X587281Y4269D01*
X587313Y4309D01*
X587317Y4313D01*
X587321Y4316D01*
X587331Y4327D01*
X587346Y4342D01*
X587368Y4356D01*
X587390Y4375D01*
X587444Y4411D01*
X587513Y4447D01*
X587594Y4480D01*
X587685Y4506D01*
X587732Y4509D01*
X587783Y4513D01*
X587786D01*
X587790D01*
X587812D01*
X587845Y4509D01*
X587885Y4502D01*
X587936Y4491D01*
X587987Y4473D01*
X588038Y4451D01*
X588089Y4418D01*
X588096Y4415D01*
X588110Y4400D01*
X588132Y4378D01*
X588161Y4349D01*
X588194Y4309D01*
X588227Y4262D01*
X588260Y4207D01*
X588289Y4142D01*
Y4145D01*
X588293Y4153D01*
X588296Y4163D01*
X588303Y4178D01*
X588322Y4222D01*
X588347Y4273D01*
X588383Y4327D01*
X588423Y4386D01*
X588475Y4440D01*
X588533Y4491D01*
X588536D01*
X588540Y4495D01*
X588562Y4509D01*
X588598Y4531D01*
X588646Y4553D01*
X588704Y4575D01*
X588773Y4597D01*
X588849Y4611D01*
X588933Y4615D01*
X588937D01*
X588948D01*
X588966D01*
X588988Y4611D01*
D02*
G37*
G36*
X588962Y2649D02*
X588991Y2646D01*
X589024Y2638D01*
X589060Y2631D01*
X589101Y2624D01*
X589188Y2595D01*
X589235Y2573D01*
X589279Y2551D01*
X589326Y2522D01*
X589373Y2489D01*
X589421Y2453D01*
X589465Y2409D01*
X589468Y2405D01*
X589475Y2398D01*
X589486Y2383D01*
X589501Y2365D01*
X589519Y2344D01*
X589537Y2314D01*
X589559Y2282D01*
X589577Y2242D01*
X589599Y2201D01*
X589621Y2154D01*
X589639Y2107D01*
X589657Y2052D01*
X589672Y1994D01*
X589683Y1932D01*
X589690Y1870D01*
X589694Y1801D01*
Y1768D01*
X589690Y1746D01*
X589687Y1717D01*
X589683Y1685D01*
X589676Y1648D01*
X589668Y1608D01*
X589647Y1521D01*
X589610Y1430D01*
X589588Y1383D01*
X589563Y1339D01*
X589530Y1295D01*
X589497Y1252D01*
X589494Y1248D01*
X589486Y1241D01*
X589475Y1230D01*
X589461Y1219D01*
X589443Y1201D01*
X589417Y1182D01*
X589392Y1161D01*
X589359Y1139D01*
X589323Y1117D01*
X589286Y1095D01*
X589199Y1055D01*
X589097Y1022D01*
X589042Y1011D01*
X588984Y1004D01*
X588944Y1313D01*
X588948D01*
X588955Y1317D01*
X588970Y1321D01*
X588988Y1324D01*
X589010Y1328D01*
X589035Y1335D01*
X589090Y1353D01*
X589155Y1379D01*
X589217Y1412D01*
X589275Y1448D01*
X589326Y1492D01*
X589330Y1499D01*
X589344Y1514D01*
X589363Y1543D01*
X589381Y1579D01*
X589403Y1623D01*
X589421Y1677D01*
X589435Y1739D01*
X589439Y1805D01*
Y1827D01*
X589435Y1841D01*
X589432Y1881D01*
X589421Y1932D01*
X589403Y1990D01*
X589377Y2052D01*
X589341Y2114D01*
X589290Y2172D01*
X589283Y2180D01*
X589261Y2198D01*
X589228Y2220D01*
X589184Y2249D01*
X589130Y2278D01*
X589068Y2300D01*
X588995Y2318D01*
X588915Y2325D01*
X588911D01*
X588904D01*
X588893D01*
X588878Y2322D01*
X588838Y2318D01*
X588791Y2307D01*
X588733Y2293D01*
X588675Y2267D01*
X588616Y2231D01*
X588562Y2183D01*
X588555Y2176D01*
X588540Y2158D01*
X588518Y2129D01*
X588493Y2089D01*
X588467Y2038D01*
X588445Y1976D01*
X588431Y1907D01*
X588423Y1830D01*
Y1798D01*
X588427Y1772D01*
X588431Y1739D01*
X588438Y1703D01*
X588445Y1659D01*
X588456Y1612D01*
X588183Y1648D01*
Y1666D01*
X588187Y1681D01*
Y1728D01*
X588180Y1768D01*
X588172Y1816D01*
X588161Y1870D01*
X588143Y1932D01*
X588118Y1990D01*
X588085Y2052D01*
Y2056D01*
X588081Y2060D01*
X588067Y2078D01*
X588041Y2103D01*
X588009Y2132D01*
X587961Y2162D01*
X587907Y2187D01*
X587845Y2205D01*
X587808Y2212D01*
X587768D01*
X587765D01*
X587761D01*
X587739D01*
X587710Y2205D01*
X587670Y2198D01*
X587626Y2183D01*
X587579Y2165D01*
X587532Y2136D01*
X587488Y2096D01*
X587484Y2092D01*
X587470Y2074D01*
X587452Y2049D01*
X587430Y2016D01*
X587412Y1972D01*
X587393Y1921D01*
X587379Y1863D01*
X587375Y1798D01*
Y1768D01*
X587383Y1736D01*
X587390Y1692D01*
X587404Y1645D01*
X587423Y1597D01*
X587452Y1546D01*
X587488Y1499D01*
X587492Y1495D01*
X587510Y1481D01*
X587535Y1459D01*
X587572Y1433D01*
X587619Y1408D01*
X587677Y1383D01*
X587746Y1361D01*
X587827Y1346D01*
X587772Y1037D01*
X587768D01*
X587757Y1040D01*
X587743Y1044D01*
X587721Y1048D01*
X587696Y1055D01*
X587666Y1066D01*
X587597Y1088D01*
X587517Y1124D01*
X587437Y1168D01*
X587361Y1222D01*
X587291Y1292D01*
X587288Y1295D01*
X587284Y1302D01*
X587277Y1313D01*
X587266Y1328D01*
X587251Y1346D01*
X587237Y1372D01*
X587222Y1397D01*
X587204Y1430D01*
X587175Y1503D01*
X587146Y1586D01*
X587128Y1685D01*
X587120Y1736D01*
Y1827D01*
X587124Y1867D01*
X587131Y1914D01*
X587142Y1972D01*
X587160Y2038D01*
X587182Y2103D01*
X587211Y2169D01*
Y2172D01*
X587215Y2176D01*
X587226Y2198D01*
X587248Y2231D01*
X587273Y2267D01*
X587310Y2311D01*
X587350Y2354D01*
X587397Y2398D01*
X587452Y2434D01*
X587459Y2438D01*
X587477Y2449D01*
X587510Y2464D01*
X587550Y2482D01*
X587597Y2500D01*
X587652Y2514D01*
X587714Y2526D01*
X587776Y2529D01*
X587783D01*
X587805D01*
X587834Y2526D01*
X587874Y2518D01*
X587921Y2507D01*
X587972Y2489D01*
X588023Y2467D01*
X588074Y2438D01*
X588081Y2434D01*
X588096Y2424D01*
X588121Y2402D01*
X588151Y2373D01*
X588183Y2336D01*
X588220Y2293D01*
X588252Y2242D01*
X588285Y2180D01*
Y2183D01*
X588289Y2191D01*
X588293Y2201D01*
X588296Y2216D01*
X588311Y2256D01*
X588333Y2307D01*
X588362Y2365D01*
X588398Y2424D01*
X588445Y2478D01*
X588500Y2529D01*
X588507Y2533D01*
X588529Y2547D01*
X588565Y2569D01*
X588613Y2591D01*
X588671Y2613D01*
X588740Y2635D01*
X588820Y2649D01*
X588908Y2653D01*
X588911D01*
X588922D01*
X588940D01*
X588962Y2649D01*
D02*
G37*
G36*
X588930Y578D02*
X588959D01*
X589028Y571D01*
X589108Y563D01*
X589192Y549D01*
X589268Y527D01*
X589341Y502D01*
X589344D01*
X589348Y498D01*
X589370Y487D01*
X589399Y469D01*
X589439Y443D01*
X589479Y407D01*
X589523Y367D01*
X589567Y316D01*
X589603Y258D01*
X589607Y250D01*
X589617Y229D01*
X589632Y196D01*
X589647Y149D01*
X589665Y90D01*
X589679Y25D01*
X589690Y-48D01*
X589694Y-128D01*
Y-161D01*
X589690Y-183D01*
X589687Y-212D01*
X589683Y-241D01*
X589668Y-317D01*
X589647Y-397D01*
X589614Y-481D01*
X589592Y-525D01*
X589567Y-565D01*
X589537Y-601D01*
X589505Y-638D01*
X589501Y-641D01*
X589497Y-645D01*
X589483Y-652D01*
X589468Y-663D01*
X589450Y-678D01*
X589425Y-692D01*
X589395Y-707D01*
X589363Y-725D01*
X589326Y-740D01*
X589283Y-754D01*
X589239Y-769D01*
X589188Y-783D01*
X589133Y-791D01*
X589071Y-802D01*
X589010Y-805D01*
X588940D01*
X588897Y-503D01*
X588900D01*
X588908D01*
X588922D01*
X588944Y-499D01*
X588966Y-496D01*
X588991D01*
X589053Y-485D01*
X589119Y-474D01*
X589184Y-452D01*
X589243Y-430D01*
X589268Y-416D01*
X589290Y-397D01*
X589293Y-394D01*
X589304Y-379D01*
X589323Y-357D01*
X589341Y-328D01*
X589363Y-288D01*
X589377Y-245D01*
X589392Y-190D01*
X589395Y-132D01*
Y-110D01*
X589392Y-88D01*
X589388Y-55D01*
X589381Y-22D01*
X589373Y14D01*
X589359Y50D01*
X589341Y87D01*
X589337Y90D01*
X589330Y101D01*
X589315Y116D01*
X589301Y138D01*
X589275Y156D01*
X589250Y178D01*
X589221Y196D01*
X589184Y210D01*
X589181D01*
X589166Y218D01*
X589141Y221D01*
X589108Y229D01*
X589064Y236D01*
X589010Y240D01*
X588944Y247D01*
X588868D01*
X587131D01*
Y582D01*
X588849D01*
X588853D01*
X588864D01*
X588878D01*
X588900D01*
X588930Y578D01*
D02*
G37*
G36*
X425397Y-149154D02*
X423941D01*
X423938D01*
X423927D01*
X423908D01*
X423887D01*
X423861Y-149157D01*
X423828D01*
X423759Y-149161D01*
X423679Y-149168D01*
X423599Y-149179D01*
X423523Y-149194D01*
X423490Y-149201D01*
X423457Y-149212D01*
X423450Y-149216D01*
X423432Y-149223D01*
X423406Y-149241D01*
X423370Y-149263D01*
X423333Y-149288D01*
X423293Y-149325D01*
X423253Y-149369D01*
X423220Y-149419D01*
X423217Y-149427D01*
X423206Y-149445D01*
X423195Y-149478D01*
X423180Y-149521D01*
X423162Y-149572D01*
X423151Y-149638D01*
X423140Y-149707D01*
X423137Y-149784D01*
Y-149820D01*
X423140Y-149842D01*
Y-149874D01*
X423144Y-149907D01*
X423159Y-149987D01*
X423177Y-150075D01*
X423206Y-150158D01*
X423246Y-150239D01*
X423271Y-150275D01*
X423301Y-150308D01*
X423304Y-150311D01*
X423308Y-150315D01*
X423319Y-150322D01*
X423333Y-150333D01*
X423355Y-150344D01*
X423377Y-150359D01*
X423410Y-150373D01*
X423443Y-150388D01*
X423483Y-150402D01*
X423530Y-150413D01*
X423584Y-150428D01*
X423643Y-150439D01*
X423708Y-150450D01*
X423777Y-150457D01*
X423857Y-150464D01*
X423941D01*
X425397D01*
Y-150799D01*
X423941D01*
X423938D01*
X423923D01*
X423905D01*
X423879D01*
X423846Y-150795D01*
X423810D01*
X423766Y-150792D01*
X423723Y-150788D01*
X423625Y-150777D01*
X423523Y-150763D01*
X423424Y-150741D01*
X423377Y-150726D01*
X423333Y-150712D01*
X423330D01*
X423322Y-150708D01*
X423311Y-150701D01*
X423297Y-150694D01*
X423257Y-150672D01*
X423206Y-150639D01*
X423148Y-150595D01*
X423089Y-150544D01*
X423028Y-150479D01*
X422973Y-150399D01*
Y-150395D01*
X422966Y-150388D01*
X422962Y-150377D01*
X422951Y-150359D01*
X422940Y-150337D01*
X422929Y-150308D01*
X422918Y-150278D01*
X422904Y-150242D01*
X422889Y-150202D01*
X422878Y-150158D01*
X422867Y-150111D01*
X422856Y-150057D01*
X422849Y-150002D01*
X422842Y-149944D01*
X422835Y-149813D01*
Y-149780D01*
X422838Y-149754D01*
Y-149725D01*
X422842Y-149689D01*
X422846Y-149649D01*
X422849Y-149609D01*
X422864Y-149518D01*
X422886Y-149419D01*
X422915Y-149325D01*
X422955Y-149234D01*
Y-149230D01*
X422962Y-149223D01*
X422969Y-149212D01*
X422977Y-149197D01*
X423006Y-149157D01*
X423046Y-149110D01*
X423097Y-149056D01*
X423155Y-149004D01*
X423228Y-148953D01*
X423308Y-148914D01*
X423311D01*
X423319Y-148910D01*
X423333Y-148906D01*
X423351Y-148899D01*
X423373Y-148892D01*
X423402Y-148884D01*
X423435Y-148873D01*
X423475Y-148866D01*
X423519Y-148859D01*
X423566Y-148848D01*
X423617Y-148841D01*
X423672Y-148833D01*
X423734Y-148826D01*
X423799Y-148822D01*
X423868Y-148819D01*
X423941D01*
X425397D01*
Y-149154D01*
D02*
G37*
G36*
X424775Y-151469D02*
X424782Y-151476D01*
X424786Y-151491D01*
X424797Y-151509D01*
X424808Y-151531D01*
X424822Y-151556D01*
X424858Y-151618D01*
X424898Y-151691D01*
X424949Y-151764D01*
X425008Y-151840D01*
X425070Y-151917D01*
X425073Y-151920D01*
X425077Y-151924D01*
X425088Y-151935D01*
X425099Y-151949D01*
X425135Y-151982D01*
X425179Y-152026D01*
X425230Y-152069D01*
X425288Y-152117D01*
X425346Y-152157D01*
X425408Y-152193D01*
Y-152393D01*
X422878D01*
Y-152084D01*
X424848D01*
X424844Y-152080D01*
X424829Y-152062D01*
X424808Y-152040D01*
X424782Y-152004D01*
X424749Y-151964D01*
X424713Y-151913D01*
X424673Y-151855D01*
X424633Y-151789D01*
Y-151786D01*
X424629Y-151782D01*
X424615Y-151760D01*
X424596Y-151724D01*
X424575Y-151680D01*
X424549Y-151629D01*
X424524Y-151574D01*
X424498Y-151520D01*
X424476Y-151465D01*
X424775D01*
Y-151469D01*
D02*
G37*
G36*
X423643Y-153187D02*
X423665D01*
X423690Y-153191D01*
X423748Y-153198D01*
X423814Y-153212D01*
X423879Y-153234D01*
X423948Y-153267D01*
X424014Y-153307D01*
X424018D01*
X424021Y-153314D01*
X424039Y-153329D01*
X424069Y-153358D01*
X424105Y-153398D01*
X424141Y-153449D01*
X424181Y-153511D01*
X424214Y-153580D01*
X424240Y-153664D01*
Y-153660D01*
X424243Y-153656D01*
X424247Y-153646D01*
X424254Y-153631D01*
X424269Y-153598D01*
X424291Y-153554D01*
X424320Y-153507D01*
X424356Y-153460D01*
X424396Y-153416D01*
X424440Y-153376D01*
X424447Y-153373D01*
X424462Y-153362D01*
X424491Y-153347D01*
X424527Y-153332D01*
X424575Y-153314D01*
X424629Y-153300D01*
X424691Y-153289D01*
X424756Y-153285D01*
X424760D01*
X424767D01*
X424782D01*
X424804Y-153289D01*
X424826Y-153292D01*
X424855Y-153296D01*
X424917Y-153311D01*
X424990Y-153332D01*
X425066Y-153369D01*
X425106Y-153391D01*
X425146Y-153416D01*
X425182Y-153449D01*
X425219Y-153482D01*
X425222Y-153485D01*
X425226Y-153493D01*
X425237Y-153504D01*
X425248Y-153518D01*
X425262Y-153536D01*
X425277Y-153562D01*
X425295Y-153591D01*
X425313Y-153620D01*
X425332Y-153656D01*
X425350Y-153697D01*
X425364Y-153740D01*
X425379Y-153788D01*
X425401Y-153889D01*
X425404Y-153948D01*
X425408Y-154006D01*
Y-154039D01*
X425404Y-154060D01*
X425401Y-154090D01*
X425397Y-154122D01*
X425393Y-154159D01*
X425383Y-154195D01*
X425361Y-154282D01*
X425328Y-154370D01*
X425306Y-154414D01*
X425281Y-154457D01*
X425248Y-154497D01*
X425215Y-154537D01*
X425211Y-154541D01*
X425208Y-154545D01*
X425197Y-154555D01*
X425182Y-154570D01*
X425161Y-154585D01*
X425139Y-154603D01*
X425084Y-154639D01*
X425015Y-154676D01*
X424935Y-154708D01*
X424844Y-154734D01*
X424797Y-154737D01*
X424746Y-154741D01*
X424742D01*
X424738D01*
X424717D01*
X424684Y-154737D01*
X424644Y-154730D01*
X424593Y-154719D01*
X424542Y-154701D01*
X424491Y-154679D01*
X424440Y-154647D01*
X424433Y-154643D01*
X424418Y-154628D01*
X424396Y-154606D01*
X424367Y-154577D01*
X424334Y-154537D01*
X424301Y-154490D01*
X424269Y-154435D01*
X424240Y-154370D01*
Y-154374D01*
X424236Y-154381D01*
X424232Y-154392D01*
X424225Y-154406D01*
X424207Y-154450D01*
X424181Y-154501D01*
X424145Y-154555D01*
X424105Y-154614D01*
X424054Y-154668D01*
X423996Y-154719D01*
X423992D01*
X423988Y-154723D01*
X423967Y-154737D01*
X423930Y-154759D01*
X423883Y-154781D01*
X423825Y-154803D01*
X423756Y-154825D01*
X423679Y-154839D01*
X423595Y-154843D01*
X423592D01*
X423581D01*
X423563D01*
X423541Y-154839D01*
X423515Y-154836D01*
X423483Y-154832D01*
X423446Y-154825D01*
X423406Y-154814D01*
X423322Y-154788D01*
X423275Y-154770D01*
X423231Y-154745D01*
X423184Y-154719D01*
X423140Y-154690D01*
X423097Y-154654D01*
X423053Y-154614D01*
X423049Y-154610D01*
X423042Y-154603D01*
X423031Y-154592D01*
X423020Y-154574D01*
X423002Y-154548D01*
X422984Y-154523D01*
X422966Y-154490D01*
X422944Y-154454D01*
X422922Y-154414D01*
X422904Y-154366D01*
X422886Y-154315D01*
X422867Y-154264D01*
X422856Y-154206D01*
X422846Y-154144D01*
X422838Y-154082D01*
X422835Y-154013D01*
Y-153977D01*
X422838Y-153951D01*
X422842Y-153919D01*
X422846Y-153882D01*
X422853Y-153842D01*
X422864Y-153798D01*
X422889Y-153700D01*
X422907Y-153649D01*
X422926Y-153602D01*
X422951Y-153551D01*
X422980Y-153500D01*
X423013Y-153453D01*
X423053Y-153409D01*
X423057Y-153405D01*
X423064Y-153398D01*
X423075Y-153387D01*
X423093Y-153373D01*
X423115Y-153358D01*
X423140Y-153336D01*
X423170Y-153318D01*
X423206Y-153296D01*
X423242Y-153274D01*
X423286Y-153256D01*
X423377Y-153220D01*
X423432Y-153205D01*
X423486Y-153194D01*
X423544Y-153187D01*
X423603Y-153183D01*
X423606D01*
X423614D01*
X423628D01*
X423643Y-153187D01*
D02*
G37*
G36*
X163398Y-101199D02*
Y-101203D01*
Y-101217D01*
Y-101236D01*
Y-101261D01*
X163394Y-101294D01*
Y-101330D01*
X163390Y-101374D01*
X163387Y-101418D01*
X163376Y-101516D01*
X163361Y-101618D01*
X163339Y-101716D01*
X163325Y-101763D01*
X163310Y-101807D01*
Y-101811D01*
X163306Y-101818D01*
X163299Y-101829D01*
X163292Y-101844D01*
X163270Y-101884D01*
X163237Y-101935D01*
X163194Y-101993D01*
X163143Y-102051D01*
X163077Y-102113D01*
X162997Y-102167D01*
X162994D01*
X162986Y-102175D01*
X162975Y-102178D01*
X162957Y-102189D01*
X162935Y-102200D01*
X162906Y-102211D01*
X162877Y-102222D01*
X162841Y-102237D01*
X162801Y-102251D01*
X162757Y-102262D01*
X162709Y-102273D01*
X162655Y-102284D01*
X162600Y-102291D01*
X162542Y-102298D01*
X162411Y-102306D01*
X162378D01*
X162353Y-102302D01*
X162324D01*
X162287Y-102298D01*
X162247Y-102295D01*
X162207Y-102291D01*
X162116Y-102277D01*
X162018Y-102255D01*
X161923Y-102226D01*
X161832Y-102186D01*
X161829D01*
X161821Y-102178D01*
X161810Y-102171D01*
X161796Y-102164D01*
X161756Y-102135D01*
X161708Y-102095D01*
X161654Y-102044D01*
X161603Y-101986D01*
X161552Y-101913D01*
X161512Y-101833D01*
Y-101829D01*
X161508Y-101822D01*
X161505Y-101807D01*
X161497Y-101789D01*
X161490Y-101767D01*
X161483Y-101738D01*
X161472Y-101705D01*
X161465Y-101665D01*
X161457Y-101621D01*
X161446Y-101574D01*
X161439Y-101523D01*
X161432Y-101469D01*
X161425Y-101407D01*
X161421Y-101341D01*
X161417Y-101272D01*
Y-101199D01*
Y-99743D01*
X161752D01*
Y-101199D01*
Y-101203D01*
Y-101214D01*
Y-101232D01*
Y-101254D01*
X161756Y-101279D01*
Y-101312D01*
X161759Y-101381D01*
X161767Y-101461D01*
X161778Y-101541D01*
X161792Y-101618D01*
X161800Y-101651D01*
X161810Y-101683D01*
X161814Y-101691D01*
X161821Y-101709D01*
X161840Y-101734D01*
X161861Y-101771D01*
X161887Y-101807D01*
X161923Y-101847D01*
X161967Y-101887D01*
X162018Y-101920D01*
X162025Y-101924D01*
X162043Y-101935D01*
X162076Y-101945D01*
X162120Y-101960D01*
X162171Y-101978D01*
X162236Y-101989D01*
X162305Y-102000D01*
X162382Y-102004D01*
X162418D01*
X162440Y-102000D01*
X162473D01*
X162506Y-101996D01*
X162586Y-101982D01*
X162673Y-101964D01*
X162757Y-101935D01*
X162837Y-101894D01*
X162873Y-101869D01*
X162906Y-101840D01*
X162910Y-101836D01*
X162913Y-101833D01*
X162921Y-101822D01*
X162932Y-101807D01*
X162943Y-101785D01*
X162957Y-101763D01*
X162972Y-101731D01*
X162986Y-101698D01*
X163001Y-101658D01*
X163012Y-101611D01*
X163026Y-101556D01*
X163037Y-101498D01*
X163048Y-101432D01*
X163055Y-101363D01*
X163063Y-101283D01*
Y-101199D01*
Y-99743D01*
X163398D01*
Y-101199D01*
D02*
G37*
G36*
X167336Y-100071D02*
X166328D01*
X166193Y-100751D01*
X166197Y-100748D01*
X166204Y-100744D01*
X166215Y-100737D01*
X166233Y-100726D01*
X166255Y-100715D01*
X166280Y-100700D01*
X166339Y-100671D01*
X166411Y-100642D01*
X166491Y-100617D01*
X166579Y-100599D01*
X166622Y-100591D01*
X166703D01*
X166725Y-100595D01*
X166754Y-100599D01*
X166786Y-100602D01*
X166823Y-100610D01*
X166863Y-100620D01*
X166950Y-100646D01*
X166998Y-100664D01*
X167045Y-100690D01*
X167092Y-100715D01*
X167139Y-100744D01*
X167183Y-100781D01*
X167227Y-100821D01*
X167230Y-100824D01*
X167238Y-100832D01*
X167249Y-100842D01*
X167263Y-100861D01*
X167281Y-100886D01*
X167300Y-100912D01*
X167321Y-100944D01*
X167343Y-100981D01*
X167361Y-101021D01*
X167383Y-101065D01*
X167402Y-101116D01*
X167420Y-101166D01*
X167434Y-101221D01*
X167445Y-101283D01*
X167452Y-101345D01*
X167456Y-101410D01*
Y-101414D01*
Y-101425D01*
Y-101443D01*
X167452Y-101469D01*
X167449Y-101498D01*
X167445Y-101531D01*
X167438Y-101570D01*
X167431Y-101611D01*
X167409Y-101705D01*
X167372Y-101804D01*
X167350Y-101854D01*
X167321Y-101902D01*
X167292Y-101953D01*
X167256Y-102000D01*
X167252Y-102004D01*
X167245Y-102015D01*
X167230Y-102029D01*
X167212Y-102047D01*
X167187Y-102069D01*
X167158Y-102098D01*
X167121Y-102124D01*
X167081Y-102153D01*
X167037Y-102182D01*
X166987Y-102208D01*
X166932Y-102233D01*
X166874Y-102259D01*
X166812Y-102277D01*
X166743Y-102291D01*
X166670Y-102302D01*
X166593Y-102306D01*
X166561D01*
X166535Y-102302D01*
X166506Y-102298D01*
X166473Y-102295D01*
X166433Y-102291D01*
X166393Y-102280D01*
X166302Y-102259D01*
X166211Y-102226D01*
X166164Y-102204D01*
X166117Y-102178D01*
X166073Y-102149D01*
X166029Y-102117D01*
X166026Y-102113D01*
X166018Y-102109D01*
X166011Y-102095D01*
X165997Y-102080D01*
X165978Y-102062D01*
X165960Y-102040D01*
X165938Y-102011D01*
X165920Y-101978D01*
X165898Y-101945D01*
X165876Y-101905D01*
X165836Y-101818D01*
X165804Y-101716D01*
X165793Y-101662D01*
X165785Y-101603D01*
X166109Y-101578D01*
Y-101581D01*
Y-101589D01*
X166113Y-101600D01*
X166117Y-101618D01*
X166128Y-101658D01*
X166142Y-101713D01*
X166164Y-101767D01*
X166193Y-101829D01*
X166229Y-101884D01*
X166273Y-101935D01*
X166280Y-101938D01*
X166295Y-101953D01*
X166324Y-101971D01*
X166364Y-101993D01*
X166408Y-102015D01*
X166462Y-102033D01*
X166524Y-102047D01*
X166593Y-102051D01*
X166615D01*
X166630Y-102047D01*
X166674Y-102044D01*
X166725Y-102029D01*
X166786Y-102011D01*
X166848Y-101982D01*
X166914Y-101938D01*
X166943Y-101913D01*
X166972Y-101884D01*
X166976Y-101880D01*
X166979Y-101876D01*
X166987Y-101865D01*
X166998Y-101854D01*
X167023Y-101814D01*
X167052Y-101763D01*
X167078Y-101701D01*
X167103Y-101625D01*
X167121Y-101534D01*
X167129Y-101487D01*
Y-101436D01*
Y-101432D01*
Y-101425D01*
Y-101410D01*
X167125Y-101392D01*
Y-101370D01*
X167121Y-101345D01*
X167110Y-101287D01*
X167092Y-101217D01*
X167067Y-101148D01*
X167030Y-101083D01*
X166979Y-101021D01*
Y-101017D01*
X166972Y-101014D01*
X166954Y-100995D01*
X166921Y-100970D01*
X166877Y-100941D01*
X166819Y-100915D01*
X166754Y-100890D01*
X166677Y-100872D01*
X166633Y-100864D01*
X166564D01*
X166535Y-100868D01*
X166499Y-100872D01*
X166455Y-100883D01*
X166411Y-100893D01*
X166364Y-100912D01*
X166317Y-100934D01*
X166313Y-100937D01*
X166299Y-100944D01*
X166277Y-100963D01*
X166248Y-100981D01*
X166218Y-101006D01*
X166189Y-101039D01*
X166157Y-101072D01*
X166131Y-101112D01*
X165840Y-101072D01*
X166084Y-99776D01*
X167336D01*
Y-100071D01*
D02*
G37*
G36*
X164723Y-99736D02*
X164752Y-99740D01*
X164788Y-99743D01*
X164828Y-99751D01*
X164868Y-99758D01*
X164963Y-99783D01*
X165057Y-99820D01*
X165105Y-99841D01*
X165152Y-99867D01*
X165196Y-99900D01*
X165236Y-99936D01*
X165239Y-99940D01*
X165247Y-99943D01*
X165254Y-99958D01*
X165269Y-99973D01*
X165287Y-99991D01*
X165305Y-100016D01*
X165323Y-100042D01*
X165345Y-100075D01*
X165381Y-100144D01*
X165418Y-100231D01*
X165432Y-100275D01*
X165439Y-100326D01*
X165447Y-100377D01*
X165451Y-100431D01*
Y-100438D01*
Y-100457D01*
X165447Y-100486D01*
X165443Y-100526D01*
X165436Y-100569D01*
X165421Y-100620D01*
X165407Y-100675D01*
X165385Y-100730D01*
X165381Y-100737D01*
X165374Y-100755D01*
X165359Y-100784D01*
X165338Y-100824D01*
X165308Y-100868D01*
X165272Y-100923D01*
X165228Y-100977D01*
X165177Y-101039D01*
X165170Y-101046D01*
X165152Y-101068D01*
X165134Y-101086D01*
X165116Y-101105D01*
X165094Y-101126D01*
X165065Y-101156D01*
X165035Y-101185D01*
X164999Y-101217D01*
X164963Y-101254D01*
X164919Y-101294D01*
X164872Y-101334D01*
X164821Y-101381D01*
X164762Y-101428D01*
X164704Y-101479D01*
X164701Y-101483D01*
X164693Y-101490D01*
X164679Y-101501D01*
X164661Y-101516D01*
X164639Y-101538D01*
X164613Y-101560D01*
X164555Y-101607D01*
X164493Y-101662D01*
X164435Y-101716D01*
X164384Y-101763D01*
X164362Y-101782D01*
X164344Y-101800D01*
X164340Y-101804D01*
X164329Y-101814D01*
X164315Y-101829D01*
X164297Y-101851D01*
X164278Y-101876D01*
X164257Y-101902D01*
X164213Y-101964D01*
X165454D01*
Y-102262D01*
X163783D01*
Y-102259D01*
Y-102244D01*
Y-102222D01*
X163787Y-102193D01*
X163791Y-102160D01*
X163798Y-102124D01*
X163805Y-102087D01*
X163820Y-102047D01*
Y-102044D01*
X163823Y-102040D01*
X163831Y-102018D01*
X163845Y-101986D01*
X163867Y-101942D01*
X163896Y-101891D01*
X163933Y-101833D01*
X163973Y-101774D01*
X164024Y-101713D01*
Y-101709D01*
X164031Y-101705D01*
X164049Y-101683D01*
X164082Y-101651D01*
X164129Y-101603D01*
X164184Y-101549D01*
X164253Y-101483D01*
X164337Y-101410D01*
X164428Y-101334D01*
X164431Y-101330D01*
X164446Y-101319D01*
X164468Y-101301D01*
X164493Y-101279D01*
X164526Y-101250D01*
X164566Y-101217D01*
X164606Y-101181D01*
X164653Y-101141D01*
X164744Y-101054D01*
X164835Y-100966D01*
X164879Y-100923D01*
X164919Y-100879D01*
X164955Y-100839D01*
X164985Y-100799D01*
Y-100795D01*
X164992Y-100792D01*
X164999Y-100781D01*
X165006Y-100766D01*
X165032Y-100726D01*
X165061Y-100679D01*
X165086Y-100620D01*
X165112Y-100559D01*
X165127Y-100489D01*
X165134Y-100424D01*
Y-100420D01*
Y-100417D01*
X165130Y-100395D01*
X165127Y-100358D01*
X165116Y-100318D01*
X165101Y-100267D01*
X165076Y-100216D01*
X165043Y-100165D01*
X164999Y-100115D01*
X164992Y-100107D01*
X164974Y-100093D01*
X164948Y-100075D01*
X164908Y-100049D01*
X164857Y-100027D01*
X164799Y-100005D01*
X164730Y-99991D01*
X164653Y-99987D01*
X164631D01*
X164617Y-99991D01*
X164573Y-99994D01*
X164522Y-100005D01*
X164468Y-100020D01*
X164406Y-100045D01*
X164348Y-100078D01*
X164293Y-100122D01*
X164286Y-100129D01*
X164271Y-100147D01*
X164249Y-100176D01*
X164227Y-100220D01*
X164202Y-100271D01*
X164180Y-100337D01*
X164165Y-100409D01*
X164158Y-100493D01*
X163842Y-100460D01*
Y-100457D01*
X163845Y-100446D01*
Y-100427D01*
X163849Y-100402D01*
X163856Y-100373D01*
X163863Y-100340D01*
X163874Y-100300D01*
X163885Y-100260D01*
X163914Y-100173D01*
X163958Y-100085D01*
X163984Y-100042D01*
X164016Y-99998D01*
X164049Y-99958D01*
X164085Y-99922D01*
X164089Y-99918D01*
X164096Y-99914D01*
X164107Y-99903D01*
X164126Y-99892D01*
X164147Y-99878D01*
X164173Y-99863D01*
X164202Y-99845D01*
X164238Y-99827D01*
X164278Y-99809D01*
X164322Y-99791D01*
X164369Y-99776D01*
X164420Y-99761D01*
X164475Y-99751D01*
X164533Y-99740D01*
X164595Y-99736D01*
X164661Y-99732D01*
X164697D01*
X164723Y-99736D01*
D02*
G37*
G36*
X96130Y12942D02*
X96163D01*
X96203Y12939D01*
X96247Y12931D01*
X96298Y12924D01*
X96403Y12906D01*
X96513Y12877D01*
X96622Y12837D01*
X96673Y12811D01*
X96724Y12782D01*
X96727Y12778D01*
X96734Y12775D01*
X96749Y12764D01*
X96764Y12749D01*
X96785Y12735D01*
X96811Y12713D01*
X96840Y12687D01*
X96869Y12658D01*
X96898Y12626D01*
X96931Y12593D01*
X96997Y12509D01*
X97058Y12411D01*
X97113Y12302D01*
Y12298D01*
X97120Y12287D01*
X97124Y12269D01*
X97135Y12247D01*
X97142Y12218D01*
X97153Y12181D01*
X97168Y12141D01*
X97179Y12098D01*
X97189Y12050D01*
X97204Y11996D01*
X97222Y11883D01*
X97237Y11756D01*
X97244Y11625D01*
Y11621D01*
Y11606D01*
Y11585D01*
X97240Y11559D01*
Y11523D01*
X97237Y11486D01*
X97233Y11439D01*
X97226Y11392D01*
X97208Y11286D01*
X97182Y11169D01*
X97146Y11053D01*
X97095Y10940D01*
X97091Y10937D01*
X97088Y10926D01*
X97080Y10911D01*
X97066Y10893D01*
X97051Y10867D01*
X97033Y10838D01*
X96986Y10773D01*
X96924Y10700D01*
X96851Y10627D01*
X96767Y10554D01*
X96669Y10492D01*
X96665Y10489D01*
X96654Y10485D01*
X96640Y10478D01*
X96622Y10467D01*
X96592Y10456D01*
X96563Y10445D01*
X96527Y10431D01*
X96487Y10416D01*
X96443Y10402D01*
X96396Y10387D01*
X96294Y10365D01*
X96178Y10347D01*
X96057Y10340D01*
X96021D01*
X95996Y10343D01*
X95963Y10347D01*
X95923Y10351D01*
X95883Y10354D01*
X95835Y10365D01*
X95737Y10387D01*
X95628Y10420D01*
X95573Y10441D01*
X95522Y10467D01*
X95471Y10500D01*
X95420Y10532D01*
X95417Y10536D01*
X95410Y10540D01*
X95395Y10551D01*
X95377Y10569D01*
X95359Y10587D01*
X95333Y10613D01*
X95308Y10642D01*
X95279Y10671D01*
X95249Y10707D01*
X95220Y10751D01*
X95187Y10795D01*
X95158Y10842D01*
X95133Y10897D01*
X95104Y10951D01*
X95082Y11009D01*
X95060Y11075D01*
X95388Y11151D01*
Y11148D01*
X95391Y11140D01*
X95399Y11126D01*
X95406Y11108D01*
X95413Y11086D01*
X95424Y11057D01*
X95453Y10998D01*
X95490Y10933D01*
X95533Y10867D01*
X95588Y10806D01*
X95646Y10751D01*
X95653Y10744D01*
X95675Y10729D01*
X95712Y10711D01*
X95759Y10685D01*
X95821Y10664D01*
X95890Y10642D01*
X95974Y10627D01*
X96065Y10623D01*
X96094D01*
X96112Y10627D01*
X96137D01*
X96167Y10631D01*
X96236Y10642D01*
X96312Y10656D01*
X96392Y10682D01*
X96476Y10718D01*
X96552Y10766D01*
X96556D01*
X96560Y10773D01*
X96585Y10791D01*
X96618Y10820D01*
X96658Y10864D01*
X96705Y10918D01*
X96749Y10980D01*
X96789Y11057D01*
X96825Y11140D01*
Y11144D01*
X96829Y11151D01*
X96833Y11162D01*
X96836Y11180D01*
X96844Y11202D01*
X96851Y11228D01*
X96862Y11290D01*
X96876Y11362D01*
X96891Y11443D01*
X96898Y11530D01*
X96902Y11625D01*
Y11628D01*
Y11639D01*
Y11657D01*
Y11679D01*
X96898Y11705D01*
Y11737D01*
X96895Y11774D01*
X96891Y11814D01*
X96880Y11901D01*
X96862Y11996D01*
X96840Y12090D01*
X96811Y12185D01*
Y12189D01*
X96807Y12196D01*
X96800Y12207D01*
X96793Y12225D01*
X96771Y12269D01*
X96738Y12320D01*
X96698Y12378D01*
X96647Y12440D01*
X96589Y12494D01*
X96520Y12545D01*
X96516D01*
X96509Y12549D01*
X96498Y12556D01*
X96483Y12564D01*
X96465Y12571D01*
X96443Y12582D01*
X96392Y12604D01*
X96327Y12626D01*
X96254Y12644D01*
X96174Y12658D01*
X96090Y12662D01*
X96065D01*
X96043Y12658D01*
X96017D01*
X95992Y12655D01*
X95926Y12640D01*
X95850Y12622D01*
X95774Y12593D01*
X95693Y12553D01*
X95653Y12531D01*
X95617Y12502D01*
X95613Y12498D01*
X95610Y12494D01*
X95599Y12484D01*
X95584Y12473D01*
X95570Y12454D01*
X95552Y12433D01*
X95530Y12411D01*
X95512Y12382D01*
X95490Y12349D01*
X95464Y12313D01*
X95442Y12276D01*
X95420Y12232D01*
X95402Y12185D01*
X95384Y12134D01*
X95366Y12079D01*
X95351Y12021D01*
X95016Y12105D01*
Y12109D01*
X95020Y12123D01*
X95027Y12145D01*
X95038Y12174D01*
X95049Y12207D01*
X95064Y12247D01*
X95082Y12291D01*
X95104Y12338D01*
X95155Y12440D01*
X95220Y12542D01*
X95260Y12593D01*
X95300Y12644D01*
X95344Y12687D01*
X95395Y12731D01*
X95399Y12735D01*
X95406Y12742D01*
X95424Y12749D01*
X95442Y12764D01*
X95471Y12782D01*
X95500Y12800D01*
X95541Y12818D01*
X95581Y12837D01*
X95628Y12858D01*
X95679Y12877D01*
X95733Y12895D01*
X95792Y12913D01*
X95854Y12928D01*
X95919Y12935D01*
X95988Y12942D01*
X96061Y12946D01*
X96101D01*
X96130Y12942D01*
D02*
G37*
G36*
X94358Y12899D02*
Y12888D01*
Y12873D01*
X94354Y12851D01*
Y12822D01*
X94350Y12786D01*
X94347Y12746D01*
X94343Y12702D01*
X94336Y12651D01*
X94328Y12600D01*
X94318Y12538D01*
X94307Y12476D01*
X94296Y12411D01*
X94281Y12338D01*
X94245Y12189D01*
Y12185D01*
X94241Y12171D01*
X94234Y12149D01*
X94223Y12116D01*
X94212Y12079D01*
X94197Y12036D01*
X94183Y11985D01*
X94161Y11930D01*
X94139Y11868D01*
X94117Y11806D01*
X94063Y11668D01*
X93997Y11523D01*
X93924Y11377D01*
X93921Y11373D01*
X93914Y11359D01*
X93903Y11341D01*
X93888Y11311D01*
X93870Y11279D01*
X93844Y11239D01*
X93819Y11195D01*
X93790Y11148D01*
X93721Y11042D01*
X93648Y10933D01*
X93564Y10820D01*
X93477Y10714D01*
X94711D01*
Y10416D01*
X93080D01*
Y10660D01*
X93084Y10664D01*
X93091Y10671D01*
X93105Y10685D01*
X93120Y10707D01*
X93142Y10733D01*
X93171Y10762D01*
X93200Y10798D01*
X93233Y10842D01*
X93266Y10886D01*
X93306Y10937D01*
X93346Y10995D01*
X93386Y11053D01*
X93429Y11119D01*
X93473Y11188D01*
X93517Y11264D01*
X93560Y11341D01*
X93564Y11344D01*
X93571Y11359D01*
X93582Y11381D01*
X93600Y11413D01*
X93619Y11453D01*
X93641Y11497D01*
X93666Y11548D01*
X93691Y11606D01*
X93721Y11672D01*
X93753Y11737D01*
X93782Y11810D01*
X93812Y11887D01*
X93870Y12043D01*
X93924Y12211D01*
Y12214D01*
X93928Y12225D01*
X93932Y12243D01*
X93939Y12265D01*
X93946Y12294D01*
X93954Y12331D01*
X93964Y12371D01*
X93972Y12414D01*
X93983Y12465D01*
X93994Y12520D01*
X94012Y12636D01*
X94030Y12764D01*
X94041Y12902D01*
X94358D01*
Y12899D01*
D02*
G37*
G36*
X92818D02*
Y12884D01*
Y12862D01*
X92814Y12833D01*
X92811Y12800D01*
X92803Y12764D01*
X92796Y12727D01*
X92781Y12687D01*
Y12684D01*
X92778Y12680D01*
X92770Y12658D01*
X92756Y12626D01*
X92734Y12582D01*
X92705Y12531D01*
X92669Y12473D01*
X92629Y12414D01*
X92578Y12353D01*
Y12349D01*
X92570Y12345D01*
X92552Y12323D01*
X92519Y12291D01*
X92472Y12243D01*
X92417Y12189D01*
X92348Y12123D01*
X92265Y12050D01*
X92174Y11974D01*
X92170Y11970D01*
X92155Y11959D01*
X92133Y11941D01*
X92108Y11919D01*
X92075Y11890D01*
X92035Y11857D01*
X91995Y11821D01*
X91948Y11781D01*
X91857Y11694D01*
X91766Y11606D01*
X91722Y11563D01*
X91682Y11519D01*
X91646Y11479D01*
X91617Y11439D01*
Y11435D01*
X91609Y11432D01*
X91602Y11421D01*
X91595Y11406D01*
X91569Y11366D01*
X91540Y11319D01*
X91515Y11260D01*
X91489Y11199D01*
X91475Y11129D01*
X91467Y11064D01*
Y11060D01*
Y11057D01*
X91471Y11035D01*
X91475Y10998D01*
X91486Y10958D01*
X91500Y10907D01*
X91526Y10857D01*
X91558Y10806D01*
X91602Y10755D01*
X91609Y10747D01*
X91628Y10733D01*
X91653Y10714D01*
X91693Y10689D01*
X91744Y10667D01*
X91802Y10645D01*
X91872Y10631D01*
X91948Y10627D01*
X91970D01*
X91984Y10631D01*
X92028Y10634D01*
X92079Y10645D01*
X92133Y10660D01*
X92195Y10685D01*
X92254Y10718D01*
X92308Y10762D01*
X92316Y10769D01*
X92330Y10787D01*
X92352Y10816D01*
X92374Y10860D01*
X92399Y10911D01*
X92421Y10977D01*
X92436Y11049D01*
X92443Y11133D01*
X92760Y11100D01*
Y11097D01*
X92756Y11086D01*
Y11068D01*
X92752Y11042D01*
X92745Y11013D01*
X92738Y10980D01*
X92727Y10940D01*
X92716Y10900D01*
X92687Y10813D01*
X92643Y10725D01*
X92618Y10682D01*
X92585Y10638D01*
X92552Y10598D01*
X92516Y10562D01*
X92512Y10558D01*
X92505Y10554D01*
X92494Y10543D01*
X92476Y10532D01*
X92454Y10518D01*
X92428Y10503D01*
X92399Y10485D01*
X92363Y10467D01*
X92323Y10449D01*
X92279Y10431D01*
X92232Y10416D01*
X92181Y10402D01*
X92126Y10391D01*
X92068Y10380D01*
X92006Y10376D01*
X91941Y10372D01*
X91904D01*
X91879Y10376D01*
X91850Y10380D01*
X91813Y10383D01*
X91773Y10391D01*
X91733Y10398D01*
X91638Y10423D01*
X91544Y10460D01*
X91496Y10482D01*
X91449Y10507D01*
X91405Y10540D01*
X91365Y10576D01*
X91362Y10580D01*
X91355Y10583D01*
X91347Y10598D01*
X91333Y10613D01*
X91315Y10631D01*
X91296Y10656D01*
X91278Y10682D01*
X91256Y10714D01*
X91220Y10784D01*
X91184Y10871D01*
X91169Y10915D01*
X91162Y10966D01*
X91154Y11017D01*
X91151Y11071D01*
Y11079D01*
Y11097D01*
X91154Y11126D01*
X91158Y11166D01*
X91165Y11210D01*
X91180Y11260D01*
X91194Y11315D01*
X91216Y11370D01*
X91220Y11377D01*
X91227Y11395D01*
X91242Y11424D01*
X91264Y11464D01*
X91293Y11508D01*
X91329Y11563D01*
X91373Y11617D01*
X91424Y11679D01*
X91431Y11686D01*
X91449Y11708D01*
X91467Y11726D01*
X91486Y11745D01*
X91507Y11767D01*
X91537Y11796D01*
X91566Y11825D01*
X91602Y11857D01*
X91638Y11894D01*
X91682Y11934D01*
X91729Y11974D01*
X91780Y12021D01*
X91839Y12069D01*
X91897Y12120D01*
X91901Y12123D01*
X91908Y12130D01*
X91922Y12141D01*
X91941Y12156D01*
X91962Y12178D01*
X91988Y12200D01*
X92046Y12247D01*
X92108Y12302D01*
X92166Y12356D01*
X92217Y12404D01*
X92239Y12422D01*
X92257Y12440D01*
X92261Y12444D01*
X92272Y12454D01*
X92286Y12469D01*
X92305Y12491D01*
X92323Y12516D01*
X92345Y12542D01*
X92388Y12604D01*
X91147D01*
Y12902D01*
X92818D01*
Y12899D01*
D02*
G37*
G36*
X606324Y-233812D02*
X606014D01*
Y-231843D01*
X606011Y-231846D01*
X605993Y-231861D01*
X605971Y-231883D01*
X605934Y-231908D01*
X605894Y-231941D01*
X605843Y-231977D01*
X605785Y-232017D01*
X605720Y-232057D01*
X605716D01*
X605712Y-232061D01*
X605690Y-232076D01*
X605654Y-232094D01*
X605610Y-232116D01*
X605559Y-232141D01*
X605505Y-232167D01*
X605450Y-232192D01*
X605396Y-232214D01*
Y-231915D01*
X605399D01*
X605407Y-231908D01*
X605421Y-231905D01*
X605439Y-231894D01*
X605461Y-231883D01*
X605487Y-231868D01*
X605548Y-231832D01*
X605621Y-231792D01*
X605694Y-231741D01*
X605771Y-231683D01*
X605847Y-231621D01*
X605851Y-231617D01*
X605854Y-231613D01*
X605865Y-231603D01*
X605880Y-231592D01*
X605912Y-231555D01*
X605956Y-231511D01*
X606000Y-231461D01*
X606047Y-231402D01*
X606087Y-231344D01*
X606124Y-231282D01*
X606324D01*
Y-233812D01*
D02*
G37*
G36*
X604096Y-231286D02*
X604125Y-231290D01*
X604162Y-231293D01*
X604202Y-231300D01*
X604242Y-231308D01*
X604336Y-231333D01*
X604431Y-231369D01*
X604478Y-231391D01*
X604526Y-231417D01*
X604569Y-231450D01*
X604609Y-231486D01*
X604613Y-231490D01*
X604620Y-231493D01*
X604628Y-231508D01*
X604642Y-231522D01*
X604660Y-231541D01*
X604679Y-231566D01*
X604697Y-231592D01*
X604719Y-231624D01*
X604755Y-231694D01*
X604791Y-231781D01*
X604806Y-231824D01*
X604813Y-231875D01*
X604820Y-231926D01*
X604824Y-231981D01*
Y-231988D01*
Y-232007D01*
X604820Y-232036D01*
X604817Y-232076D01*
X604810Y-232119D01*
X604795Y-232170D01*
X604780Y-232225D01*
X604759Y-232280D01*
X604755Y-232287D01*
X604748Y-232305D01*
X604733Y-232334D01*
X604711Y-232374D01*
X604682Y-232418D01*
X604646Y-232472D01*
X604602Y-232527D01*
X604551Y-232589D01*
X604544Y-232596D01*
X604526Y-232618D01*
X604507Y-232636D01*
X604489Y-232655D01*
X604467Y-232676D01*
X604438Y-232705D01*
X604409Y-232734D01*
X604373Y-232767D01*
X604336Y-232804D01*
X604293Y-232844D01*
X604245Y-232884D01*
X604194Y-232931D01*
X604136Y-232978D01*
X604078Y-233029D01*
X604074Y-233033D01*
X604067Y-233040D01*
X604052Y-233051D01*
X604034Y-233066D01*
X604012Y-233088D01*
X603987Y-233109D01*
X603929Y-233157D01*
X603867Y-233211D01*
X603809Y-233266D01*
X603758Y-233313D01*
X603736Y-233331D01*
X603718Y-233350D01*
X603714Y-233353D01*
X603703Y-233364D01*
X603688Y-233379D01*
X603670Y-233401D01*
X603652Y-233426D01*
X603630Y-233452D01*
X603587Y-233513D01*
X604828D01*
Y-233812D01*
X603157D01*
Y-233808D01*
Y-233794D01*
Y-233772D01*
X603161Y-233743D01*
X603164Y-233710D01*
X603172Y-233674D01*
X603179Y-233637D01*
X603193Y-233597D01*
Y-233594D01*
X603197Y-233590D01*
X603204Y-233568D01*
X603219Y-233535D01*
X603241Y-233492D01*
X603270Y-233441D01*
X603306Y-233383D01*
X603346Y-233324D01*
X603397Y-233262D01*
Y-233259D01*
X603405Y-233255D01*
X603423Y-233233D01*
X603455Y-233201D01*
X603503Y-233153D01*
X603557Y-233099D01*
X603627Y-233033D01*
X603710Y-232960D01*
X603801Y-232884D01*
X603805Y-232880D01*
X603820Y-232869D01*
X603841Y-232851D01*
X603867Y-232829D01*
X603900Y-232800D01*
X603940Y-232767D01*
X603980Y-232731D01*
X604027Y-232691D01*
X604118Y-232604D01*
X604209Y-232516D01*
X604253Y-232472D01*
X604293Y-232429D01*
X604329Y-232389D01*
X604358Y-232349D01*
Y-232345D01*
X604365Y-232341D01*
X604373Y-232330D01*
X604380Y-232316D01*
X604406Y-232276D01*
X604435Y-232229D01*
X604460Y-232170D01*
X604486Y-232108D01*
X604500Y-232039D01*
X604507Y-231974D01*
Y-231970D01*
Y-231966D01*
X604504Y-231945D01*
X604500Y-231908D01*
X604489Y-231868D01*
X604475Y-231817D01*
X604449Y-231766D01*
X604417Y-231715D01*
X604373Y-231664D01*
X604365Y-231657D01*
X604347Y-231643D01*
X604322Y-231624D01*
X604282Y-231599D01*
X604231Y-231577D01*
X604173Y-231555D01*
X604103Y-231541D01*
X604027Y-231537D01*
X604005D01*
X603991Y-231541D01*
X603947Y-231544D01*
X603896Y-231555D01*
X603841Y-231570D01*
X603780Y-231595D01*
X603721Y-231628D01*
X603667Y-231672D01*
X603659Y-231679D01*
X603645Y-231697D01*
X603623Y-231726D01*
X603601Y-231770D01*
X603576Y-231821D01*
X603554Y-231886D01*
X603539Y-231959D01*
X603532Y-232043D01*
X603215Y-232010D01*
Y-232007D01*
X603219Y-231996D01*
Y-231977D01*
X603223Y-231952D01*
X603230Y-231923D01*
X603237Y-231890D01*
X603248Y-231850D01*
X603259Y-231810D01*
X603288Y-231723D01*
X603332Y-231635D01*
X603357Y-231592D01*
X603390Y-231548D01*
X603423Y-231508D01*
X603459Y-231471D01*
X603463Y-231468D01*
X603470Y-231464D01*
X603481Y-231453D01*
X603499Y-231442D01*
X603521Y-231428D01*
X603546Y-231413D01*
X603576Y-231395D01*
X603612Y-231377D01*
X603652Y-231359D01*
X603696Y-231340D01*
X603743Y-231326D01*
X603794Y-231311D01*
X603849Y-231300D01*
X603907Y-231290D01*
X603969Y-231286D01*
X604034Y-231282D01*
X604071D01*
X604096Y-231286D01*
D02*
G37*
G36*
X601821Y-231297D02*
X601894Y-231300D01*
X601967Y-231308D01*
X602040Y-231319D01*
X602101Y-231329D01*
X602105D01*
X602112Y-231333D01*
X602123D01*
X602138Y-231340D01*
X602178Y-231351D01*
X602229Y-231369D01*
X602287Y-231395D01*
X602349Y-231428D01*
X602411Y-231464D01*
X602469Y-231511D01*
X602473Y-231515D01*
X602476Y-231519D01*
X602487Y-231530D01*
X602502Y-231541D01*
X602538Y-231577D01*
X602582Y-231628D01*
X602629Y-231690D01*
X602680Y-231763D01*
X602728Y-231846D01*
X602768Y-231941D01*
Y-231945D01*
X602771Y-231952D01*
X602778Y-231966D01*
X602782Y-231988D01*
X602793Y-232014D01*
X602800Y-232043D01*
X602808Y-232076D01*
X602818Y-232116D01*
X602829Y-232156D01*
X602837Y-232203D01*
X602855Y-232305D01*
X602866Y-232418D01*
X602870Y-232542D01*
Y-232545D01*
Y-232553D01*
Y-232571D01*
Y-232589D01*
X602866Y-232614D01*
Y-232644D01*
X602862Y-232713D01*
X602851Y-232793D01*
X602840Y-232876D01*
X602822Y-232964D01*
X602800Y-233051D01*
Y-233055D01*
X602797Y-233062D01*
X602793Y-233073D01*
X602789Y-233088D01*
X602775Y-233128D01*
X602753Y-233179D01*
X602731Y-233237D01*
X602702Y-233295D01*
X602666Y-233357D01*
X602629Y-233415D01*
X602626Y-233422D01*
X602611Y-233441D01*
X602589Y-233466D01*
X602560Y-233499D01*
X602527Y-233535D01*
X602487Y-233572D01*
X602447Y-233612D01*
X602400Y-233645D01*
X602393Y-233648D01*
X602378Y-233659D01*
X602353Y-233674D01*
X602316Y-233692D01*
X602273Y-233714D01*
X602222Y-233732D01*
X602163Y-233754D01*
X602098Y-233772D01*
X602091D01*
X602080Y-233776D01*
X602069Y-233779D01*
X602032Y-233783D01*
X601981Y-233790D01*
X601923Y-233797D01*
X601854Y-233805D01*
X601778Y-233808D01*
X601694Y-233812D01*
X600787D01*
Y-231293D01*
X601756D01*
X601821Y-231297D01*
D02*
G37*
G36*
X608220Y-184322D02*
X608249Y-184326D01*
X608285Y-184329D01*
X608325Y-184337D01*
X608365Y-184344D01*
X608460Y-184370D01*
X608555Y-184406D01*
X608602Y-184428D01*
X608649Y-184453D01*
X608693Y-184486D01*
X608733Y-184522D01*
X608737Y-184526D01*
X608744Y-184530D01*
X608751Y-184544D01*
X608766Y-184559D01*
X608784Y-184577D01*
X608802Y-184602D01*
X608820Y-184628D01*
X608842Y-184661D01*
X608879Y-184730D01*
X608915Y-184817D01*
X608930Y-184861D01*
X608937Y-184912D01*
X608944Y-184963D01*
X608948Y-185018D01*
Y-185025D01*
Y-185043D01*
X608944Y-185072D01*
X608941Y-185112D01*
X608933Y-185156D01*
X608919Y-185207D01*
X608904Y-185261D01*
X608882Y-185316D01*
X608879Y-185323D01*
X608871Y-185341D01*
X608857Y-185371D01*
X608835Y-185411D01*
X608806Y-185454D01*
X608770Y-185509D01*
X608726Y-185564D01*
X608675Y-185625D01*
X608668Y-185633D01*
X608649Y-185654D01*
X608631Y-185673D01*
X608613Y-185691D01*
X608591Y-185713D01*
X608562Y-185742D01*
X608533Y-185771D01*
X608497Y-185804D01*
X608460Y-185840D01*
X608416Y-185880D01*
X608369Y-185920D01*
X608318Y-185968D01*
X608260Y-186015D01*
X608202Y-186066D01*
X608198Y-186069D01*
X608191Y-186077D01*
X608176Y-186088D01*
X608158Y-186102D01*
X608136Y-186124D01*
X608111Y-186146D01*
X608052Y-186193D01*
X607991Y-186248D01*
X607932Y-186302D01*
X607881Y-186350D01*
X607860Y-186368D01*
X607841Y-186386D01*
X607838Y-186390D01*
X607827Y-186401D01*
X607812Y-186415D01*
X607794Y-186437D01*
X607776Y-186463D01*
X607754Y-186488D01*
X607710Y-186550D01*
X608952D01*
Y-186848D01*
X607281D01*
Y-186845D01*
Y-186830D01*
Y-186808D01*
X607284Y-186779D01*
X607288Y-186747D01*
X607295Y-186710D01*
X607303Y-186674D01*
X607317Y-186634D01*
Y-186630D01*
X607321Y-186626D01*
X607328Y-186604D01*
X607343Y-186572D01*
X607364Y-186528D01*
X607394Y-186477D01*
X607430Y-186419D01*
X607470Y-186361D01*
X607521Y-186299D01*
Y-186295D01*
X607528Y-186292D01*
X607546Y-186270D01*
X607579Y-186237D01*
X607626Y-186190D01*
X607681Y-186135D01*
X607750Y-186069D01*
X607834Y-185997D01*
X607925Y-185920D01*
X607929Y-185917D01*
X607943Y-185906D01*
X607965Y-185887D01*
X607991Y-185866D01*
X608023Y-185837D01*
X608063Y-185804D01*
X608103Y-185767D01*
X608151Y-185727D01*
X608242Y-185640D01*
X608333Y-185553D01*
X608376Y-185509D01*
X608416Y-185465D01*
X608453Y-185425D01*
X608482Y-185385D01*
Y-185381D01*
X608489Y-185378D01*
X608497Y-185367D01*
X608504Y-185352D01*
X608529Y-185312D01*
X608558Y-185265D01*
X608584Y-185207D01*
X608609Y-185145D01*
X608624Y-185076D01*
X608631Y-185010D01*
Y-185007D01*
Y-185003D01*
X608628Y-184981D01*
X608624Y-184945D01*
X608613Y-184905D01*
X608598Y-184854D01*
X608573Y-184803D01*
X608540Y-184752D01*
X608497Y-184701D01*
X608489Y-184694D01*
X608471Y-184679D01*
X608446Y-184661D01*
X608405Y-184635D01*
X608355Y-184613D01*
X608296Y-184592D01*
X608227Y-184577D01*
X608151Y-184573D01*
X608129D01*
X608114Y-184577D01*
X608071Y-184581D01*
X608020Y-184592D01*
X607965Y-184606D01*
X607903Y-184632D01*
X607845Y-184664D01*
X607790Y-184708D01*
X607783Y-184715D01*
X607768Y-184734D01*
X607747Y-184763D01*
X607725Y-184806D01*
X607699Y-184857D01*
X607678Y-184923D01*
X607663Y-184996D01*
X607656Y-185079D01*
X607339Y-185047D01*
Y-185043D01*
X607343Y-185032D01*
Y-185014D01*
X607346Y-184988D01*
X607353Y-184959D01*
X607361Y-184926D01*
X607372Y-184886D01*
X607383Y-184846D01*
X607412Y-184759D01*
X607455Y-184672D01*
X607481Y-184628D01*
X607514Y-184584D01*
X607546Y-184544D01*
X607583Y-184508D01*
X607586Y-184504D01*
X607594Y-184501D01*
X607605Y-184490D01*
X607623Y-184479D01*
X607645Y-184464D01*
X607670Y-184450D01*
X607699Y-184431D01*
X607736Y-184413D01*
X607776Y-184395D01*
X607819Y-184377D01*
X607867Y-184362D01*
X607918Y-184348D01*
X607972Y-184337D01*
X608031Y-184326D01*
X608092Y-184322D01*
X608158Y-184319D01*
X608194D01*
X608220Y-184322D01*
D02*
G37*
G36*
X606531Y-186848D02*
X606221D01*
Y-184879D01*
X606218Y-184883D01*
X606200Y-184897D01*
X606178Y-184919D01*
X606141Y-184945D01*
X606101Y-184977D01*
X606050Y-185014D01*
X605992Y-185054D01*
X605927Y-185094D01*
X605923D01*
X605919Y-185098D01*
X605898Y-185112D01*
X605861Y-185130D01*
X605817Y-185152D01*
X605766Y-185178D01*
X605712Y-185203D01*
X605657Y-185229D01*
X605603Y-185250D01*
Y-184952D01*
X605606D01*
X605614Y-184945D01*
X605628Y-184941D01*
X605646Y-184930D01*
X605668Y-184919D01*
X605694Y-184905D01*
X605756Y-184868D01*
X605828Y-184828D01*
X605901Y-184777D01*
X605978Y-184719D01*
X606054Y-184657D01*
X606058Y-184653D01*
X606061Y-184650D01*
X606072Y-184639D01*
X606087Y-184628D01*
X606119Y-184592D01*
X606163Y-184548D01*
X606207Y-184497D01*
X606254Y-184439D01*
X606294Y-184380D01*
X606331Y-184319D01*
X606531D01*
Y-186848D01*
D02*
G37*
G36*
X603987Y-184333D02*
X604059Y-184337D01*
X604132Y-184344D01*
X604205Y-184355D01*
X604267Y-184366D01*
X604270D01*
X604278Y-184370D01*
X604289D01*
X604303Y-184377D01*
X604343Y-184388D01*
X604394Y-184406D01*
X604452Y-184431D01*
X604514Y-184464D01*
X604576Y-184501D01*
X604634Y-184548D01*
X604638Y-184552D01*
X604642Y-184555D01*
X604653Y-184566D01*
X604667Y-184577D01*
X604704Y-184613D01*
X604747Y-184664D01*
X604795Y-184726D01*
X604846Y-184799D01*
X604893Y-184883D01*
X604933Y-184977D01*
Y-184981D01*
X604937Y-184988D01*
X604944Y-185003D01*
X604948Y-185025D01*
X604958Y-185050D01*
X604966Y-185079D01*
X604973Y-185112D01*
X604984Y-185152D01*
X604995Y-185192D01*
X605002Y-185240D01*
X605020Y-185341D01*
X605031Y-185454D01*
X605035Y-185578D01*
Y-185582D01*
Y-185589D01*
Y-185607D01*
Y-185625D01*
X605031Y-185651D01*
Y-185680D01*
X605027Y-185749D01*
X605017Y-185829D01*
X605006Y-185913D01*
X604987Y-186000D01*
X604966Y-186088D01*
Y-186091D01*
X604962Y-186099D01*
X604958Y-186109D01*
X604955Y-186124D01*
X604940Y-186164D01*
X604918Y-186215D01*
X604896Y-186273D01*
X604867Y-186331D01*
X604831Y-186393D01*
X604795Y-186452D01*
X604791Y-186459D01*
X604776Y-186477D01*
X604755Y-186503D01*
X604725Y-186535D01*
X604693Y-186572D01*
X604653Y-186608D01*
X604613Y-186648D01*
X604565Y-186681D01*
X604558Y-186685D01*
X604543Y-186696D01*
X604518Y-186710D01*
X604482Y-186728D01*
X604438Y-186750D01*
X604387Y-186768D01*
X604329Y-186790D01*
X604263Y-186808D01*
X604256D01*
X604245Y-186812D01*
X604234Y-186816D01*
X604198Y-186819D01*
X604147Y-186827D01*
X604088Y-186834D01*
X604019Y-186841D01*
X603943Y-186845D01*
X603859Y-186848D01*
X602953D01*
Y-184329D01*
X603921D01*
X603987Y-184333D01*
D02*
G37*
G36*
X609934Y-197341D02*
X607965D01*
X607968Y-197345D01*
X607983Y-197363D01*
X608005Y-197385D01*
X608030Y-197422D01*
X608063Y-197461D01*
X608099Y-197512D01*
X608139Y-197571D01*
X608179Y-197636D01*
Y-197640D01*
X608183Y-197643D01*
X608197Y-197665D01*
X608216Y-197702D01*
X608238Y-197746D01*
X608263Y-197796D01*
X608288Y-197851D01*
X608314Y-197906D01*
X608336Y-197960D01*
X608037D01*
Y-197957D01*
X608030Y-197949D01*
X608026Y-197935D01*
X608015Y-197916D01*
X608005Y-197895D01*
X607990Y-197869D01*
X607954Y-197807D01*
X607913Y-197734D01*
X607863Y-197662D01*
X607804Y-197585D01*
X607742Y-197509D01*
X607739Y-197505D01*
X607735Y-197502D01*
X607724Y-197491D01*
X607713Y-197476D01*
X607677Y-197443D01*
X607633Y-197400D01*
X607582Y-197356D01*
X607524Y-197309D01*
X607466Y-197269D01*
X607404Y-197232D01*
Y-197032D01*
X609934D01*
Y-197341D01*
D02*
G37*
G36*
Y-199074D02*
Y-199402D01*
X608015Y-199929D01*
X608012D01*
X608005Y-199933D01*
X607994Y-199937D01*
X607975Y-199940D01*
X607935Y-199951D01*
X607888Y-199962D01*
X607837Y-199977D01*
X607790Y-199991D01*
X607750Y-200002D01*
X607731Y-200006D01*
X607721Y-200009D01*
X607724D01*
X607728Y-200013D01*
X607750Y-200017D01*
X607783Y-200024D01*
X607823Y-200035D01*
X607866Y-200046D01*
X607917Y-200061D01*
X607968Y-200071D01*
X608015Y-200086D01*
X609934Y-200617D01*
Y-200967D01*
X607415Y-201626D01*
Y-201280D01*
X609067Y-200905D01*
X609071D01*
X609078Y-200901D01*
X609093Y-200898D01*
X609111Y-200894D01*
X609136Y-200890D01*
X609162Y-200883D01*
X609195Y-200876D01*
X609231Y-200869D01*
X609308Y-200850D01*
X609395Y-200832D01*
X609490Y-200814D01*
X609584Y-200796D01*
X609581D01*
X609566Y-200792D01*
X609548Y-200785D01*
X609519Y-200781D01*
X609490Y-200774D01*
X609453Y-200763D01*
X609373Y-200745D01*
X609293Y-200723D01*
X609253Y-200716D01*
X609217Y-200705D01*
X609184Y-200697D01*
X609155Y-200690D01*
X609133Y-200683D01*
X609118Y-200679D01*
X607415Y-200202D01*
Y-199798D01*
X608693Y-199442D01*
X608696D01*
X608714Y-199434D01*
X608740Y-199427D01*
X608773Y-199420D01*
X608816Y-199409D01*
X608863Y-199394D01*
X608918Y-199380D01*
X608980Y-199365D01*
X609049Y-199347D01*
X609118Y-199332D01*
X609268Y-199300D01*
X609424Y-199267D01*
X609584Y-199241D01*
X609581D01*
X609573Y-199238D01*
X609559D01*
X609541Y-199231D01*
X609519Y-199227D01*
X609493Y-199220D01*
X609460Y-199216D01*
X609424Y-199205D01*
X609344Y-199187D01*
X609249Y-199165D01*
X609148Y-199143D01*
X609035Y-199114D01*
X607415Y-198721D01*
Y-198382D01*
X609934Y-199074D01*
D02*
G37*
G36*
X609300Y-201859D02*
X609351Y-201866D01*
X609410Y-201881D01*
X609471Y-201899D01*
X609537Y-201928D01*
X609606Y-201968D01*
X609610D01*
X609613Y-201972D01*
X609635Y-201990D01*
X609668Y-202015D01*
X609704Y-202052D01*
X609748Y-202099D01*
X609795Y-202157D01*
X609839Y-202223D01*
X609879Y-202299D01*
Y-202303D01*
X609883Y-202310D01*
X609886Y-202321D01*
X609894Y-202336D01*
X609901Y-202357D01*
X609912Y-202383D01*
X609926Y-202441D01*
X609945Y-202510D01*
X609963Y-202594D01*
X609974Y-202685D01*
X609977Y-202783D01*
Y-202841D01*
X609974Y-202871D01*
Y-202903D01*
X609970Y-202940D01*
X609967Y-202983D01*
X609952Y-203074D01*
X609937Y-203169D01*
X609912Y-203264D01*
X609879Y-203355D01*
Y-203358D01*
X609875Y-203366D01*
X609868Y-203377D01*
X609861Y-203391D01*
X609839Y-203435D01*
X609806Y-203486D01*
X609763Y-203544D01*
X609712Y-203606D01*
X609650Y-203664D01*
X609581Y-203719D01*
X609577D01*
X609570Y-203726D01*
X609559Y-203730D01*
X609544Y-203741D01*
X609526Y-203748D01*
X609504Y-203759D01*
X609450Y-203784D01*
X609380Y-203810D01*
X609304Y-203832D01*
X609217Y-203846D01*
X609126Y-203853D01*
X609096Y-203540D01*
X609100D01*
X609104D01*
X609115Y-203537D01*
X609129D01*
X609162Y-203529D01*
X609209Y-203519D01*
X609257Y-203504D01*
X609311Y-203489D01*
X609362Y-203464D01*
X609410Y-203438D01*
X609413Y-203435D01*
X609428Y-203424D01*
X609453Y-203406D01*
X609479Y-203377D01*
X609512Y-203340D01*
X609544Y-203300D01*
X609577Y-203245D01*
X609606Y-203187D01*
Y-203184D01*
X609610Y-203180D01*
X609613Y-203169D01*
X609617Y-203158D01*
X609628Y-203122D01*
X609643Y-203074D01*
X609657Y-203016D01*
X609668Y-202951D01*
X609675Y-202878D01*
X609679Y-202798D01*
Y-202765D01*
X609675Y-202729D01*
X609672Y-202685D01*
X609664Y-202634D01*
X609657Y-202576D01*
X609643Y-202518D01*
X609624Y-202463D01*
X609621Y-202456D01*
X609613Y-202437D01*
X609599Y-202412D01*
X609584Y-202379D01*
X609559Y-202346D01*
X609533Y-202310D01*
X609504Y-202274D01*
X609468Y-202244D01*
X609464Y-202241D01*
X609450Y-202234D01*
X609431Y-202223D01*
X609402Y-202208D01*
X609373Y-202193D01*
X609337Y-202183D01*
X609297Y-202175D01*
X609253Y-202172D01*
X609249D01*
X609231D01*
X609209Y-202175D01*
X609180Y-202179D01*
X609151Y-202190D01*
X609115Y-202201D01*
X609078Y-202219D01*
X609046Y-202244D01*
X609042Y-202248D01*
X609031Y-202259D01*
X609016Y-202274D01*
X608995Y-202299D01*
X608973Y-202328D01*
X608947Y-202368D01*
X608922Y-202416D01*
X608900Y-202470D01*
X608896Y-202474D01*
X608893Y-202492D01*
X608882Y-202521D01*
X608878Y-202539D01*
X608871Y-202565D01*
X608860Y-202590D01*
X608853Y-202623D01*
X608842Y-202660D01*
X608831Y-202703D01*
X608820Y-202747D01*
X608805Y-202798D01*
X608791Y-202856D01*
X608776Y-202918D01*
Y-202922D01*
X608773Y-202933D01*
X608769Y-202951D01*
X608762Y-202973D01*
X608754Y-203002D01*
X608747Y-203034D01*
X608725Y-203107D01*
X608700Y-203187D01*
X608674Y-203271D01*
X608649Y-203344D01*
X608634Y-203377D01*
X608620Y-203406D01*
Y-203409D01*
X608616Y-203413D01*
X608602Y-203435D01*
X608583Y-203467D01*
X608554Y-203504D01*
X608521Y-203548D01*
X608481Y-203591D01*
X608434Y-203635D01*
X608383Y-203671D01*
X608376Y-203675D01*
X608358Y-203686D01*
X608328Y-203700D01*
X608292Y-203715D01*
X608245Y-203730D01*
X608190Y-203744D01*
X608132Y-203755D01*
X608070Y-203759D01*
X608066D01*
X608063D01*
X608052D01*
X608037D01*
X608001Y-203751D01*
X607954Y-203744D01*
X607899Y-203733D01*
X607837Y-203715D01*
X607775Y-203690D01*
X607713Y-203653D01*
X607710D01*
X607706Y-203649D01*
X607684Y-203631D01*
X607655Y-203606D01*
X607619Y-203573D01*
X607579Y-203529D01*
X607535Y-203475D01*
X607495Y-203409D01*
X607458Y-203337D01*
Y-203333D01*
X607455Y-203326D01*
X607451Y-203315D01*
X607444Y-203300D01*
X607437Y-203282D01*
X607429Y-203256D01*
X607415Y-203202D01*
X607400Y-203133D01*
X607386Y-203053D01*
X607375Y-202969D01*
X607371Y-202874D01*
Y-202827D01*
X607375Y-202801D01*
Y-202776D01*
X607382Y-202707D01*
X607393Y-202630D01*
X607411Y-202550D01*
X607433Y-202463D01*
X607462Y-202383D01*
Y-202379D01*
X607466Y-202372D01*
X607473Y-202361D01*
X607480Y-202346D01*
X607499Y-202310D01*
X607531Y-202263D01*
X607568Y-202208D01*
X607615Y-202153D01*
X607670Y-202102D01*
X607731Y-202055D01*
X607735D01*
X607739Y-202052D01*
X607750Y-202044D01*
X607761Y-202037D01*
X607797Y-202019D01*
X607844Y-201997D01*
X607903Y-201972D01*
X607972Y-201953D01*
X608044Y-201935D01*
X608125Y-201928D01*
X608150Y-202248D01*
X608146D01*
X608139D01*
X608128Y-202252D01*
X608110Y-202255D01*
X608070Y-202266D01*
X608015Y-202281D01*
X607957Y-202303D01*
X607899Y-202336D01*
X607844Y-202376D01*
X607793Y-202427D01*
X607790Y-202434D01*
X607775Y-202452D01*
X607753Y-202488D01*
X607731Y-202536D01*
X607710Y-202598D01*
X607688Y-202670D01*
X607673Y-202761D01*
X607670Y-202863D01*
Y-202914D01*
X607673Y-202936D01*
X607677Y-202965D01*
X607684Y-203031D01*
X607699Y-203103D01*
X607717Y-203176D01*
X607746Y-203245D01*
X607764Y-203275D01*
X607783Y-203304D01*
X607786Y-203311D01*
X607801Y-203326D01*
X607826Y-203347D01*
X607855Y-203369D01*
X607895Y-203395D01*
X607939Y-203417D01*
X607990Y-203431D01*
X608048Y-203438D01*
X608055D01*
X608070D01*
X608096Y-203435D01*
X608125Y-203428D01*
X608161Y-203417D01*
X608197Y-203398D01*
X608234Y-203377D01*
X608270Y-203344D01*
X608274Y-203340D01*
X608285Y-203322D01*
X608296Y-203307D01*
X608303Y-203293D01*
X608314Y-203271D01*
X608328Y-203245D01*
X608339Y-203213D01*
X608354Y-203176D01*
X608368Y-203136D01*
X608387Y-203089D01*
X608401Y-203038D01*
X608420Y-202980D01*
X608434Y-202914D01*
X608452Y-202841D01*
Y-202838D01*
X608456Y-202823D01*
X608460Y-202801D01*
X608467Y-202776D01*
X608474Y-202743D01*
X608485Y-202703D01*
X608496Y-202663D01*
X608507Y-202619D01*
X608532Y-202525D01*
X608558Y-202434D01*
X608572Y-202390D01*
X608587Y-202350D01*
X608598Y-202314D01*
X608612Y-202285D01*
Y-202281D01*
X608616Y-202274D01*
X608623Y-202263D01*
X608631Y-202248D01*
X608652Y-202208D01*
X608681Y-202161D01*
X608722Y-202106D01*
X608765Y-202052D01*
X608816Y-202001D01*
X608871Y-201957D01*
X608878Y-201953D01*
X608896Y-201939D01*
X608929Y-201924D01*
X608973Y-201902D01*
X609024Y-201884D01*
X609086Y-201866D01*
X609155Y-201855D01*
X609228Y-201851D01*
X609231D01*
X609235D01*
X609246D01*
X609260D01*
X609300Y-201859D01*
D02*
G37*
G36*
X602843Y-148171D02*
X602861D01*
X602887Y-148175D01*
X602949Y-148186D01*
X603018Y-148200D01*
X603094Y-148226D01*
X603171Y-148259D01*
X603247Y-148302D01*
X603251D01*
X603254Y-148310D01*
X603265Y-148317D01*
X603280Y-148328D01*
X603316Y-148357D01*
X603364Y-148397D01*
X603411Y-148452D01*
X603465Y-148517D01*
X603513Y-148593D01*
X603556Y-148681D01*
Y-148685D01*
X603560Y-148692D01*
X603567Y-148706D01*
X603575Y-148725D01*
X603582Y-148750D01*
X603593Y-148783D01*
X603600Y-148819D01*
X603611Y-148859D01*
X603622Y-148907D01*
X603633Y-148961D01*
X603640Y-149019D01*
X603647Y-149081D01*
X603655Y-149150D01*
X603662Y-149223D01*
X603666Y-149303D01*
Y-149387D01*
Y-149391D01*
Y-149409D01*
Y-149434D01*
Y-149467D01*
X603662Y-149507D01*
Y-149555D01*
X603658Y-149609D01*
X603651Y-149664D01*
X603640Y-149787D01*
X603622Y-149918D01*
X603596Y-150042D01*
X603578Y-150104D01*
X603560Y-150159D01*
Y-150162D01*
X603556Y-150170D01*
X603549Y-150184D01*
X603542Y-150206D01*
X603531Y-150228D01*
X603516Y-150257D01*
X603480Y-150319D01*
X603436Y-150388D01*
X603385Y-150461D01*
X603320Y-150530D01*
X603247Y-150592D01*
X603243D01*
X603236Y-150599D01*
X603225Y-150606D01*
X603211Y-150614D01*
X603189Y-150625D01*
X603167Y-150639D01*
X603138Y-150654D01*
X603109Y-150665D01*
X603040Y-150694D01*
X602956Y-150719D01*
X602865Y-150734D01*
X602763Y-150741D01*
X602734D01*
X602716Y-150738D01*
X602690D01*
X602661Y-150734D01*
X602592Y-150719D01*
X602515Y-150701D01*
X602435Y-150672D01*
X602355Y-150632D01*
X602315Y-150606D01*
X602279Y-150577D01*
X602275Y-150574D01*
X602272Y-150570D01*
X602261Y-150559D01*
X602250Y-150548D01*
X602235Y-150530D01*
X602217Y-150508D01*
X602180Y-150457D01*
X602144Y-150392D01*
X602108Y-150312D01*
X602079Y-150221D01*
X602057Y-150115D01*
X602355Y-150090D01*
Y-150093D01*
X602359Y-150101D01*
Y-150108D01*
X602362Y-150122D01*
X602373Y-150162D01*
X602388Y-150206D01*
X602406Y-150257D01*
X602432Y-150308D01*
X602461Y-150355D01*
X602497Y-150395D01*
X602501Y-150399D01*
X602515Y-150410D01*
X602541Y-150424D01*
X602570Y-150439D01*
X602610Y-150457D01*
X602657Y-150472D01*
X602712Y-150483D01*
X602770Y-150486D01*
X602796D01*
X602821Y-150483D01*
X602854Y-150479D01*
X602894Y-150472D01*
X602934Y-150461D01*
X602978Y-150446D01*
X603018Y-150424D01*
X603021Y-150421D01*
X603036Y-150414D01*
X603058Y-150399D01*
X603080Y-150377D01*
X603109Y-150352D01*
X603138Y-150322D01*
X603167Y-150290D01*
X603196Y-150250D01*
X603200Y-150246D01*
X603207Y-150228D01*
X603222Y-150202D01*
X603236Y-150170D01*
X603254Y-150126D01*
X603272Y-150075D01*
X603291Y-150017D01*
X603309Y-149951D01*
Y-149948D01*
X603313Y-149944D01*
Y-149933D01*
X603316Y-149918D01*
X603324Y-149882D01*
X603334Y-149835D01*
X603342Y-149776D01*
X603349Y-149715D01*
X603353Y-149645D01*
X603356Y-149573D01*
Y-149569D01*
Y-149558D01*
Y-149540D01*
Y-149511D01*
X603353Y-149518D01*
X603338Y-149536D01*
X603316Y-149562D01*
X603291Y-149598D01*
X603254Y-149635D01*
X603211Y-149675D01*
X603160Y-149715D01*
X603101Y-149751D01*
X603094Y-149755D01*
X603072Y-149766D01*
X603040Y-149780D01*
X602999Y-149795D01*
X602945Y-149813D01*
X602887Y-149828D01*
X602821Y-149838D01*
X602752Y-149842D01*
X602723D01*
X602701Y-149838D01*
X602672Y-149835D01*
X602643Y-149831D01*
X602606Y-149824D01*
X602570Y-149813D01*
X602486Y-149787D01*
X602443Y-149769D01*
X602399Y-149747D01*
X602352Y-149722D01*
X602308Y-149689D01*
X602264Y-149656D01*
X602224Y-149616D01*
X602221Y-149613D01*
X602213Y-149605D01*
X602206Y-149594D01*
X602191Y-149576D01*
X602173Y-149551D01*
X602155Y-149525D01*
X602137Y-149493D01*
X602119Y-149456D01*
X602097Y-149416D01*
X602079Y-149372D01*
X602060Y-149321D01*
X602042Y-149271D01*
X602028Y-149212D01*
X602020Y-149150D01*
X602013Y-149089D01*
X602009Y-149019D01*
Y-149016D01*
Y-149001D01*
Y-148983D01*
X602013Y-148958D01*
X602017Y-148925D01*
X602020Y-148885D01*
X602028Y-148845D01*
X602039Y-148797D01*
X602064Y-148703D01*
X602082Y-148652D01*
X602104Y-148597D01*
X602130Y-148546D01*
X602162Y-148499D01*
X602195Y-148448D01*
X602235Y-148404D01*
X602239Y-148401D01*
X602246Y-148393D01*
X602257Y-148382D01*
X602275Y-148368D01*
X602297Y-148350D01*
X602326Y-148328D01*
X602355Y-148310D01*
X602392Y-148284D01*
X602428Y-148262D01*
X602472Y-148244D01*
X602570Y-148204D01*
X602621Y-148189D01*
X602679Y-148179D01*
X602737Y-148171D01*
X602799Y-148168D01*
X602825D01*
X602843Y-148171D01*
D02*
G37*
G36*
X601216Y-150697D02*
X600907D01*
Y-148728D01*
X600903Y-148732D01*
X600885Y-148746D01*
X600863Y-148768D01*
X600826Y-148794D01*
X600786Y-148827D01*
X600735Y-148863D01*
X600677Y-148903D01*
X600612Y-148943D01*
X600608D01*
X600604Y-148947D01*
X600583Y-148961D01*
X600546Y-148979D01*
X600502Y-149001D01*
X600452Y-149027D01*
X600397Y-149052D01*
X600342Y-149078D01*
X600288Y-149100D01*
Y-148801D01*
X600291D01*
X600299Y-148794D01*
X600313Y-148790D01*
X600331Y-148779D01*
X600353Y-148768D01*
X600379Y-148754D01*
X600441Y-148717D01*
X600513Y-148677D01*
X600586Y-148626D01*
X600663Y-148568D01*
X600739Y-148506D01*
X600743Y-148503D01*
X600746Y-148499D01*
X600757Y-148488D01*
X600772Y-148477D01*
X600805Y-148441D01*
X600848Y-148397D01*
X600892Y-148346D01*
X600939Y-148288D01*
X600979Y-148230D01*
X601016Y-148168D01*
X601216D01*
Y-150697D01*
D02*
G37*
G36*
X598672Y-148182D02*
X598744Y-148186D01*
X598817Y-148193D01*
X598890Y-148204D01*
X598952Y-148215D01*
X598955D01*
X598963Y-148219D01*
X598974D01*
X598988Y-148226D01*
X599028Y-148237D01*
X599079Y-148255D01*
X599137Y-148281D01*
X599199Y-148313D01*
X599261Y-148350D01*
X599320Y-148397D01*
X599323Y-148401D01*
X599327Y-148404D01*
X599338Y-148415D01*
X599352Y-148426D01*
X599389Y-148462D01*
X599432Y-148513D01*
X599480Y-148575D01*
X599531Y-148648D01*
X599578Y-148732D01*
X599618Y-148827D01*
Y-148830D01*
X599622Y-148837D01*
X599629Y-148852D01*
X599633Y-148874D01*
X599643Y-148899D01*
X599651Y-148928D01*
X599658Y-148961D01*
X599669Y-149001D01*
X599680Y-149041D01*
X599687Y-149089D01*
X599705Y-149190D01*
X599716Y-149303D01*
X599720Y-149427D01*
Y-149431D01*
Y-149438D01*
Y-149456D01*
Y-149474D01*
X599716Y-149500D01*
Y-149529D01*
X599713Y-149598D01*
X599702Y-149678D01*
X599691Y-149762D01*
X599673Y-149849D01*
X599651Y-149937D01*
Y-149940D01*
X599647Y-149948D01*
X599643Y-149959D01*
X599640Y-149973D01*
X599625Y-150013D01*
X599603Y-150064D01*
X599582Y-150122D01*
X599552Y-150181D01*
X599516Y-150242D01*
X599480Y-150301D01*
X599476Y-150308D01*
X599461Y-150326D01*
X599440Y-150352D01*
X599410Y-150384D01*
X599378Y-150421D01*
X599338Y-150457D01*
X599298Y-150497D01*
X599250Y-150530D01*
X599243Y-150534D01*
X599228Y-150545D01*
X599203Y-150559D01*
X599167Y-150577D01*
X599123Y-150599D01*
X599072Y-150617D01*
X599014Y-150639D01*
X598948Y-150657D01*
X598941D01*
X598930Y-150661D01*
X598919Y-150665D01*
X598883Y-150668D01*
X598832Y-150676D01*
X598773Y-150683D01*
X598704Y-150690D01*
X598628Y-150694D01*
X598544Y-150697D01*
X597638D01*
Y-148179D01*
X598606D01*
X598672Y-148182D01*
D02*
G37*
G36*
X483591Y-263178D02*
X483638Y-263186D01*
X483697Y-263196D01*
X483762Y-263215D01*
X483827Y-263236D01*
X483893Y-263266D01*
X483897D01*
X483900Y-263269D01*
X483922Y-263280D01*
X483955Y-263302D01*
X483991Y-263328D01*
X484035Y-263364D01*
X484079Y-263404D01*
X484122Y-263451D01*
X484159Y-263506D01*
X484162Y-263513D01*
X484173Y-263531D01*
X484188Y-263564D01*
X484206Y-263604D01*
X484224Y-263651D01*
X484239Y-263706D01*
X484250Y-263768D01*
X484253Y-263830D01*
Y-263837D01*
Y-263859D01*
X484250Y-263888D01*
X484242Y-263928D01*
X484232Y-263975D01*
X484213Y-264026D01*
X484192Y-264077D01*
X484162Y-264128D01*
X484159Y-264136D01*
X484148Y-264150D01*
X484126Y-264176D01*
X484097Y-264205D01*
X484060Y-264237D01*
X484017Y-264274D01*
X483966Y-264307D01*
X483904Y-264339D01*
X483908D01*
X483915Y-264343D01*
X483926Y-264347D01*
X483940Y-264350D01*
X483980Y-264365D01*
X484031Y-264387D01*
X484090Y-264416D01*
X484148Y-264452D01*
X484202Y-264500D01*
X484253Y-264554D01*
X484257Y-264561D01*
X484272Y-264583D01*
X484293Y-264620D01*
X484315Y-264667D01*
X484337Y-264725D01*
X484359Y-264794D01*
X484374Y-264875D01*
X484377Y-264962D01*
Y-264966D01*
Y-264976D01*
Y-264995D01*
X484374Y-265016D01*
X484370Y-265046D01*
X484363Y-265078D01*
X484355Y-265115D01*
X484348Y-265155D01*
X484319Y-265242D01*
X484297Y-265289D01*
X484275Y-265333D01*
X484246Y-265380D01*
X484213Y-265428D01*
X484177Y-265475D01*
X484133Y-265519D01*
X484130Y-265522D01*
X484122Y-265530D01*
X484108Y-265541D01*
X484090Y-265555D01*
X484068Y-265573D01*
X484039Y-265592D01*
X484006Y-265613D01*
X483966Y-265632D01*
X483926Y-265653D01*
X483879Y-265675D01*
X483831Y-265693D01*
X483777Y-265712D01*
X483718Y-265726D01*
X483656Y-265737D01*
X483595Y-265744D01*
X483525Y-265748D01*
X483493D01*
X483471Y-265744D01*
X483442Y-265741D01*
X483409Y-265737D01*
X483372Y-265730D01*
X483332Y-265723D01*
X483245Y-265701D01*
X483154Y-265664D01*
X483107Y-265642D01*
X483063Y-265617D01*
X483019Y-265584D01*
X482976Y-265551D01*
X482972Y-265548D01*
X482965Y-265541D01*
X482954Y-265530D01*
X482943Y-265515D01*
X482925Y-265497D01*
X482907Y-265471D01*
X482885Y-265446D01*
X482863Y-265413D01*
X482841Y-265377D01*
X482819Y-265340D01*
X482779Y-265253D01*
X482746Y-265151D01*
X482735Y-265096D01*
X482728Y-265038D01*
X483038Y-264998D01*
Y-265002D01*
X483041Y-265009D01*
X483045Y-265024D01*
X483048Y-265042D01*
X483052Y-265064D01*
X483060Y-265089D01*
X483078Y-265144D01*
X483103Y-265209D01*
X483136Y-265271D01*
X483172Y-265330D01*
X483216Y-265380D01*
X483223Y-265384D01*
X483238Y-265399D01*
X483267Y-265417D01*
X483303Y-265435D01*
X483347Y-265457D01*
X483402Y-265475D01*
X483463Y-265490D01*
X483529Y-265493D01*
X483551D01*
X483565Y-265490D01*
X483605Y-265486D01*
X483656Y-265475D01*
X483715Y-265457D01*
X483777Y-265431D01*
X483838Y-265395D01*
X483897Y-265344D01*
X483904Y-265337D01*
X483922Y-265315D01*
X483944Y-265282D01*
X483973Y-265238D01*
X484002Y-265184D01*
X484024Y-265122D01*
X484042Y-265049D01*
X484050Y-264969D01*
Y-264966D01*
Y-264958D01*
Y-264947D01*
X484046Y-264933D01*
X484042Y-264893D01*
X484031Y-264845D01*
X484017Y-264787D01*
X483991Y-264729D01*
X483955Y-264671D01*
X483908Y-264616D01*
X483900Y-264609D01*
X483882Y-264594D01*
X483853Y-264572D01*
X483813Y-264547D01*
X483762Y-264521D01*
X483700Y-264500D01*
X483631Y-264485D01*
X483555Y-264478D01*
X483522D01*
X483496Y-264481D01*
X483463Y-264485D01*
X483427Y-264492D01*
X483383Y-264500D01*
X483336Y-264510D01*
X483372Y-264237D01*
X483391D01*
X483405Y-264241D01*
X483453D01*
X483493Y-264234D01*
X483540Y-264227D01*
X483595Y-264216D01*
X483656Y-264197D01*
X483715Y-264172D01*
X483777Y-264139D01*
X483780D01*
X483784Y-264136D01*
X483802Y-264121D01*
X483827Y-264095D01*
X483857Y-264063D01*
X483886Y-264015D01*
X483911Y-263961D01*
X483929Y-263899D01*
X483937Y-263863D01*
Y-263823D01*
Y-263819D01*
Y-263815D01*
Y-263793D01*
X483929Y-263764D01*
X483922Y-263724D01*
X483908Y-263681D01*
X483889Y-263633D01*
X483860Y-263586D01*
X483820Y-263542D01*
X483817Y-263539D01*
X483798Y-263524D01*
X483773Y-263506D01*
X483740Y-263484D01*
X483697Y-263466D01*
X483645Y-263448D01*
X483587Y-263433D01*
X483522Y-263429D01*
X483493D01*
X483460Y-263437D01*
X483416Y-263444D01*
X483369Y-263458D01*
X483322Y-263477D01*
X483271Y-263506D01*
X483223Y-263542D01*
X483220Y-263546D01*
X483205Y-263564D01*
X483183Y-263590D01*
X483158Y-263626D01*
X483132Y-263673D01*
X483107Y-263732D01*
X483085Y-263801D01*
X483070Y-263881D01*
X482761Y-263826D01*
Y-263823D01*
X482765Y-263812D01*
X482768Y-263797D01*
X482772Y-263775D01*
X482779Y-263750D01*
X482790Y-263721D01*
X482812Y-263651D01*
X482848Y-263571D01*
X482892Y-263491D01*
X482947Y-263415D01*
X483016Y-263346D01*
X483019Y-263342D01*
X483027Y-263338D01*
X483038Y-263331D01*
X483052Y-263320D01*
X483070Y-263306D01*
X483096Y-263291D01*
X483121Y-263277D01*
X483154Y-263258D01*
X483227Y-263229D01*
X483311Y-263200D01*
X483409Y-263182D01*
X483460Y-263175D01*
X483551D01*
X483591Y-263178D01*
D02*
G37*
G36*
X482295Y-264641D02*
Y-264645D01*
Y-264660D01*
Y-264678D01*
Y-264703D01*
X482291Y-264736D01*
Y-264773D01*
X482288Y-264816D01*
X482284Y-264860D01*
X482273Y-264958D01*
X482259Y-265060D01*
X482237Y-265158D01*
X482222Y-265206D01*
X482208Y-265249D01*
Y-265253D01*
X482204Y-265260D01*
X482197Y-265271D01*
X482190Y-265286D01*
X482168Y-265326D01*
X482135Y-265377D01*
X482091Y-265435D01*
X482040Y-265493D01*
X481975Y-265555D01*
X481895Y-265610D01*
X481891D01*
X481884Y-265617D01*
X481873Y-265621D01*
X481855Y-265632D01*
X481833Y-265642D01*
X481804Y-265653D01*
X481775Y-265664D01*
X481738Y-265679D01*
X481698Y-265693D01*
X481654Y-265704D01*
X481607Y-265715D01*
X481553Y-265726D01*
X481498Y-265734D01*
X481440Y-265741D01*
X481309Y-265748D01*
X481276D01*
X481250Y-265744D01*
X481221D01*
X481185Y-265741D01*
X481145Y-265737D01*
X481105Y-265734D01*
X481014Y-265719D01*
X480915Y-265697D01*
X480821Y-265668D01*
X480730Y-265628D01*
X480726D01*
X480719Y-265621D01*
X480708Y-265613D01*
X480693Y-265606D01*
X480653Y-265577D01*
X480606Y-265537D01*
X480551Y-265486D01*
X480501Y-265428D01*
X480450Y-265355D01*
X480410Y-265275D01*
Y-265271D01*
X480406Y-265264D01*
X480402Y-265249D01*
X480395Y-265231D01*
X480388Y-265209D01*
X480380Y-265180D01*
X480370Y-265147D01*
X480362Y-265107D01*
X480355Y-265064D01*
X480344Y-265016D01*
X480337Y-264966D01*
X480330Y-264911D01*
X480322Y-264849D01*
X480318Y-264784D01*
X480315Y-264714D01*
Y-264641D01*
Y-263186D01*
X480650D01*
Y-264641D01*
Y-264645D01*
Y-264656D01*
Y-264674D01*
Y-264696D01*
X480653Y-264722D01*
Y-264754D01*
X480657Y-264824D01*
X480664Y-264904D01*
X480675Y-264984D01*
X480690Y-265060D01*
X480697Y-265093D01*
X480708Y-265126D01*
X480712Y-265133D01*
X480719Y-265151D01*
X480737Y-265177D01*
X480759Y-265213D01*
X480785Y-265249D01*
X480821Y-265289D01*
X480864Y-265330D01*
X480915Y-265362D01*
X480923Y-265366D01*
X480941Y-265377D01*
X480974Y-265388D01*
X481017Y-265402D01*
X481068Y-265421D01*
X481134Y-265431D01*
X481203Y-265442D01*
X481280Y-265446D01*
X481316D01*
X481338Y-265442D01*
X481370D01*
X481403Y-265439D01*
X481483Y-265424D01*
X481571Y-265406D01*
X481654Y-265377D01*
X481735Y-265337D01*
X481771Y-265311D01*
X481804Y-265282D01*
X481807Y-265279D01*
X481811Y-265275D01*
X481818Y-265264D01*
X481829Y-265249D01*
X481840Y-265228D01*
X481855Y-265206D01*
X481869Y-265173D01*
X481884Y-265140D01*
X481898Y-265100D01*
X481909Y-265053D01*
X481924Y-264998D01*
X481935Y-264940D01*
X481946Y-264875D01*
X481953Y-264805D01*
X481960Y-264725D01*
Y-264641D01*
Y-263186D01*
X482295D01*
Y-264641D01*
D02*
G37*
G36*
X485578Y-263178D02*
X485626Y-263186D01*
X485680Y-263196D01*
X485739Y-263211D01*
X485800Y-263229D01*
X485859Y-263258D01*
X485862D01*
X485866Y-263262D01*
X485884Y-263273D01*
X485913Y-263291D01*
X485950Y-263317D01*
X485990Y-263353D01*
X486033Y-263393D01*
X486073Y-263440D01*
X486113Y-263495D01*
X486117Y-263502D01*
X486132Y-263520D01*
X486146Y-263553D01*
X486172Y-263600D01*
X486194Y-263655D01*
X486223Y-263717D01*
X486248Y-263790D01*
X486270Y-263870D01*
Y-263874D01*
X486274Y-263881D01*
X486277Y-263892D01*
X486281Y-263910D01*
X486284Y-263932D01*
X486288Y-263957D01*
X486295Y-263990D01*
X486299Y-264026D01*
X486306Y-264066D01*
X486310Y-264110D01*
X486314Y-264161D01*
X486321Y-264212D01*
X486325Y-264270D01*
Y-264329D01*
X486328Y-264394D01*
Y-264463D01*
Y-264467D01*
Y-264481D01*
Y-264507D01*
Y-264536D01*
X486325Y-264576D01*
Y-264620D01*
X486321Y-264667D01*
X486317Y-264718D01*
X486306Y-264834D01*
X486288Y-264955D01*
X486266Y-265071D01*
X486252Y-265126D01*
X486234Y-265180D01*
Y-265184D01*
X486230Y-265191D01*
X486223Y-265206D01*
X486215Y-265224D01*
X486208Y-265249D01*
X486194Y-265275D01*
X486164Y-265337D01*
X486128Y-265402D01*
X486081Y-265475D01*
X486026Y-265541D01*
X485960Y-265602D01*
X485957D01*
X485953Y-265610D01*
X485942Y-265617D01*
X485928Y-265624D01*
X485910Y-265635D01*
X485891Y-265650D01*
X485837Y-265675D01*
X485771Y-265701D01*
X485695Y-265726D01*
X485604Y-265741D01*
X485506Y-265748D01*
X485469D01*
X485444Y-265744D01*
X485415Y-265741D01*
X485378Y-265734D01*
X485338Y-265726D01*
X485294Y-265715D01*
X485251Y-265701D01*
X485203Y-265686D01*
X485156Y-265664D01*
X485109Y-265639D01*
X485062Y-265610D01*
X485014Y-265573D01*
X484971Y-265533D01*
X484930Y-265490D01*
X484927Y-265486D01*
X484920Y-265475D01*
X484909Y-265457D01*
X484890Y-265428D01*
X484872Y-265395D01*
X484854Y-265351D01*
X484829Y-265300D01*
X484807Y-265242D01*
X484785Y-265177D01*
X484763Y-265100D01*
X484741Y-265016D01*
X484723Y-264922D01*
X484705Y-264820D01*
X484694Y-264711D01*
X484687Y-264591D01*
X484683Y-264463D01*
Y-264459D01*
Y-264445D01*
Y-264420D01*
Y-264390D01*
X484687Y-264350D01*
Y-264307D01*
X484690Y-264259D01*
X484694Y-264205D01*
X484705Y-264092D01*
X484723Y-263972D01*
X484745Y-263852D01*
X484759Y-263797D01*
X484774Y-263742D01*
Y-263739D01*
X484777Y-263732D01*
X484785Y-263717D01*
X484792Y-263699D01*
X484799Y-263673D01*
X484814Y-263648D01*
X484843Y-263586D01*
X484879Y-263520D01*
X484927Y-263451D01*
X484981Y-263382D01*
X485047Y-263324D01*
X485051D01*
X485054Y-263317D01*
X485065Y-263309D01*
X485080Y-263302D01*
X485098Y-263287D01*
X485120Y-263277D01*
X485174Y-263247D01*
X485240Y-263222D01*
X485316Y-263196D01*
X485407Y-263182D01*
X485506Y-263175D01*
X485538D01*
X485578Y-263178D01*
D02*
G37*
G36*
X189720Y-89265D02*
X187751D01*
X187754Y-89268D01*
X187769Y-89287D01*
X187791Y-89309D01*
X187816Y-89345D01*
X187849Y-89385D01*
X187886Y-89436D01*
X187926Y-89494D01*
X187966Y-89560D01*
Y-89563D01*
X187969Y-89567D01*
X187984Y-89589D01*
X188002Y-89625D01*
X188024Y-89669D01*
X188049Y-89720D01*
X188075Y-89774D01*
X188100Y-89829D01*
X188122Y-89884D01*
X187824D01*
Y-89880D01*
X187816Y-89873D01*
X187813Y-89858D01*
X187802Y-89840D01*
X187791Y-89818D01*
X187776Y-89793D01*
X187740Y-89731D01*
X187700Y-89658D01*
X187649Y-89585D01*
X187591Y-89509D01*
X187529Y-89432D01*
X187525Y-89429D01*
X187522Y-89425D01*
X187511Y-89414D01*
X187500Y-89399D01*
X187463Y-89367D01*
X187420Y-89323D01*
X187369Y-89279D01*
X187311Y-89232D01*
X187252Y-89192D01*
X187190Y-89156D01*
Y-88955D01*
X189720D01*
Y-89265D01*
D02*
G37*
G36*
X189032Y-90430D02*
X189061Y-90433D01*
X189094Y-90441D01*
X189130Y-90448D01*
X189171Y-90455D01*
X189258Y-90484D01*
X189305Y-90506D01*
X189349Y-90528D01*
X189396Y-90557D01*
X189444Y-90590D01*
X189491Y-90626D01*
X189534Y-90670D01*
X189538Y-90674D01*
X189545Y-90681D01*
X189556Y-90695D01*
X189571Y-90714D01*
X189589Y-90735D01*
X189607Y-90764D01*
X189629Y-90797D01*
X189647Y-90837D01*
X189669Y-90877D01*
X189691Y-90925D01*
X189709Y-90972D01*
X189727Y-91027D01*
X189742Y-91085D01*
X189753Y-91147D01*
X189760Y-91209D01*
X189764Y-91278D01*
Y-91311D01*
X189760Y-91332D01*
X189757Y-91361D01*
X189753Y-91394D01*
X189746Y-91431D01*
X189738Y-91471D01*
X189716Y-91558D01*
X189680Y-91649D01*
X189658Y-91696D01*
X189633Y-91740D01*
X189600Y-91784D01*
X189567Y-91827D01*
X189564Y-91831D01*
X189556Y-91838D01*
X189545Y-91849D01*
X189531Y-91860D01*
X189513Y-91878D01*
X189487Y-91897D01*
X189462Y-91918D01*
X189429Y-91940D01*
X189393Y-91962D01*
X189356Y-91984D01*
X189269Y-92024D01*
X189167Y-92057D01*
X189112Y-92068D01*
X189054Y-92075D01*
X189014Y-91765D01*
X189018D01*
X189025Y-91762D01*
X189040Y-91758D01*
X189058Y-91755D01*
X189079Y-91751D01*
X189105Y-91744D01*
X189160Y-91725D01*
X189225Y-91700D01*
X189287Y-91667D01*
X189345Y-91631D01*
X189396Y-91587D01*
X189400Y-91580D01*
X189414Y-91565D01*
X189433Y-91536D01*
X189451Y-91500D01*
X189473Y-91456D01*
X189491Y-91401D01*
X189505Y-91340D01*
X189509Y-91274D01*
Y-91252D01*
X189505Y-91238D01*
X189502Y-91198D01*
X189491Y-91147D01*
X189473Y-91088D01*
X189447Y-91027D01*
X189411Y-90965D01*
X189360Y-90907D01*
X189353Y-90899D01*
X189331Y-90881D01*
X189298Y-90859D01*
X189254Y-90830D01*
X189200Y-90801D01*
X189138Y-90779D01*
X189065Y-90761D01*
X188985Y-90754D01*
X188981D01*
X188974D01*
X188963D01*
X188949Y-90757D01*
X188908Y-90761D01*
X188861Y-90772D01*
X188803Y-90786D01*
X188745Y-90812D01*
X188686Y-90848D01*
X188632Y-90896D01*
X188625Y-90903D01*
X188610Y-90921D01*
X188588Y-90950D01*
X188563Y-90990D01*
X188537Y-91041D01*
X188515Y-91103D01*
X188501Y-91172D01*
X188494Y-91249D01*
Y-91281D01*
X188497Y-91307D01*
X188501Y-91340D01*
X188508Y-91376D01*
X188515Y-91420D01*
X188526Y-91467D01*
X188253Y-91431D01*
Y-91412D01*
X188257Y-91398D01*
Y-91351D01*
X188250Y-91311D01*
X188242Y-91263D01*
X188231Y-91209D01*
X188213Y-91147D01*
X188188Y-91088D01*
X188155Y-91027D01*
Y-91023D01*
X188151Y-91019D01*
X188137Y-91001D01*
X188111Y-90976D01*
X188078Y-90947D01*
X188031Y-90917D01*
X187977Y-90892D01*
X187915Y-90874D01*
X187878Y-90866D01*
X187838D01*
X187835D01*
X187831D01*
X187809D01*
X187780Y-90874D01*
X187740Y-90881D01*
X187696Y-90896D01*
X187649Y-90914D01*
X187602Y-90943D01*
X187558Y-90983D01*
X187554Y-90987D01*
X187540Y-91005D01*
X187522Y-91030D01*
X187500Y-91063D01*
X187481Y-91107D01*
X187463Y-91158D01*
X187449Y-91216D01*
X187445Y-91281D01*
Y-91311D01*
X187452Y-91343D01*
X187460Y-91387D01*
X187474Y-91434D01*
X187493Y-91482D01*
X187522Y-91533D01*
X187558Y-91580D01*
X187562Y-91584D01*
X187580Y-91598D01*
X187605Y-91620D01*
X187642Y-91645D01*
X187689Y-91671D01*
X187747Y-91696D01*
X187816Y-91718D01*
X187897Y-91733D01*
X187842Y-92042D01*
X187838D01*
X187827Y-92039D01*
X187813Y-92035D01*
X187791Y-92031D01*
X187766Y-92024D01*
X187736Y-92013D01*
X187667Y-91991D01*
X187587Y-91955D01*
X187507Y-91911D01*
X187431Y-91856D01*
X187361Y-91787D01*
X187358Y-91784D01*
X187354Y-91776D01*
X187347Y-91765D01*
X187336Y-91751D01*
X187321Y-91733D01*
X187307Y-91707D01*
X187292Y-91682D01*
X187274Y-91649D01*
X187245Y-91576D01*
X187216Y-91492D01*
X187198Y-91394D01*
X187190Y-91343D01*
Y-91252D01*
X187194Y-91212D01*
X187201Y-91165D01*
X187212Y-91107D01*
X187230Y-91041D01*
X187252Y-90976D01*
X187281Y-90910D01*
Y-90907D01*
X187285Y-90903D01*
X187296Y-90881D01*
X187318Y-90848D01*
X187343Y-90812D01*
X187380Y-90768D01*
X187420Y-90724D01*
X187467Y-90681D01*
X187522Y-90644D01*
X187529Y-90641D01*
X187547Y-90630D01*
X187580Y-90615D01*
X187620Y-90597D01*
X187667Y-90579D01*
X187722Y-90564D01*
X187784Y-90553D01*
X187846Y-90550D01*
X187853D01*
X187875D01*
X187904Y-90553D01*
X187944Y-90561D01*
X187991Y-90572D01*
X188042Y-90590D01*
X188093Y-90612D01*
X188144Y-90641D01*
X188151Y-90644D01*
X188166Y-90655D01*
X188191Y-90677D01*
X188221Y-90706D01*
X188253Y-90743D01*
X188290Y-90786D01*
X188322Y-90837D01*
X188355Y-90899D01*
Y-90896D01*
X188359Y-90888D01*
X188362Y-90877D01*
X188366Y-90863D01*
X188381Y-90823D01*
X188402Y-90772D01*
X188432Y-90714D01*
X188468Y-90655D01*
X188515Y-90601D01*
X188570Y-90550D01*
X188577Y-90546D01*
X188599Y-90532D01*
X188635Y-90510D01*
X188683Y-90488D01*
X188741Y-90466D01*
X188810Y-90444D01*
X188890Y-90430D01*
X188978Y-90426D01*
X188981D01*
X188992D01*
X189010D01*
X189032Y-90430D01*
D02*
G37*
G36*
X188752Y-92512D02*
X188788D01*
X188832Y-92515D01*
X188876Y-92519D01*
X188974Y-92530D01*
X189076Y-92545D01*
X189174Y-92566D01*
X189222Y-92581D01*
X189265Y-92595D01*
X189269D01*
X189276Y-92599D01*
X189287Y-92606D01*
X189302Y-92614D01*
X189342Y-92636D01*
X189393Y-92668D01*
X189451Y-92712D01*
X189509Y-92763D01*
X189571Y-92828D01*
X189626Y-92909D01*
Y-92912D01*
X189633Y-92919D01*
X189636Y-92930D01*
X189647Y-92949D01*
X189658Y-92970D01*
X189669Y-93000D01*
X189680Y-93029D01*
X189695Y-93065D01*
X189709Y-93105D01*
X189720Y-93149D01*
X189731Y-93196D01*
X189742Y-93251D01*
X189749Y-93305D01*
X189757Y-93363D01*
X189764Y-93494D01*
Y-93527D01*
X189760Y-93553D01*
Y-93582D01*
X189757Y-93618D01*
X189753Y-93658D01*
X189749Y-93698D01*
X189735Y-93789D01*
X189713Y-93888D01*
X189684Y-93982D01*
X189644Y-94073D01*
Y-94077D01*
X189636Y-94084D01*
X189629Y-94095D01*
X189622Y-94110D01*
X189593Y-94150D01*
X189553Y-94197D01*
X189502Y-94252D01*
X189444Y-94303D01*
X189371Y-94354D01*
X189291Y-94394D01*
X189287D01*
X189280Y-94397D01*
X189265Y-94401D01*
X189247Y-94408D01*
X189225Y-94415D01*
X189196Y-94423D01*
X189163Y-94434D01*
X189123Y-94441D01*
X189079Y-94448D01*
X189032Y-94459D01*
X188981Y-94466D01*
X188927Y-94474D01*
X188865Y-94481D01*
X188799Y-94485D01*
X188730Y-94488D01*
X188657D01*
X187201D01*
Y-94153D01*
X188657D01*
X188661D01*
X188672D01*
X188690D01*
X188712D01*
X188737Y-94150D01*
X188770D01*
X188839Y-94146D01*
X188919Y-94139D01*
X188999Y-94128D01*
X189076Y-94113D01*
X189109Y-94106D01*
X189141Y-94095D01*
X189149Y-94091D01*
X189167Y-94084D01*
X189192Y-94066D01*
X189229Y-94044D01*
X189265Y-94019D01*
X189305Y-93982D01*
X189345Y-93939D01*
X189378Y-93888D01*
X189382Y-93880D01*
X189393Y-93862D01*
X189403Y-93829D01*
X189418Y-93786D01*
X189436Y-93735D01*
X189447Y-93669D01*
X189458Y-93600D01*
X189462Y-93524D01*
Y-93487D01*
X189458Y-93465D01*
Y-93433D01*
X189454Y-93400D01*
X189440Y-93320D01*
X189422Y-93232D01*
X189393Y-93149D01*
X189353Y-93069D01*
X189327Y-93032D01*
X189298Y-93000D01*
X189294Y-92996D01*
X189291Y-92992D01*
X189280Y-92985D01*
X189265Y-92974D01*
X189243Y-92963D01*
X189222Y-92949D01*
X189189Y-92934D01*
X189156Y-92919D01*
X189116Y-92905D01*
X189069Y-92894D01*
X189014Y-92879D01*
X188956Y-92868D01*
X188890Y-92857D01*
X188821Y-92850D01*
X188741Y-92843D01*
X188657D01*
X187201D01*
Y-92508D01*
X188657D01*
X188661D01*
X188675D01*
X188694D01*
X188719D01*
X188752Y-92512D01*
D02*
G37*
G36*
X189070Y-33913D02*
X189674D01*
Y-34222D01*
X189070D01*
Y-35318D01*
X188786D01*
X187155Y-34164D01*
Y-33913D01*
X188786D01*
Y-33571D01*
X189070D01*
Y-33913D01*
D02*
G37*
G36*
Y-35871D02*
X189674D01*
Y-36181D01*
X189070D01*
Y-37277D01*
X188786D01*
X187155Y-36123D01*
Y-35871D01*
X188786D01*
Y-35529D01*
X189070D01*
Y-35871D01*
D02*
G37*
G36*
X188953Y-37593D02*
X188982D01*
X189051Y-37600D01*
X189131Y-37608D01*
X189215Y-37622D01*
X189292Y-37644D01*
X189364Y-37670D01*
X189368D01*
X189372Y-37673D01*
X189393Y-37684D01*
X189423Y-37702D01*
X189463Y-37728D01*
X189503Y-37764D01*
X189546Y-37804D01*
X189590Y-37855D01*
X189627Y-37914D01*
X189630Y-37921D01*
X189641Y-37943D01*
X189656Y-37975D01*
X189670Y-38023D01*
X189688Y-38081D01*
X189703Y-38146D01*
X189714Y-38219D01*
X189717Y-38299D01*
Y-38332D01*
X189714Y-38354D01*
X189710Y-38383D01*
X189707Y-38412D01*
X189692Y-38489D01*
X189670Y-38569D01*
X189637Y-38652D01*
X189616Y-38696D01*
X189590Y-38736D01*
X189561Y-38772D01*
X189528Y-38809D01*
X189525Y-38813D01*
X189521Y-38816D01*
X189506Y-38824D01*
X189492Y-38834D01*
X189474Y-38849D01*
X189448Y-38864D01*
X189419Y-38878D01*
X189386Y-38896D01*
X189350Y-38911D01*
X189306Y-38925D01*
X189262Y-38940D01*
X189211Y-38954D01*
X189157Y-38962D01*
X189095Y-38973D01*
X189033Y-38976D01*
X188964D01*
X188920Y-38674D01*
X188924D01*
X188931D01*
X188946D01*
X188968Y-38671D01*
X188989Y-38667D01*
X189015D01*
X189077Y-38656D01*
X189142Y-38645D01*
X189208Y-38623D01*
X189266Y-38601D01*
X189292Y-38587D01*
X189313Y-38569D01*
X189317Y-38565D01*
X189328Y-38550D01*
X189346Y-38529D01*
X189364Y-38500D01*
X189386Y-38460D01*
X189401Y-38416D01*
X189415Y-38361D01*
X189419Y-38303D01*
Y-38281D01*
X189415Y-38259D01*
X189412Y-38227D01*
X189404Y-38194D01*
X189397Y-38157D01*
X189383Y-38121D01*
X189364Y-38085D01*
X189361Y-38081D01*
X189354Y-38070D01*
X189339Y-38056D01*
X189324Y-38034D01*
X189299Y-38015D01*
X189273Y-37994D01*
X189244Y-37975D01*
X189208Y-37961D01*
X189204D01*
X189190Y-37953D01*
X189164Y-37950D01*
X189131Y-37943D01*
X189088Y-37935D01*
X189033Y-37932D01*
X188968Y-37924D01*
X188891D01*
X187155D01*
Y-37589D01*
X188873D01*
X188877D01*
X188888D01*
X188902D01*
X188924D01*
X188953Y-37593D01*
D02*
G37*
G36*
X531313Y-276526D02*
X531342Y-276530D01*
X531375Y-276534D01*
X531415Y-276537D01*
X531455Y-276548D01*
X531546Y-276570D01*
X531637Y-276603D01*
X531684Y-276625D01*
X531732Y-276650D01*
X531776Y-276679D01*
X531819Y-276712D01*
X531823Y-276716D01*
X531830Y-276719D01*
X531837Y-276734D01*
X531852Y-276748D01*
X531870Y-276766D01*
X531888Y-276788D01*
X531910Y-276817D01*
X531928Y-276850D01*
X531950Y-276883D01*
X531972Y-276923D01*
X532012Y-277010D01*
X532045Y-277112D01*
X532056Y-277167D01*
X532063Y-277225D01*
X531739Y-277251D01*
Y-277247D01*
Y-277240D01*
X531735Y-277229D01*
X531732Y-277211D01*
X531721Y-277171D01*
X531706Y-277116D01*
X531684Y-277061D01*
X531655Y-276999D01*
X531619Y-276945D01*
X531575Y-276894D01*
X531568Y-276890D01*
X531553Y-276876D01*
X531524Y-276857D01*
X531484Y-276836D01*
X531441Y-276814D01*
X531386Y-276796D01*
X531324Y-276781D01*
X531255Y-276778D01*
X531233D01*
X531218Y-276781D01*
X531175Y-276785D01*
X531124Y-276799D01*
X531062Y-276817D01*
X531000Y-276847D01*
X530935Y-276890D01*
X530905Y-276916D01*
X530876Y-276945D01*
X530873Y-276948D01*
X530869Y-276952D01*
X530862Y-276963D01*
X530851Y-276974D01*
X530825Y-277014D01*
X530796Y-277065D01*
X530771Y-277127D01*
X530745Y-277203D01*
X530727Y-277294D01*
X530720Y-277342D01*
Y-277393D01*
Y-277396D01*
Y-277403D01*
Y-277418D01*
X530723Y-277436D01*
Y-277458D01*
X530727Y-277484D01*
X530738Y-277542D01*
X530756Y-277611D01*
X530782Y-277680D01*
X530818Y-277746D01*
X530869Y-277808D01*
Y-277811D01*
X530876Y-277815D01*
X530895Y-277833D01*
X530927Y-277858D01*
X530971Y-277888D01*
X531029Y-277913D01*
X531095Y-277939D01*
X531171Y-277957D01*
X531215Y-277964D01*
X531284D01*
X531313Y-277960D01*
X531350Y-277957D01*
X531393Y-277946D01*
X531437Y-277935D01*
X531484Y-277917D01*
X531532Y-277895D01*
X531535Y-277891D01*
X531550Y-277884D01*
X531572Y-277866D01*
X531601Y-277848D01*
X531630Y-277822D01*
X531659Y-277789D01*
X531692Y-277757D01*
X531717Y-277717D01*
X532008Y-277757D01*
X531765Y-279052D01*
X530512D01*
Y-278758D01*
X531521D01*
X531655Y-278077D01*
X531652Y-278081D01*
X531644Y-278084D01*
X531634Y-278092D01*
X531615Y-278102D01*
X531594Y-278113D01*
X531568Y-278128D01*
X531510Y-278157D01*
X531437Y-278186D01*
X531357Y-278212D01*
X531270Y-278230D01*
X531226Y-278237D01*
X531146D01*
X531124Y-278234D01*
X531095Y-278230D01*
X531062Y-278226D01*
X531026Y-278219D01*
X530986Y-278208D01*
X530898Y-278183D01*
X530851Y-278164D01*
X530804Y-278139D01*
X530756Y-278113D01*
X530709Y-278084D01*
X530665Y-278048D01*
X530622Y-278008D01*
X530618Y-278004D01*
X530611Y-277997D01*
X530600Y-277986D01*
X530585Y-277968D01*
X530567Y-277942D01*
X530549Y-277917D01*
X530527Y-277884D01*
X530505Y-277848D01*
X530487Y-277808D01*
X530465Y-277764D01*
X530447Y-277713D01*
X530429Y-277662D01*
X530414Y-277607D01*
X530403Y-277545D01*
X530396Y-277484D01*
X530392Y-277418D01*
Y-277414D01*
Y-277403D01*
Y-277385D01*
X530396Y-277360D01*
X530400Y-277331D01*
X530403Y-277298D01*
X530410Y-277258D01*
X530418Y-277218D01*
X530440Y-277123D01*
X530476Y-277025D01*
X530498Y-276974D01*
X530527Y-276927D01*
X530556Y-276876D01*
X530592Y-276828D01*
X530596Y-276825D01*
X530603Y-276814D01*
X530618Y-276799D01*
X530636Y-276781D01*
X530662Y-276759D01*
X530691Y-276730D01*
X530727Y-276705D01*
X530767Y-276676D01*
X530811Y-276646D01*
X530862Y-276621D01*
X530916Y-276595D01*
X530975Y-276570D01*
X531037Y-276552D01*
X531106Y-276537D01*
X531179Y-276526D01*
X531255Y-276523D01*
X531288D01*
X531313Y-276526D01*
D02*
G37*
G36*
X535204D02*
X535233Y-276530D01*
X535263Y-276534D01*
X535339Y-276548D01*
X535419Y-276570D01*
X535503Y-276603D01*
X535546Y-276625D01*
X535587Y-276650D01*
X535623Y-276679D01*
X535659Y-276712D01*
X535663Y-276716D01*
X535667Y-276719D01*
X535674Y-276734D01*
X535685Y-276748D01*
X535699Y-276766D01*
X535714Y-276792D01*
X535729Y-276821D01*
X535747Y-276854D01*
X535761Y-276890D01*
X535776Y-276934D01*
X535790Y-276978D01*
X535805Y-277029D01*
X535812Y-277083D01*
X535823Y-277145D01*
X535827Y-277207D01*
Y-277276D01*
X535525Y-277320D01*
Y-277316D01*
Y-277309D01*
Y-277294D01*
X535521Y-277273D01*
X535517Y-277251D01*
Y-277225D01*
X535506Y-277163D01*
X535496Y-277098D01*
X535474Y-277032D01*
X535452Y-276974D01*
X535437Y-276948D01*
X535419Y-276927D01*
X535415Y-276923D01*
X535401Y-276912D01*
X535379Y-276894D01*
X535350Y-276876D01*
X535310Y-276854D01*
X535266Y-276839D01*
X535212Y-276825D01*
X535153Y-276821D01*
X535132D01*
X535110Y-276825D01*
X535077Y-276828D01*
X535044Y-276836D01*
X535008Y-276843D01*
X534971Y-276857D01*
X534935Y-276876D01*
X534931Y-276879D01*
X534920Y-276887D01*
X534906Y-276901D01*
X534884Y-276916D01*
X534866Y-276941D01*
X534844Y-276967D01*
X534826Y-276996D01*
X534811Y-277032D01*
Y-277036D01*
X534804Y-277050D01*
X534800Y-277076D01*
X534793Y-277109D01*
X534786Y-277152D01*
X534782Y-277207D01*
X534775Y-277273D01*
Y-277349D01*
Y-279085D01*
X534440D01*
Y-277367D01*
Y-277363D01*
Y-277353D01*
Y-277338D01*
Y-277316D01*
X534444Y-277287D01*
Y-277258D01*
X534451Y-277189D01*
X534458Y-277109D01*
X534473Y-277025D01*
X534494Y-276948D01*
X534520Y-276876D01*
Y-276872D01*
X534524Y-276869D01*
X534535Y-276847D01*
X534553Y-276817D01*
X534578Y-276778D01*
X534615Y-276737D01*
X534655Y-276694D01*
X534706Y-276650D01*
X534764Y-276614D01*
X534771Y-276610D01*
X534793Y-276599D01*
X534826Y-276585D01*
X534873Y-276570D01*
X534931Y-276552D01*
X534997Y-276537D01*
X535070Y-276526D01*
X535150Y-276523D01*
X535183D01*
X535204Y-276526D01*
D02*
G37*
G36*
X533031Y-277171D02*
X534127D01*
Y-277454D01*
X532973Y-279085D01*
X532722D01*
Y-277454D01*
X532380D01*
Y-277171D01*
X532722D01*
Y-276566D01*
X533031D01*
Y-277171D01*
D02*
G37*
G36*
X168459Y-124746D02*
X168507Y-124753D01*
X168565Y-124764D01*
X168630Y-124783D01*
X168696Y-124804D01*
X168761Y-124833D01*
X168765D01*
X168769Y-124837D01*
X168790Y-124848D01*
X168823Y-124870D01*
X168860Y-124895D01*
X168903Y-124932D01*
X168947Y-124972D01*
X168991Y-125019D01*
X169027Y-125074D01*
X169031Y-125081D01*
X169042Y-125099D01*
X169056Y-125132D01*
X169074Y-125172D01*
X169093Y-125219D01*
X169107Y-125274D01*
X169118Y-125336D01*
X169122Y-125398D01*
Y-125405D01*
Y-125427D01*
X169118Y-125456D01*
X169111Y-125496D01*
X169100Y-125543D01*
X169082Y-125594D01*
X169060Y-125645D01*
X169031Y-125696D01*
X169027Y-125703D01*
X169016Y-125718D01*
X168994Y-125743D01*
X168965Y-125773D01*
X168929Y-125805D01*
X168885Y-125842D01*
X168834Y-125874D01*
X168772Y-125907D01*
X168776D01*
X168783Y-125911D01*
X168794Y-125915D01*
X168809Y-125918D01*
X168849Y-125933D01*
X168900Y-125955D01*
X168958Y-125984D01*
X169016Y-126020D01*
X169071Y-126067D01*
X169122Y-126122D01*
X169125Y-126129D01*
X169140Y-126151D01*
X169162Y-126188D01*
X169184Y-126235D01*
X169205Y-126293D01*
X169227Y-126362D01*
X169242Y-126442D01*
X169246Y-126530D01*
Y-126533D01*
Y-126544D01*
Y-126562D01*
X169242Y-126584D01*
X169238Y-126613D01*
X169231Y-126646D01*
X169224Y-126683D01*
X169216Y-126723D01*
X169187Y-126810D01*
X169165Y-126857D01*
X169143Y-126901D01*
X169114Y-126948D01*
X169082Y-126996D01*
X169045Y-127043D01*
X169002Y-127087D01*
X168998Y-127090D01*
X168991Y-127097D01*
X168976Y-127108D01*
X168958Y-127123D01*
X168936Y-127141D01*
X168907Y-127159D01*
X168874Y-127181D01*
X168834Y-127199D01*
X168794Y-127221D01*
X168747Y-127243D01*
X168700Y-127261D01*
X168645Y-127279D01*
X168587Y-127294D01*
X168525Y-127305D01*
X168463Y-127312D01*
X168394Y-127316D01*
X168361D01*
X168339Y-127312D01*
X168310Y-127309D01*
X168277Y-127305D01*
X168241Y-127298D01*
X168201Y-127290D01*
X168113Y-127269D01*
X168022Y-127232D01*
X167975Y-127210D01*
X167931Y-127185D01*
X167888Y-127152D01*
X167844Y-127119D01*
X167840Y-127116D01*
X167833Y-127108D01*
X167822Y-127097D01*
X167811Y-127083D01*
X167793Y-127065D01*
X167775Y-127039D01*
X167753Y-127014D01*
X167731Y-126981D01*
X167709Y-126945D01*
X167687Y-126908D01*
X167648Y-126821D01*
X167615Y-126719D01*
X167604Y-126664D01*
X167596Y-126606D01*
X167906Y-126566D01*
Y-126570D01*
X167910Y-126577D01*
X167913Y-126592D01*
X167917Y-126610D01*
X167920Y-126632D01*
X167928Y-126657D01*
X167946Y-126712D01*
X167972Y-126777D01*
X168004Y-126839D01*
X168041Y-126897D01*
X168084Y-126948D01*
X168092Y-126952D01*
X168106Y-126967D01*
X168135Y-126985D01*
X168172Y-127003D01*
X168215Y-127025D01*
X168270Y-127043D01*
X168332Y-127058D01*
X168397Y-127061D01*
X168419D01*
X168434Y-127058D01*
X168474Y-127054D01*
X168525Y-127043D01*
X168583Y-127025D01*
X168645Y-126999D01*
X168707Y-126963D01*
X168765Y-126912D01*
X168772Y-126905D01*
X168790Y-126883D01*
X168812Y-126850D01*
X168841Y-126806D01*
X168870Y-126752D01*
X168892Y-126690D01*
X168911Y-126617D01*
X168918Y-126537D01*
Y-126533D01*
Y-126526D01*
Y-126515D01*
X168914Y-126501D01*
X168911Y-126461D01*
X168900Y-126413D01*
X168885Y-126355D01*
X168860Y-126297D01*
X168823Y-126239D01*
X168776Y-126184D01*
X168769Y-126177D01*
X168750Y-126162D01*
X168721Y-126140D01*
X168681Y-126115D01*
X168630Y-126089D01*
X168568Y-126067D01*
X168499Y-126053D01*
X168423Y-126046D01*
X168390D01*
X168365Y-126049D01*
X168332Y-126053D01*
X168295Y-126060D01*
X168252Y-126067D01*
X168204Y-126078D01*
X168241Y-125805D01*
X168259D01*
X168274Y-125809D01*
X168321D01*
X168361Y-125802D01*
X168408Y-125794D01*
X168463Y-125784D01*
X168525Y-125765D01*
X168583Y-125740D01*
X168645Y-125707D01*
X168649D01*
X168652Y-125703D01*
X168670Y-125689D01*
X168696Y-125663D01*
X168725Y-125631D01*
X168754Y-125583D01*
X168780Y-125529D01*
X168798Y-125467D01*
X168805Y-125430D01*
Y-125390D01*
Y-125387D01*
Y-125383D01*
Y-125361D01*
X168798Y-125332D01*
X168790Y-125292D01*
X168776Y-125248D01*
X168758Y-125201D01*
X168729Y-125154D01*
X168688Y-125110D01*
X168685Y-125106D01*
X168667Y-125092D01*
X168641Y-125074D01*
X168608Y-125052D01*
X168565Y-125034D01*
X168514Y-125015D01*
X168456Y-125001D01*
X168390Y-124997D01*
X168361D01*
X168328Y-125004D01*
X168284Y-125012D01*
X168237Y-125026D01*
X168190Y-125045D01*
X168139Y-125074D01*
X168092Y-125110D01*
X168088Y-125114D01*
X168073Y-125132D01*
X168052Y-125157D01*
X168026Y-125194D01*
X168001Y-125241D01*
X167975Y-125299D01*
X167953Y-125368D01*
X167939Y-125449D01*
X167629Y-125394D01*
Y-125390D01*
X167633Y-125379D01*
X167637Y-125365D01*
X167640Y-125343D01*
X167648Y-125318D01*
X167658Y-125288D01*
X167680Y-125219D01*
X167717Y-125139D01*
X167760Y-125059D01*
X167815Y-124983D01*
X167884Y-124914D01*
X167888Y-124910D01*
X167895Y-124906D01*
X167906Y-124899D01*
X167920Y-124888D01*
X167939Y-124873D01*
X167964Y-124859D01*
X167990Y-124844D01*
X168022Y-124826D01*
X168095Y-124797D01*
X168179Y-124768D01*
X168277Y-124750D01*
X168328Y-124742D01*
X168419D01*
X168459Y-124746D01*
D02*
G37*
G36*
X165205Y-126209D02*
Y-126213D01*
Y-126228D01*
Y-126246D01*
Y-126271D01*
X165201Y-126304D01*
Y-126340D01*
X165198Y-126384D01*
X165194Y-126428D01*
X165183Y-126526D01*
X165169Y-126628D01*
X165147Y-126726D01*
X165132Y-126774D01*
X165118Y-126817D01*
Y-126821D01*
X165114Y-126828D01*
X165107Y-126839D01*
X165100Y-126854D01*
X165078Y-126894D01*
X165045Y-126945D01*
X165001Y-127003D01*
X164950Y-127061D01*
X164885Y-127123D01*
X164805Y-127178D01*
X164801D01*
X164794Y-127185D01*
X164783Y-127189D01*
X164765Y-127199D01*
X164743Y-127210D01*
X164714Y-127221D01*
X164684Y-127232D01*
X164648Y-127247D01*
X164608Y-127261D01*
X164564Y-127272D01*
X164517Y-127283D01*
X164462Y-127294D01*
X164408Y-127301D01*
X164350Y-127309D01*
X164219Y-127316D01*
X164186D01*
X164160Y-127312D01*
X164131D01*
X164095Y-127309D01*
X164055Y-127305D01*
X164015Y-127301D01*
X163924Y-127287D01*
X163826Y-127265D01*
X163731Y-127236D01*
X163640Y-127196D01*
X163636D01*
X163629Y-127189D01*
X163618Y-127181D01*
X163603Y-127174D01*
X163563Y-127145D01*
X163516Y-127105D01*
X163461Y-127054D01*
X163410Y-126996D01*
X163360Y-126923D01*
X163320Y-126843D01*
Y-126839D01*
X163316Y-126832D01*
X163312Y-126817D01*
X163305Y-126799D01*
X163298Y-126777D01*
X163290Y-126748D01*
X163279Y-126715D01*
X163272Y-126675D01*
X163265Y-126632D01*
X163254Y-126584D01*
X163247Y-126533D01*
X163240Y-126479D01*
X163232Y-126417D01*
X163228Y-126351D01*
X163225Y-126282D01*
Y-126209D01*
Y-124753D01*
X163560D01*
Y-126209D01*
Y-126213D01*
Y-126224D01*
Y-126242D01*
Y-126264D01*
X163563Y-126289D01*
Y-126322D01*
X163567Y-126391D01*
X163574Y-126471D01*
X163585Y-126551D01*
X163600Y-126628D01*
X163607Y-126661D01*
X163618Y-126693D01*
X163622Y-126701D01*
X163629Y-126719D01*
X163647Y-126744D01*
X163669Y-126781D01*
X163695Y-126817D01*
X163731Y-126857D01*
X163775Y-126897D01*
X163826Y-126930D01*
X163833Y-126934D01*
X163851Y-126945D01*
X163884Y-126956D01*
X163927Y-126970D01*
X163978Y-126988D01*
X164044Y-126999D01*
X164113Y-127010D01*
X164190Y-127014D01*
X164226D01*
X164248Y-127010D01*
X164280D01*
X164313Y-127006D01*
X164393Y-126992D01*
X164481Y-126974D01*
X164564Y-126945D01*
X164645Y-126905D01*
X164681Y-126879D01*
X164714Y-126850D01*
X164717Y-126846D01*
X164721Y-126843D01*
X164728Y-126832D01*
X164739Y-126817D01*
X164750Y-126795D01*
X164765Y-126774D01*
X164779Y-126741D01*
X164794Y-126708D01*
X164808Y-126668D01*
X164819Y-126621D01*
X164834Y-126566D01*
X164845Y-126508D01*
X164856Y-126442D01*
X164863Y-126373D01*
X164870Y-126293D01*
Y-126209D01*
Y-124753D01*
X165205D01*
Y-126209D01*
D02*
G37*
G36*
X166799Y-127272D02*
X166490D01*
Y-125303D01*
X166486Y-125307D01*
X166468Y-125321D01*
X166446Y-125343D01*
X166410Y-125368D01*
X166370Y-125401D01*
X166319Y-125438D01*
X166261Y-125478D01*
X166195Y-125518D01*
X166191D01*
X166188Y-125521D01*
X166166Y-125536D01*
X166130Y-125554D01*
X166086Y-125576D01*
X166035Y-125601D01*
X165980Y-125627D01*
X165926Y-125652D01*
X165871Y-125674D01*
Y-125376D01*
X165875D01*
X165882Y-125368D01*
X165897Y-125365D01*
X165915Y-125354D01*
X165937Y-125343D01*
X165962Y-125329D01*
X166024Y-125292D01*
X166097Y-125252D01*
X166170Y-125201D01*
X166246Y-125143D01*
X166323Y-125081D01*
X166326Y-125077D01*
X166330Y-125074D01*
X166341Y-125063D01*
X166355Y-125052D01*
X166388Y-125015D01*
X166432Y-124972D01*
X166475Y-124921D01*
X166523Y-124863D01*
X166563Y-124804D01*
X166599Y-124742D01*
X166799D01*
Y-127272D01*
D02*
G37*
G36*
X453946Y-141913D02*
X453976Y-141916D01*
X454008Y-141924D01*
X454045Y-141931D01*
X454085Y-141938D01*
X454172Y-141967D01*
X454219Y-141989D01*
X454263Y-142011D01*
X454311Y-142040D01*
X454358Y-142073D01*
X454405Y-142109D01*
X454449Y-142153D01*
X454453Y-142157D01*
X454460Y-142164D01*
X454471Y-142178D01*
X454485Y-142197D01*
X454503Y-142218D01*
X454522Y-142247D01*
X454543Y-142280D01*
X454562Y-142320D01*
X454584Y-142360D01*
X454605Y-142408D01*
X454624Y-142455D01*
X454642Y-142510D01*
X454656Y-142568D01*
X454667Y-142630D01*
X454674Y-142692D01*
X454678Y-142761D01*
Y-142794D01*
X454674Y-142815D01*
X454671Y-142844D01*
X454667Y-142877D01*
X454660Y-142914D01*
X454653Y-142954D01*
X454631Y-143041D01*
X454594Y-143132D01*
X454573Y-143179D01*
X454547Y-143223D01*
X454514Y-143267D01*
X454482Y-143310D01*
X454478Y-143314D01*
X454471Y-143321D01*
X454460Y-143332D01*
X454445Y-143343D01*
X454427Y-143361D01*
X454401Y-143380D01*
X454376Y-143401D01*
X454343Y-143423D01*
X454307Y-143445D01*
X454270Y-143467D01*
X454183Y-143507D01*
X454081Y-143540D01*
X454027Y-143551D01*
X453968Y-143558D01*
X453928Y-143248D01*
X453932D01*
X453939Y-143245D01*
X453954Y-143241D01*
X453972Y-143238D01*
X453994Y-143234D01*
X454019Y-143227D01*
X454074Y-143209D01*
X454139Y-143183D01*
X454201Y-143150D01*
X454259Y-143114D01*
X454311Y-143070D01*
X454314Y-143063D01*
X454329Y-143048D01*
X454347Y-143019D01*
X454365Y-142983D01*
X454387Y-142939D01*
X454405Y-142885D01*
X454420Y-142823D01*
X454423Y-142757D01*
Y-142735D01*
X454420Y-142721D01*
X454416Y-142681D01*
X454405Y-142630D01*
X454387Y-142571D01*
X454361Y-142510D01*
X454325Y-142448D01*
X454274Y-142390D01*
X454267Y-142382D01*
X454245Y-142364D01*
X454212Y-142342D01*
X454169Y-142313D01*
X454114Y-142284D01*
X454052Y-142262D01*
X453979Y-142244D01*
X453899Y-142237D01*
X453896D01*
X453888D01*
X453877D01*
X453863Y-142240D01*
X453823Y-142244D01*
X453775Y-142255D01*
X453717Y-142269D01*
X453659Y-142295D01*
X453601Y-142331D01*
X453546Y-142379D01*
X453539Y-142386D01*
X453524Y-142404D01*
X453502Y-142433D01*
X453477Y-142473D01*
X453451Y-142524D01*
X453430Y-142586D01*
X453415Y-142655D01*
X453408Y-142732D01*
Y-142764D01*
X453411Y-142790D01*
X453415Y-142823D01*
X453422Y-142859D01*
X453430Y-142903D01*
X453441Y-142950D01*
X453167Y-142914D01*
Y-142895D01*
X453171Y-142881D01*
Y-142834D01*
X453164Y-142794D01*
X453157Y-142746D01*
X453146Y-142692D01*
X453127Y-142630D01*
X453102Y-142571D01*
X453069Y-142510D01*
Y-142506D01*
X453066Y-142502D01*
X453051Y-142484D01*
X453026Y-142459D01*
X452993Y-142429D01*
X452946Y-142400D01*
X452891Y-142375D01*
X452829Y-142357D01*
X452793Y-142350D01*
X452753D01*
X452749D01*
X452745D01*
X452723D01*
X452694Y-142357D01*
X452654Y-142364D01*
X452611Y-142379D01*
X452563Y-142397D01*
X452516Y-142426D01*
X452472Y-142466D01*
X452469Y-142470D01*
X452454Y-142488D01*
X452436Y-142513D01*
X452414Y-142546D01*
X452396Y-142590D01*
X452378Y-142641D01*
X452363Y-142699D01*
X452359Y-142764D01*
Y-142794D01*
X452367Y-142826D01*
X452374Y-142870D01*
X452389Y-142917D01*
X452407Y-142965D01*
X452436Y-143016D01*
X452472Y-143063D01*
X452476Y-143067D01*
X452494Y-143081D01*
X452520Y-143103D01*
X452556Y-143128D01*
X452603Y-143154D01*
X452662Y-143179D01*
X452731Y-143201D01*
X452811Y-143216D01*
X452756Y-143525D01*
X452753D01*
X452742Y-143521D01*
X452727Y-143518D01*
X452705Y-143514D01*
X452680Y-143507D01*
X452651Y-143496D01*
X452582Y-143474D01*
X452501Y-143438D01*
X452421Y-143394D01*
X452345Y-143340D01*
X452276Y-143270D01*
X452272Y-143267D01*
X452269Y-143260D01*
X452261Y-143248D01*
X452250Y-143234D01*
X452236Y-143216D01*
X452221Y-143190D01*
X452207Y-143165D01*
X452188Y-143132D01*
X452159Y-143059D01*
X452130Y-142975D01*
X452112Y-142877D01*
X452105Y-142826D01*
Y-142735D01*
X452108Y-142695D01*
X452116Y-142648D01*
X452127Y-142590D01*
X452145Y-142524D01*
X452167Y-142459D01*
X452196Y-142393D01*
Y-142390D01*
X452199Y-142386D01*
X452210Y-142364D01*
X452232Y-142331D01*
X452257Y-142295D01*
X452294Y-142251D01*
X452334Y-142208D01*
X452381Y-142164D01*
X452436Y-142127D01*
X452443Y-142124D01*
X452461Y-142113D01*
X452494Y-142098D01*
X452534Y-142080D01*
X452582Y-142062D01*
X452636Y-142047D01*
X452698Y-142036D01*
X452760Y-142033D01*
X452767D01*
X452789D01*
X452818Y-142036D01*
X452858Y-142044D01*
X452906Y-142055D01*
X452956Y-142073D01*
X453007Y-142095D01*
X453058Y-142124D01*
X453066Y-142127D01*
X453080Y-142138D01*
X453106Y-142160D01*
X453135Y-142189D01*
X453167Y-142226D01*
X453204Y-142269D01*
X453237Y-142320D01*
X453269Y-142382D01*
Y-142379D01*
X453273Y-142371D01*
X453277Y-142360D01*
X453280Y-142346D01*
X453295Y-142306D01*
X453317Y-142255D01*
X453346Y-142197D01*
X453382Y-142138D01*
X453430Y-142084D01*
X453484Y-142033D01*
X453491Y-142029D01*
X453513Y-142015D01*
X453550Y-141993D01*
X453597Y-141971D01*
X453655Y-141949D01*
X453724Y-141927D01*
X453804Y-141913D01*
X453892Y-141909D01*
X453896D01*
X453906D01*
X453925D01*
X453946Y-141913D01*
D02*
G37*
G36*
X452396Y-143871D02*
X452403Y-143878D01*
X452418Y-143893D01*
X452439Y-143907D01*
X452465Y-143929D01*
X452494Y-143958D01*
X452530Y-143988D01*
X452574Y-144020D01*
X452618Y-144053D01*
X452669Y-144093D01*
X452727Y-144133D01*
X452785Y-144173D01*
X452851Y-144217D01*
X452920Y-144261D01*
X452996Y-144304D01*
X453073Y-144348D01*
X453077Y-144351D01*
X453091Y-144359D01*
X453113Y-144370D01*
X453146Y-144388D01*
X453186Y-144406D01*
X453229Y-144428D01*
X453280Y-144453D01*
X453339Y-144479D01*
X453404Y-144508D01*
X453470Y-144541D01*
X453543Y-144570D01*
X453619Y-144599D01*
X453775Y-144657D01*
X453943Y-144712D01*
X453946D01*
X453957Y-144715D01*
X453976Y-144719D01*
X453998Y-144726D01*
X454027Y-144734D01*
X454063Y-144741D01*
X454103Y-144752D01*
X454147Y-144759D01*
X454198Y-144770D01*
X454252Y-144781D01*
X454369Y-144799D01*
X454496Y-144817D01*
X454635Y-144828D01*
Y-145145D01*
X454631D01*
X454620D01*
X454605D01*
X454584Y-145141D01*
X454554D01*
X454518Y-145138D01*
X454478Y-145134D01*
X454434Y-145130D01*
X454383Y-145123D01*
X454332Y-145116D01*
X454270Y-145105D01*
X454209Y-145094D01*
X454143Y-145083D01*
X454070Y-145069D01*
X453921Y-145032D01*
X453917D01*
X453903Y-145028D01*
X453881Y-145021D01*
X453848Y-145010D01*
X453812Y-144999D01*
X453768Y-144985D01*
X453717Y-144970D01*
X453663Y-144948D01*
X453601Y-144927D01*
X453539Y-144905D01*
X453401Y-144850D01*
X453255Y-144785D01*
X453109Y-144712D01*
X453106Y-144708D01*
X453091Y-144701D01*
X453073Y-144690D01*
X453044Y-144675D01*
X453011Y-144657D01*
X452971Y-144632D01*
X452927Y-144606D01*
X452880Y-144577D01*
X452774Y-144508D01*
X452665Y-144435D01*
X452552Y-144351D01*
X452447Y-144264D01*
Y-145498D01*
X452148D01*
Y-143867D01*
X452392D01*
X452396Y-143871D01*
D02*
G37*
G36*
X453856Y-145808D02*
X453877Y-145815D01*
X453906Y-145826D01*
X453939Y-145837D01*
X453979Y-145851D01*
X454023Y-145869D01*
X454070Y-145891D01*
X454172Y-145942D01*
X454274Y-146008D01*
X454325Y-146048D01*
X454376Y-146088D01*
X454420Y-146131D01*
X454463Y-146182D01*
X454467Y-146186D01*
X454474Y-146193D01*
X454482Y-146212D01*
X454496Y-146230D01*
X454514Y-146259D01*
X454532Y-146288D01*
X454551Y-146328D01*
X454569Y-146368D01*
X454591Y-146415D01*
X454609Y-146466D01*
X454627Y-146521D01*
X454645Y-146579D01*
X454660Y-146641D01*
X454667Y-146706D01*
X454674Y-146776D01*
X454678Y-146848D01*
Y-146888D01*
X454674Y-146918D01*
Y-146950D01*
X454671Y-146991D01*
X454664Y-147034D01*
X454656Y-147085D01*
X454638Y-147191D01*
X454609Y-147300D01*
X454569Y-147409D01*
X454543Y-147460D01*
X454514Y-147511D01*
X454511Y-147515D01*
X454507Y-147522D01*
X454496Y-147537D01*
X454482Y-147551D01*
X454467Y-147573D01*
X454445Y-147598D01*
X454420Y-147627D01*
X454391Y-147657D01*
X454358Y-147686D01*
X454325Y-147719D01*
X454241Y-147784D01*
X454143Y-147846D01*
X454034Y-147900D01*
X454030D01*
X454019Y-147908D01*
X454001Y-147911D01*
X453979Y-147922D01*
X453950Y-147930D01*
X453914Y-147941D01*
X453874Y-147955D01*
X453830Y-147966D01*
X453783Y-147977D01*
X453728Y-147992D01*
X453615Y-148010D01*
X453488Y-148024D01*
X453357Y-148031D01*
X453353D01*
X453339D01*
X453317D01*
X453291Y-148028D01*
X453255D01*
X453219Y-148024D01*
X453171Y-148021D01*
X453124Y-148013D01*
X453018Y-147995D01*
X452902Y-147970D01*
X452785Y-147933D01*
X452672Y-147882D01*
X452669Y-147879D01*
X452658Y-147875D01*
X452643Y-147868D01*
X452625Y-147853D01*
X452600Y-147839D01*
X452571Y-147820D01*
X452505Y-147773D01*
X452432Y-147711D01*
X452359Y-147638D01*
X452287Y-147555D01*
X452225Y-147456D01*
X452221Y-147453D01*
X452217Y-147442D01*
X452210Y-147427D01*
X452199Y-147409D01*
X452188Y-147380D01*
X452177Y-147351D01*
X452163Y-147314D01*
X452148Y-147274D01*
X452134Y-147231D01*
X452119Y-147183D01*
X452097Y-147081D01*
X452079Y-146965D01*
X452072Y-146845D01*
Y-146809D01*
X452075Y-146783D01*
X452079Y-146750D01*
X452083Y-146710D01*
X452086Y-146670D01*
X452097Y-146623D01*
X452119Y-146525D01*
X452152Y-146415D01*
X452174Y-146361D01*
X452199Y-146310D01*
X452232Y-146259D01*
X452265Y-146208D01*
X452269Y-146204D01*
X452272Y-146197D01*
X452283Y-146182D01*
X452301Y-146164D01*
X452319Y-146146D01*
X452345Y-146121D01*
X452374Y-146095D01*
X452403Y-146066D01*
X452439Y-146037D01*
X452483Y-146008D01*
X452527Y-145975D01*
X452574Y-145946D01*
X452629Y-145920D01*
X452683Y-145891D01*
X452742Y-145869D01*
X452807Y-145847D01*
X452884Y-146175D01*
X452880D01*
X452873Y-146179D01*
X452858Y-146186D01*
X452840Y-146193D01*
X452818Y-146201D01*
X452789Y-146212D01*
X452731Y-146241D01*
X452665Y-146277D01*
X452600Y-146321D01*
X452538Y-146375D01*
X452483Y-146433D01*
X452476Y-146441D01*
X452461Y-146463D01*
X452443Y-146499D01*
X452418Y-146546D01*
X452396Y-146608D01*
X452374Y-146677D01*
X452359Y-146761D01*
X452356Y-146852D01*
Y-146881D01*
X452359Y-146899D01*
Y-146925D01*
X452363Y-146954D01*
X452374Y-147023D01*
X452389Y-147100D01*
X452414Y-147180D01*
X452451Y-147264D01*
X452498Y-147340D01*
Y-147344D01*
X452505Y-147347D01*
X452523Y-147373D01*
X452552Y-147405D01*
X452596Y-147445D01*
X452651Y-147493D01*
X452712Y-147537D01*
X452789Y-147576D01*
X452873Y-147613D01*
X452876D01*
X452884Y-147617D01*
X452894Y-147620D01*
X452913Y-147624D01*
X452935Y-147631D01*
X452960Y-147638D01*
X453022Y-147649D01*
X453095Y-147664D01*
X453175Y-147678D01*
X453262Y-147686D01*
X453357Y-147689D01*
X453361D01*
X453371D01*
X453390D01*
X453411D01*
X453437Y-147686D01*
X453470D01*
X453506Y-147682D01*
X453546Y-147678D01*
X453633Y-147668D01*
X453728Y-147649D01*
X453823Y-147627D01*
X453917Y-147598D01*
X453921D01*
X453928Y-147595D01*
X453939Y-147587D01*
X453957Y-147580D01*
X454001Y-147558D01*
X454052Y-147526D01*
X454110Y-147485D01*
X454172Y-147434D01*
X454227Y-147376D01*
X454278Y-147307D01*
Y-147303D01*
X454281Y-147296D01*
X454289Y-147285D01*
X454296Y-147271D01*
X454303Y-147253D01*
X454314Y-147231D01*
X454336Y-147180D01*
X454358Y-147114D01*
X454376Y-147041D01*
X454391Y-146961D01*
X454394Y-146878D01*
Y-146852D01*
X454391Y-146830D01*
Y-146805D01*
X454387Y-146779D01*
X454372Y-146714D01*
X454354Y-146637D01*
X454325Y-146561D01*
X454285Y-146481D01*
X454263Y-146441D01*
X454234Y-146404D01*
X454230Y-146401D01*
X454227Y-146397D01*
X454216Y-146386D01*
X454205Y-146372D01*
X454187Y-146357D01*
X454165Y-146339D01*
X454143Y-146317D01*
X454114Y-146299D01*
X454081Y-146277D01*
X454045Y-146251D01*
X454008Y-146230D01*
X453965Y-146208D01*
X453917Y-146190D01*
X453866Y-146171D01*
X453812Y-146153D01*
X453754Y-146139D01*
X453837Y-145804D01*
X453841D01*
X453856Y-145808D01*
D02*
G37*
G36*
X458126Y-101972D02*
X458162D01*
X458199Y-101976D01*
X458246Y-101979D01*
X458293Y-101987D01*
X458399Y-102005D01*
X458516Y-102030D01*
X458632Y-102067D01*
X458745Y-102118D01*
X458748Y-102121D01*
X458759Y-102125D01*
X458774Y-102132D01*
X458792Y-102147D01*
X458818Y-102161D01*
X458847Y-102180D01*
X458912Y-102227D01*
X458985Y-102289D01*
X459058Y-102362D01*
X459131Y-102445D01*
X459193Y-102544D01*
X459196Y-102547D01*
X459200Y-102558D01*
X459207Y-102573D01*
X459218Y-102591D01*
X459229Y-102620D01*
X459240Y-102649D01*
X459254Y-102686D01*
X459269Y-102726D01*
X459284Y-102769D01*
X459298Y-102817D01*
X459320Y-102919D01*
X459338Y-103035D01*
X459345Y-103155D01*
Y-103191D01*
X459342Y-103217D01*
X459338Y-103250D01*
X459335Y-103290D01*
X459331Y-103330D01*
X459320Y-103377D01*
X459298Y-103475D01*
X459265Y-103585D01*
X459243Y-103639D01*
X459218Y-103690D01*
X459185Y-103741D01*
X459153Y-103792D01*
X459149Y-103796D01*
X459145Y-103803D01*
X459134Y-103818D01*
X459116Y-103836D01*
X459098Y-103854D01*
X459072Y-103879D01*
X459043Y-103905D01*
X459014Y-103934D01*
X458978Y-103963D01*
X458934Y-103992D01*
X458890Y-104025D01*
X458843Y-104054D01*
X458788Y-104080D01*
X458734Y-104109D01*
X458676Y-104131D01*
X458610Y-104153D01*
X458534Y-103825D01*
X458537D01*
X458545Y-103821D01*
X458559Y-103814D01*
X458577Y-103807D01*
X458599Y-103799D01*
X458628Y-103788D01*
X458687Y-103759D01*
X458752Y-103723D01*
X458818Y-103679D01*
X458880Y-103625D01*
X458934Y-103567D01*
X458941Y-103559D01*
X458956Y-103537D01*
X458974Y-103501D01*
X459000Y-103454D01*
X459022Y-103392D01*
X459043Y-103323D01*
X459058Y-103239D01*
X459061Y-103148D01*
Y-103119D01*
X459058Y-103101D01*
Y-103075D01*
X459054Y-103046D01*
X459043Y-102977D01*
X459029Y-102900D01*
X459003Y-102820D01*
X458967Y-102736D01*
X458919Y-102660D01*
Y-102656D01*
X458912Y-102653D01*
X458894Y-102627D01*
X458865Y-102595D01*
X458821Y-102555D01*
X458767Y-102507D01*
X458705Y-102463D01*
X458628Y-102424D01*
X458545Y-102387D01*
X458541D01*
X458534Y-102383D01*
X458523Y-102380D01*
X458505Y-102376D01*
X458483Y-102369D01*
X458457Y-102362D01*
X458395Y-102351D01*
X458323Y-102336D01*
X458243Y-102322D01*
X458155Y-102314D01*
X458061Y-102311D01*
X458057D01*
X458046D01*
X458028D01*
X458006D01*
X457980Y-102314D01*
X457948D01*
X457911Y-102318D01*
X457871Y-102322D01*
X457784Y-102332D01*
X457689Y-102351D01*
X457595Y-102373D01*
X457500Y-102402D01*
X457496D01*
X457489Y-102405D01*
X457478Y-102413D01*
X457460Y-102420D01*
X457416Y-102442D01*
X457365Y-102474D01*
X457307Y-102515D01*
X457245Y-102566D01*
X457191Y-102624D01*
X457140Y-102693D01*
Y-102697D01*
X457136Y-102704D01*
X457129Y-102715D01*
X457121Y-102729D01*
X457114Y-102747D01*
X457103Y-102769D01*
X457081Y-102820D01*
X457059Y-102886D01*
X457041Y-102959D01*
X457027Y-103039D01*
X457023Y-103122D01*
Y-103148D01*
X457027Y-103170D01*
Y-103195D01*
X457030Y-103221D01*
X457045Y-103286D01*
X457063Y-103363D01*
X457092Y-103439D01*
X457132Y-103519D01*
X457154Y-103559D01*
X457183Y-103596D01*
X457187Y-103599D01*
X457191Y-103603D01*
X457201Y-103614D01*
X457212Y-103628D01*
X457231Y-103643D01*
X457252Y-103661D01*
X457274Y-103683D01*
X457303Y-103701D01*
X457336Y-103723D01*
X457373Y-103749D01*
X457409Y-103770D01*
X457453Y-103792D01*
X457500Y-103810D01*
X457551Y-103829D01*
X457606Y-103847D01*
X457664Y-103861D01*
X457580Y-104196D01*
X457576D01*
X457562Y-104192D01*
X457540Y-104185D01*
X457511Y-104174D01*
X457478Y-104163D01*
X457438Y-104149D01*
X457394Y-104131D01*
X457347Y-104109D01*
X457245Y-104058D01*
X457143Y-103992D01*
X457092Y-103952D01*
X457041Y-103912D01*
X456998Y-103869D01*
X456954Y-103818D01*
X456950Y-103814D01*
X456943Y-103807D01*
X456936Y-103788D01*
X456921Y-103770D01*
X456903Y-103741D01*
X456885Y-103712D01*
X456867Y-103672D01*
X456848Y-103632D01*
X456827Y-103585D01*
X456808Y-103534D01*
X456790Y-103479D01*
X456772Y-103421D01*
X456757Y-103359D01*
X456750Y-103294D01*
X456743Y-103224D01*
X456739Y-103152D01*
Y-103112D01*
X456743Y-103082D01*
Y-103050D01*
X456746Y-103009D01*
X456754Y-102966D01*
X456761Y-102915D01*
X456779Y-102809D01*
X456808Y-102700D01*
X456848Y-102591D01*
X456874Y-102540D01*
X456903Y-102489D01*
X456907Y-102485D01*
X456910Y-102478D01*
X456921Y-102463D01*
X456936Y-102449D01*
X456950Y-102427D01*
X456972Y-102402D01*
X456998Y-102373D01*
X457027Y-102343D01*
X457059Y-102314D01*
X457092Y-102281D01*
X457176Y-102216D01*
X457274Y-102154D01*
X457383Y-102100D01*
X457387D01*
X457398Y-102092D01*
X457416Y-102089D01*
X457438Y-102078D01*
X457467Y-102070D01*
X457504Y-102059D01*
X457544Y-102045D01*
X457587Y-102034D01*
X457635Y-102023D01*
X457689Y-102008D01*
X457802Y-101990D01*
X457930Y-101976D01*
X458061Y-101969D01*
X458064D01*
X458079D01*
X458101D01*
X458126Y-101972D01*
D02*
G37*
G36*
X459269Y-106133D02*
X459025D01*
X459022Y-106129D01*
X459014Y-106122D01*
X459000Y-106107D01*
X458978Y-106093D01*
X458952Y-106071D01*
X458923Y-106042D01*
X458887Y-106012D01*
X458843Y-105980D01*
X458799Y-105947D01*
X458748Y-105907D01*
X458690Y-105867D01*
X458632Y-105827D01*
X458567Y-105783D01*
X458497Y-105739D01*
X458421Y-105696D01*
X458344Y-105652D01*
X458341Y-105649D01*
X458326Y-105641D01*
X458304Y-105630D01*
X458272Y-105612D01*
X458232Y-105594D01*
X458188Y-105572D01*
X458137Y-105547D01*
X458079Y-105521D01*
X458013Y-105492D01*
X457948Y-105459D01*
X457875Y-105430D01*
X457798Y-105401D01*
X457642Y-105343D01*
X457475Y-105288D01*
X457471D01*
X457460Y-105285D01*
X457442Y-105281D01*
X457420Y-105274D01*
X457391Y-105266D01*
X457354Y-105259D01*
X457314Y-105248D01*
X457271Y-105241D01*
X457220Y-105230D01*
X457165Y-105219D01*
X457049Y-105201D01*
X456921Y-105183D01*
X456783Y-105172D01*
Y-104855D01*
X456786D01*
X456797D01*
X456812D01*
X456834Y-104859D01*
X456863D01*
X456899Y-104862D01*
X456939Y-104866D01*
X456983Y-104870D01*
X457034Y-104877D01*
X457085Y-104884D01*
X457147Y-104895D01*
X457209Y-104906D01*
X457274Y-104917D01*
X457347Y-104931D01*
X457496Y-104968D01*
X457500D01*
X457514Y-104972D01*
X457536Y-104979D01*
X457569Y-104990D01*
X457606Y-105001D01*
X457649Y-105015D01*
X457700Y-105030D01*
X457755Y-105052D01*
X457817Y-105073D01*
X457878Y-105095D01*
X458017Y-105150D01*
X458162Y-105215D01*
X458308Y-105288D01*
X458312Y-105292D01*
X458326Y-105299D01*
X458344Y-105310D01*
X458373Y-105325D01*
X458406Y-105343D01*
X458446Y-105368D01*
X458490Y-105394D01*
X458537Y-105423D01*
X458643Y-105492D01*
X458752Y-105565D01*
X458865Y-105649D01*
X458970Y-105736D01*
Y-104502D01*
X459269D01*
Y-106133D01*
D02*
G37*
G36*
X457467Y-106762D02*
X457464D01*
X457456D01*
X457445Y-106766D01*
X457427Y-106770D01*
X457387Y-106781D01*
X457333Y-106795D01*
X457278Y-106817D01*
X457216Y-106846D01*
X457161Y-106883D01*
X457111Y-106926D01*
X457107Y-106933D01*
X457092Y-106948D01*
X457074Y-106977D01*
X457052Y-107017D01*
X457030Y-107061D01*
X457012Y-107115D01*
X456998Y-107177D01*
X456994Y-107246D01*
Y-107268D01*
X456998Y-107283D01*
X457001Y-107327D01*
X457016Y-107378D01*
X457034Y-107439D01*
X457063Y-107501D01*
X457107Y-107567D01*
X457132Y-107596D01*
X457161Y-107625D01*
X457165Y-107629D01*
X457169Y-107632D01*
X457180Y-107640D01*
X457191Y-107650D01*
X457231Y-107676D01*
X457281Y-107705D01*
X457343Y-107731D01*
X457420Y-107756D01*
X457511Y-107774D01*
X457558Y-107782D01*
X457609D01*
X457613D01*
X457620D01*
X457635D01*
X457653Y-107778D01*
X457675D01*
X457700Y-107774D01*
X457758Y-107763D01*
X457828Y-107745D01*
X457897Y-107720D01*
X457962Y-107683D01*
X458024Y-107632D01*
X458028D01*
X458031Y-107625D01*
X458050Y-107607D01*
X458075Y-107574D01*
X458104Y-107530D01*
X458130Y-107472D01*
X458155Y-107407D01*
X458173Y-107330D01*
X458181Y-107287D01*
Y-107217D01*
X458177Y-107188D01*
X458173Y-107152D01*
X458162Y-107108D01*
X458151Y-107064D01*
X458133Y-107017D01*
X458111Y-106970D01*
X458108Y-106966D01*
X458101Y-106952D01*
X458082Y-106930D01*
X458064Y-106901D01*
X458039Y-106872D01*
X458006Y-106843D01*
X457973Y-106810D01*
X457933Y-106784D01*
X457973Y-106493D01*
X459269Y-106737D01*
Y-107989D01*
X458974D01*
Y-106981D01*
X458293Y-106846D01*
X458297Y-106850D01*
X458301Y-106857D01*
X458308Y-106868D01*
X458319Y-106886D01*
X458330Y-106908D01*
X458344Y-106933D01*
X458373Y-106992D01*
X458403Y-107064D01*
X458428Y-107145D01*
X458446Y-107232D01*
X458454Y-107276D01*
Y-107356D01*
X458450Y-107378D01*
X458446Y-107407D01*
X458443Y-107439D01*
X458435Y-107476D01*
X458425Y-107516D01*
X458399Y-107603D01*
X458381Y-107650D01*
X458355Y-107698D01*
X458330Y-107745D01*
X458301Y-107792D01*
X458264Y-107836D01*
X458224Y-107880D01*
X458221Y-107884D01*
X458213Y-107891D01*
X458203Y-107902D01*
X458184Y-107916D01*
X458159Y-107934D01*
X458133Y-107953D01*
X458101Y-107975D01*
X458064Y-107996D01*
X458024Y-108015D01*
X457980Y-108036D01*
X457930Y-108055D01*
X457878Y-108073D01*
X457824Y-108087D01*
X457762Y-108098D01*
X457700Y-108106D01*
X457635Y-108109D01*
X457631D01*
X457620D01*
X457602D01*
X457576Y-108106D01*
X457547Y-108102D01*
X457514Y-108098D01*
X457475Y-108091D01*
X457434Y-108084D01*
X457340Y-108062D01*
X457241Y-108026D01*
X457191Y-108004D01*
X457143Y-107975D01*
X457092Y-107945D01*
X457045Y-107909D01*
X457041Y-107905D01*
X457030Y-107898D01*
X457016Y-107884D01*
X456998Y-107865D01*
X456976Y-107840D01*
X456947Y-107811D01*
X456921Y-107774D01*
X456892Y-107734D01*
X456863Y-107691D01*
X456838Y-107640D01*
X456812Y-107585D01*
X456786Y-107527D01*
X456768Y-107465D01*
X456754Y-107396D01*
X456743Y-107323D01*
X456739Y-107246D01*
Y-107214D01*
X456743Y-107188D01*
X456746Y-107159D01*
X456750Y-107126D01*
X456754Y-107086D01*
X456765Y-107046D01*
X456786Y-106955D01*
X456819Y-106864D01*
X456841Y-106817D01*
X456867Y-106770D01*
X456896Y-106726D01*
X456928Y-106682D01*
X456932Y-106679D01*
X456936Y-106671D01*
X456950Y-106664D01*
X456965Y-106649D01*
X456983Y-106631D01*
X457005Y-106613D01*
X457034Y-106591D01*
X457067Y-106573D01*
X457099Y-106551D01*
X457140Y-106529D01*
X457227Y-106489D01*
X457329Y-106457D01*
X457383Y-106446D01*
X457442Y-106438D01*
X457467Y-106762D01*
D02*
G37*
G36*
X353753Y-119886D02*
X353785D01*
X353825Y-119889D01*
X353869Y-119896D01*
X353920Y-119904D01*
X354026Y-119922D01*
X354135Y-119951D01*
X354244Y-119991D01*
X354295Y-120017D01*
X354346Y-120046D01*
X354350Y-120049D01*
X354357Y-120053D01*
X354371Y-120064D01*
X354386Y-120078D01*
X354408Y-120093D01*
X354433Y-120115D01*
X354462Y-120140D01*
X354491Y-120169D01*
X354521Y-120202D01*
X354553Y-120235D01*
X354619Y-120319D01*
X354681Y-120417D01*
X354735Y-120526D01*
Y-120530D01*
X354743Y-120541D01*
X354746Y-120559D01*
X354757Y-120581D01*
X354765Y-120610D01*
X354776Y-120646D01*
X354790Y-120686D01*
X354801Y-120730D01*
X354812Y-120777D01*
X354826Y-120832D01*
X354845Y-120945D01*
X354859Y-121072D01*
X354867Y-121203D01*
Y-121207D01*
Y-121221D01*
Y-121243D01*
X354863Y-121269D01*
Y-121305D01*
X354859Y-121342D01*
X354855Y-121389D01*
X354848Y-121436D01*
X354830Y-121542D01*
X354805Y-121658D01*
X354768Y-121775D01*
X354717Y-121888D01*
X354714Y-121891D01*
X354710Y-121902D01*
X354703Y-121917D01*
X354688Y-121935D01*
X354674Y-121960D01*
X354655Y-121989D01*
X354608Y-122055D01*
X354546Y-122128D01*
X354473Y-122201D01*
X354390Y-122273D01*
X354291Y-122335D01*
X354288Y-122339D01*
X354277Y-122343D01*
X354262Y-122350D01*
X354244Y-122361D01*
X354215Y-122372D01*
X354186Y-122382D01*
X354149Y-122397D01*
X354109Y-122412D01*
X354066Y-122426D01*
X354018Y-122441D01*
X353916Y-122463D01*
X353800Y-122481D01*
X353680Y-122488D01*
X353643D01*
X353618Y-122484D01*
X353585Y-122481D01*
X353545Y-122477D01*
X353505Y-122474D01*
X353458Y-122463D01*
X353360Y-122441D01*
X353250Y-122408D01*
X353196Y-122386D01*
X353145Y-122361D01*
X353094Y-122328D01*
X353043Y-122295D01*
X353039Y-122292D01*
X353032Y-122288D01*
X353017Y-122277D01*
X352999Y-122259D01*
X352981Y-122241D01*
X352956Y-122215D01*
X352930Y-122186D01*
X352901Y-122157D01*
X352872Y-122120D01*
X352843Y-122077D01*
X352810Y-122033D01*
X352781Y-121986D01*
X352755Y-121931D01*
X352726Y-121877D01*
X352704Y-121818D01*
X352682Y-121753D01*
X353010Y-121676D01*
Y-121680D01*
X353014Y-121687D01*
X353021Y-121702D01*
X353028Y-121720D01*
X353035Y-121742D01*
X353046Y-121771D01*
X353076Y-121829D01*
X353112Y-121895D01*
X353156Y-121960D01*
X353210Y-122022D01*
X353269Y-122077D01*
X353276Y-122084D01*
X353298Y-122099D01*
X353334Y-122117D01*
X353381Y-122142D01*
X353443Y-122164D01*
X353512Y-122186D01*
X353596Y-122201D01*
X353687Y-122204D01*
X353716D01*
X353734Y-122201D01*
X353760D01*
X353789Y-122197D01*
X353858Y-122186D01*
X353935Y-122171D01*
X354015Y-122146D01*
X354098Y-122109D01*
X354175Y-122062D01*
X354179D01*
X354182Y-122055D01*
X354208Y-122037D01*
X354240Y-122008D01*
X354280Y-121964D01*
X354328Y-121909D01*
X354371Y-121847D01*
X354412Y-121771D01*
X354448Y-121687D01*
Y-121684D01*
X354451Y-121676D01*
X354455Y-121665D01*
X354459Y-121647D01*
X354466Y-121625D01*
X354473Y-121600D01*
X354484Y-121538D01*
X354499Y-121465D01*
X354513Y-121385D01*
X354521Y-121298D01*
X354524Y-121203D01*
Y-121200D01*
Y-121189D01*
Y-121170D01*
Y-121149D01*
X354521Y-121123D01*
Y-121090D01*
X354517Y-121054D01*
X354513Y-121014D01*
X354503Y-120926D01*
X354484Y-120832D01*
X354462Y-120737D01*
X354433Y-120643D01*
Y-120639D01*
X354430Y-120632D01*
X354422Y-120621D01*
X354415Y-120603D01*
X354393Y-120559D01*
X354361Y-120508D01*
X354321Y-120450D01*
X354270Y-120388D01*
X354211Y-120333D01*
X354142Y-120282D01*
X354138D01*
X354131Y-120279D01*
X354120Y-120271D01*
X354106Y-120264D01*
X354087Y-120257D01*
X354066Y-120246D01*
X354015Y-120224D01*
X353949Y-120202D01*
X353876Y-120184D01*
X353796Y-120169D01*
X353713Y-120166D01*
X353687D01*
X353665Y-120169D01*
X353640D01*
X353614Y-120173D01*
X353549Y-120188D01*
X353472Y-120206D01*
X353396Y-120235D01*
X353316Y-120275D01*
X353276Y-120297D01*
X353239Y-120326D01*
X353236Y-120330D01*
X353232Y-120333D01*
X353221Y-120344D01*
X353207Y-120355D01*
X353192Y-120373D01*
X353174Y-120395D01*
X353152Y-120417D01*
X353134Y-120446D01*
X353112Y-120479D01*
X353086Y-120515D01*
X353065Y-120552D01*
X353043Y-120595D01*
X353025Y-120643D01*
X353006Y-120694D01*
X352988Y-120748D01*
X352974Y-120806D01*
X352639Y-120723D01*
Y-120719D01*
X352642Y-120704D01*
X352650Y-120683D01*
X352661Y-120653D01*
X352672Y-120621D01*
X352686Y-120581D01*
X352704Y-120537D01*
X352726Y-120490D01*
X352777Y-120388D01*
X352843Y-120286D01*
X352883Y-120235D01*
X352923Y-120184D01*
X352966Y-120140D01*
X353017Y-120097D01*
X353021Y-120093D01*
X353028Y-120086D01*
X353046Y-120078D01*
X353065Y-120064D01*
X353094Y-120046D01*
X353123Y-120027D01*
X353163Y-120009D01*
X353203Y-119991D01*
X353250Y-119969D01*
X353301Y-119951D01*
X353356Y-119933D01*
X353414Y-119915D01*
X353476Y-119900D01*
X353541Y-119893D01*
X353611Y-119886D01*
X353683Y-119882D01*
X353724D01*
X353753Y-119886D01*
D02*
G37*
G36*
X351590D02*
X351623Y-119889D01*
X351660Y-119893D01*
X351700Y-119900D01*
X351743Y-119911D01*
X351842Y-119936D01*
X351893Y-119955D01*
X351940Y-119973D01*
X351991Y-119998D01*
X352042Y-120027D01*
X352089Y-120060D01*
X352133Y-120100D01*
X352136Y-120104D01*
X352144Y-120111D01*
X352155Y-120122D01*
X352169Y-120140D01*
X352184Y-120162D01*
X352206Y-120188D01*
X352224Y-120217D01*
X352246Y-120253D01*
X352268Y-120290D01*
X352286Y-120333D01*
X352322Y-120424D01*
X352337Y-120479D01*
X352348Y-120533D01*
X352355Y-120592D01*
X352359Y-120650D01*
Y-120653D01*
Y-120661D01*
Y-120675D01*
X352355Y-120690D01*
Y-120712D01*
X352351Y-120737D01*
X352344Y-120796D01*
X352329Y-120861D01*
X352308Y-120926D01*
X352275Y-120996D01*
X352235Y-121061D01*
Y-121065D01*
X352227Y-121069D01*
X352213Y-121087D01*
X352184Y-121116D01*
X352144Y-121152D01*
X352093Y-121189D01*
X352031Y-121229D01*
X351962Y-121261D01*
X351878Y-121287D01*
X351882D01*
X351885Y-121291D01*
X351896Y-121294D01*
X351911Y-121301D01*
X351943Y-121316D01*
X351987Y-121338D01*
X352034Y-121367D01*
X352082Y-121403D01*
X352126Y-121443D01*
X352166Y-121487D01*
X352169Y-121494D01*
X352180Y-121509D01*
X352195Y-121538D01*
X352209Y-121574D01*
X352227Y-121622D01*
X352242Y-121676D01*
X352253Y-121738D01*
X352257Y-121804D01*
Y-121807D01*
Y-121815D01*
Y-121829D01*
X352253Y-121851D01*
X352249Y-121873D01*
X352246Y-121902D01*
X352231Y-121964D01*
X352209Y-122037D01*
X352173Y-122113D01*
X352151Y-122153D01*
X352126Y-122193D01*
X352093Y-122230D01*
X352060Y-122266D01*
X352056Y-122270D01*
X352049Y-122273D01*
X352038Y-122284D01*
X352024Y-122295D01*
X352005Y-122310D01*
X351980Y-122324D01*
X351951Y-122343D01*
X351922Y-122361D01*
X351885Y-122379D01*
X351845Y-122397D01*
X351802Y-122412D01*
X351754Y-122426D01*
X351652Y-122448D01*
X351594Y-122452D01*
X351536Y-122455D01*
X351503D01*
X351481Y-122452D01*
X351452Y-122448D01*
X351419Y-122444D01*
X351383Y-122441D01*
X351347Y-122430D01*
X351259Y-122408D01*
X351172Y-122375D01*
X351128Y-122353D01*
X351084Y-122328D01*
X351045Y-122295D01*
X351004Y-122262D01*
X351001Y-122259D01*
X350997Y-122255D01*
X350986Y-122244D01*
X350972Y-122230D01*
X350957Y-122208D01*
X350939Y-122186D01*
X350903Y-122131D01*
X350866Y-122062D01*
X350833Y-121982D01*
X350808Y-121891D01*
X350804Y-121844D01*
X350801Y-121793D01*
Y-121789D01*
Y-121786D01*
Y-121764D01*
X350804Y-121731D01*
X350812Y-121691D01*
X350822Y-121640D01*
X350841Y-121589D01*
X350863Y-121538D01*
X350895Y-121487D01*
X350899Y-121480D01*
X350913Y-121465D01*
X350935Y-121443D01*
X350964Y-121414D01*
X351004Y-121381D01*
X351052Y-121349D01*
X351106Y-121316D01*
X351172Y-121287D01*
X351168D01*
X351161Y-121283D01*
X351150Y-121280D01*
X351135Y-121272D01*
X351092Y-121254D01*
X351041Y-121229D01*
X350986Y-121192D01*
X350928Y-121152D01*
X350873Y-121101D01*
X350822Y-121043D01*
Y-121039D01*
X350819Y-121036D01*
X350804Y-121014D01*
X350782Y-120977D01*
X350761Y-120930D01*
X350739Y-120872D01*
X350717Y-120803D01*
X350702Y-120726D01*
X350699Y-120643D01*
Y-120639D01*
Y-120628D01*
Y-120610D01*
X350702Y-120588D01*
X350706Y-120563D01*
X350710Y-120530D01*
X350717Y-120493D01*
X350728Y-120453D01*
X350753Y-120370D01*
X350771Y-120322D01*
X350797Y-120279D01*
X350822Y-120231D01*
X350851Y-120188D01*
X350888Y-120144D01*
X350928Y-120100D01*
X350932Y-120097D01*
X350939Y-120089D01*
X350950Y-120078D01*
X350968Y-120068D01*
X350993Y-120049D01*
X351019Y-120031D01*
X351052Y-120013D01*
X351088Y-119991D01*
X351128Y-119969D01*
X351175Y-119951D01*
X351226Y-119933D01*
X351277Y-119915D01*
X351336Y-119904D01*
X351397Y-119893D01*
X351459Y-119886D01*
X351529Y-119882D01*
X351565D01*
X351590Y-119886D01*
D02*
G37*
G36*
X350440Y-119929D02*
Y-119944D01*
Y-119966D01*
X350437Y-119995D01*
X350433Y-120027D01*
X350426Y-120064D01*
X350418Y-120100D01*
X350404Y-120140D01*
Y-120144D01*
X350400Y-120148D01*
X350393Y-120169D01*
X350378Y-120202D01*
X350357Y-120246D01*
X350327Y-120297D01*
X350291Y-120355D01*
X350251Y-120413D01*
X350200Y-120475D01*
Y-120479D01*
X350193Y-120482D01*
X350174Y-120504D01*
X350142Y-120537D01*
X350094Y-120584D01*
X350040Y-120639D01*
X349971Y-120704D01*
X349887Y-120777D01*
X349796Y-120854D01*
X349792Y-120857D01*
X349778Y-120868D01*
X349756Y-120887D01*
X349730Y-120908D01*
X349698Y-120937D01*
X349658Y-120970D01*
X349618Y-121007D01*
X349570Y-121047D01*
X349479Y-121134D01*
X349388Y-121221D01*
X349345Y-121265D01*
X349305Y-121309D01*
X349268Y-121349D01*
X349239Y-121389D01*
Y-121392D01*
X349232Y-121396D01*
X349224Y-121407D01*
X349217Y-121422D01*
X349192Y-121462D01*
X349163Y-121509D01*
X349137Y-121567D01*
X349112Y-121629D01*
X349097Y-121698D01*
X349090Y-121764D01*
Y-121767D01*
Y-121771D01*
X349093Y-121793D01*
X349097Y-121829D01*
X349108Y-121869D01*
X349123Y-121920D01*
X349148Y-121971D01*
X349181Y-122022D01*
X349224Y-122073D01*
X349232Y-122080D01*
X349250Y-122095D01*
X349275Y-122113D01*
X349316Y-122139D01*
X349366Y-122160D01*
X349425Y-122182D01*
X349494Y-122197D01*
X349570Y-122201D01*
X349592D01*
X349607Y-122197D01*
X349650Y-122193D01*
X349701Y-122182D01*
X349756Y-122168D01*
X349818Y-122142D01*
X349876Y-122109D01*
X349931Y-122066D01*
X349938Y-122059D01*
X349953Y-122040D01*
X349974Y-122011D01*
X349996Y-121968D01*
X350022Y-121917D01*
X350044Y-121851D01*
X350058Y-121778D01*
X350065Y-121695D01*
X350382Y-121727D01*
Y-121731D01*
X350378Y-121742D01*
Y-121760D01*
X350375Y-121786D01*
X350367Y-121815D01*
X350360Y-121847D01*
X350349Y-121888D01*
X350338Y-121927D01*
X350309Y-122015D01*
X350266Y-122102D01*
X350240Y-122146D01*
X350207Y-122190D01*
X350174Y-122230D01*
X350138Y-122266D01*
X350134Y-122270D01*
X350127Y-122273D01*
X350116Y-122284D01*
X350098Y-122295D01*
X350076Y-122310D01*
X350051Y-122324D01*
X350022Y-122343D01*
X349985Y-122361D01*
X349945Y-122379D01*
X349902Y-122397D01*
X349854Y-122412D01*
X349803Y-122426D01*
X349749Y-122437D01*
X349690Y-122448D01*
X349628Y-122452D01*
X349563Y-122455D01*
X349527D01*
X349501Y-122452D01*
X349472Y-122448D01*
X349436Y-122444D01*
X349395Y-122437D01*
X349356Y-122430D01*
X349261Y-122404D01*
X349166Y-122368D01*
X349119Y-122346D01*
X349072Y-122321D01*
X349028Y-122288D01*
X348988Y-122251D01*
X348984Y-122248D01*
X348977Y-122244D01*
X348970Y-122230D01*
X348955Y-122215D01*
X348937Y-122197D01*
X348919Y-122171D01*
X348901Y-122146D01*
X348879Y-122113D01*
X348842Y-122044D01*
X348806Y-121957D01*
X348791Y-121913D01*
X348784Y-121862D01*
X348777Y-121811D01*
X348773Y-121756D01*
Y-121749D01*
Y-121731D01*
X348777Y-121702D01*
X348780Y-121662D01*
X348788Y-121618D01*
X348802Y-121567D01*
X348817Y-121513D01*
X348839Y-121458D01*
X348842Y-121451D01*
X348850Y-121432D01*
X348864Y-121403D01*
X348886Y-121363D01*
X348915Y-121320D01*
X348952Y-121265D01*
X348995Y-121210D01*
X349046Y-121149D01*
X349053Y-121141D01*
X349072Y-121119D01*
X349090Y-121101D01*
X349108Y-121083D01*
X349130Y-121061D01*
X349159Y-121032D01*
X349188Y-121003D01*
X349224Y-120970D01*
X349261Y-120934D01*
X349305Y-120894D01*
X349352Y-120854D01*
X349403Y-120806D01*
X349461Y-120759D01*
X349519Y-120708D01*
X349523Y-120704D01*
X349530Y-120697D01*
X349545Y-120686D01*
X349563Y-120672D01*
X349585Y-120650D01*
X349610Y-120628D01*
X349669Y-120581D01*
X349730Y-120526D01*
X349789Y-120472D01*
X349840Y-120424D01*
X349862Y-120406D01*
X349880Y-120388D01*
X349883Y-120384D01*
X349894Y-120373D01*
X349909Y-120359D01*
X349927Y-120337D01*
X349945Y-120311D01*
X349967Y-120286D01*
X350011Y-120224D01*
X348769D01*
Y-119925D01*
X350440D01*
Y-119929D01*
D02*
G37*
G36*
X389922Y-105871D02*
X389951Y-105875D01*
X389984Y-105882D01*
X390020Y-105889D01*
X390060Y-105897D01*
X390148Y-105926D01*
X390195Y-105948D01*
X390239Y-105969D01*
X390286Y-105999D01*
X390334Y-106031D01*
X390381Y-106068D01*
X390424Y-106111D01*
X390428Y-106115D01*
X390435Y-106122D01*
X390446Y-106137D01*
X390461Y-106155D01*
X390479Y-106177D01*
X390497Y-106206D01*
X390519Y-106239D01*
X390537Y-106279D01*
X390559Y-106319D01*
X390581Y-106366D01*
X390599Y-106413D01*
X390617Y-106468D01*
X390632Y-106526D01*
X390643Y-106588D01*
X390650Y-106650D01*
X390654Y-106719D01*
Y-106752D01*
X390650Y-106774D01*
X390647Y-106803D01*
X390643Y-106836D01*
X390636Y-106872D01*
X390628Y-106912D01*
X390606Y-107000D01*
X390570Y-107091D01*
X390548Y-107138D01*
X390523Y-107182D01*
X390490Y-107225D01*
X390457Y-107269D01*
X390454Y-107273D01*
X390446Y-107280D01*
X390435Y-107291D01*
X390421Y-107302D01*
X390403Y-107320D01*
X390377Y-107338D01*
X390352Y-107360D01*
X390319Y-107382D01*
X390283Y-107404D01*
X390246Y-107425D01*
X390159Y-107466D01*
X390057Y-107498D01*
X390002Y-107509D01*
X389944Y-107516D01*
X389904Y-107207D01*
X389908D01*
X389915Y-107203D01*
X389930Y-107200D01*
X389948Y-107196D01*
X389969Y-107193D01*
X389995Y-107185D01*
X390050Y-107167D01*
X390115Y-107141D01*
X390177Y-107109D01*
X390235Y-107072D01*
X390286Y-107029D01*
X390290Y-107021D01*
X390304Y-107007D01*
X390323Y-106978D01*
X390341Y-106941D01*
X390363Y-106898D01*
X390381Y-106843D01*
X390395Y-106781D01*
X390399Y-106716D01*
Y-106694D01*
X390395Y-106679D01*
X390392Y-106639D01*
X390381Y-106588D01*
X390363Y-106530D01*
X390337Y-106468D01*
X390301Y-106406D01*
X390250Y-106348D01*
X390243Y-106341D01*
X390221Y-106323D01*
X390188Y-106301D01*
X390144Y-106272D01*
X390090Y-106242D01*
X390028Y-106221D01*
X389955Y-106202D01*
X389875Y-106195D01*
X389871D01*
X389864D01*
X389853D01*
X389839Y-106199D01*
X389798Y-106202D01*
X389751Y-106213D01*
X389693Y-106228D01*
X389635Y-106253D01*
X389576Y-106290D01*
X389522Y-106337D01*
X389514Y-106344D01*
X389500Y-106363D01*
X389478Y-106392D01*
X389453Y-106432D01*
X389427Y-106483D01*
X389405Y-106545D01*
X389391Y-106614D01*
X389384Y-106690D01*
Y-106723D01*
X389387Y-106748D01*
X389391Y-106781D01*
X389398Y-106818D01*
X389405Y-106861D01*
X389416Y-106909D01*
X389143Y-106872D01*
Y-106854D01*
X389147Y-106839D01*
Y-106792D01*
X389140Y-106752D01*
X389132Y-106705D01*
X389121Y-106650D01*
X389103Y-106588D01*
X389078Y-106530D01*
X389045Y-106468D01*
Y-106465D01*
X389041Y-106461D01*
X389027Y-106443D01*
X389001Y-106417D01*
X388968Y-106388D01*
X388921Y-106359D01*
X388867Y-106333D01*
X388805Y-106315D01*
X388768Y-106308D01*
X388728D01*
X388725D01*
X388721D01*
X388699D01*
X388670Y-106315D01*
X388630Y-106323D01*
X388586Y-106337D01*
X388539Y-106355D01*
X388492Y-106384D01*
X388448Y-106424D01*
X388444Y-106428D01*
X388430Y-106446D01*
X388412Y-106472D01*
X388390Y-106504D01*
X388372Y-106548D01*
X388353Y-106599D01*
X388339Y-106657D01*
X388335Y-106723D01*
Y-106752D01*
X388342Y-106785D01*
X388350Y-106828D01*
X388364Y-106876D01*
X388383Y-106923D01*
X388412Y-106974D01*
X388448Y-107021D01*
X388452Y-107025D01*
X388470Y-107040D01*
X388495Y-107061D01*
X388532Y-107087D01*
X388579Y-107112D01*
X388637Y-107138D01*
X388706Y-107160D01*
X388787Y-107174D01*
X388732Y-107484D01*
X388728D01*
X388717Y-107480D01*
X388703Y-107476D01*
X388681Y-107473D01*
X388655Y-107466D01*
X388626Y-107455D01*
X388557Y-107433D01*
X388477Y-107396D01*
X388397Y-107353D01*
X388321Y-107298D01*
X388251Y-107229D01*
X388248Y-107225D01*
X388244Y-107218D01*
X388237Y-107207D01*
X388226Y-107193D01*
X388211Y-107174D01*
X388197Y-107149D01*
X388182Y-107123D01*
X388164Y-107091D01*
X388135Y-107018D01*
X388106Y-106934D01*
X388088Y-106836D01*
X388080Y-106785D01*
Y-106694D01*
X388084Y-106654D01*
X388091Y-106606D01*
X388102Y-106548D01*
X388120Y-106483D01*
X388142Y-106417D01*
X388171Y-106352D01*
Y-106348D01*
X388175Y-106344D01*
X388186Y-106323D01*
X388208Y-106290D01*
X388233Y-106253D01*
X388270Y-106210D01*
X388310Y-106166D01*
X388357Y-106122D01*
X388412Y-106086D01*
X388419Y-106082D01*
X388437Y-106071D01*
X388470Y-106057D01*
X388510Y-106039D01*
X388557Y-106020D01*
X388612Y-106006D01*
X388674Y-105995D01*
X388736Y-105991D01*
X388743D01*
X388765D01*
X388794Y-105995D01*
X388834Y-106002D01*
X388881Y-106013D01*
X388932Y-106031D01*
X388983Y-106053D01*
X389034Y-106082D01*
X389041Y-106086D01*
X389056Y-106097D01*
X389081Y-106119D01*
X389110Y-106148D01*
X389143Y-106184D01*
X389180Y-106228D01*
X389212Y-106279D01*
X389245Y-106341D01*
Y-106337D01*
X389249Y-106330D01*
X389252Y-106319D01*
X389256Y-106304D01*
X389271Y-106264D01*
X389293Y-106213D01*
X389322Y-106155D01*
X389358Y-106097D01*
X389405Y-106042D01*
X389460Y-105991D01*
X389467Y-105988D01*
X389489Y-105973D01*
X389525Y-105951D01*
X389573Y-105929D01*
X389631Y-105907D01*
X389700Y-105886D01*
X389780Y-105871D01*
X389868Y-105868D01*
X389871D01*
X389882D01*
X389900D01*
X389922Y-105871D01*
D02*
G37*
G36*
X389948Y-107826D02*
X389973Y-107829D01*
X390006Y-107833D01*
X390042Y-107840D01*
X390082Y-107851D01*
X390166Y-107877D01*
X390213Y-107895D01*
X390257Y-107921D01*
X390304Y-107946D01*
X390348Y-107975D01*
X390392Y-108011D01*
X390435Y-108052D01*
X390439Y-108055D01*
X390446Y-108062D01*
X390457Y-108073D01*
X390468Y-108092D01*
X390486Y-108117D01*
X390505Y-108142D01*
X390523Y-108175D01*
X390545Y-108212D01*
X390566Y-108252D01*
X390585Y-108299D01*
X390603Y-108350D01*
X390621Y-108401D01*
X390632Y-108459D01*
X390643Y-108521D01*
X390650Y-108583D01*
X390654Y-108652D01*
Y-108688D01*
X390650Y-108714D01*
X390647Y-108747D01*
X390643Y-108783D01*
X390636Y-108823D01*
X390625Y-108867D01*
X390599Y-108965D01*
X390581Y-109016D01*
X390563Y-109063D01*
X390537Y-109114D01*
X390508Y-109165D01*
X390476Y-109213D01*
X390435Y-109256D01*
X390432Y-109260D01*
X390424Y-109267D01*
X390414Y-109278D01*
X390395Y-109293D01*
X390374Y-109307D01*
X390348Y-109329D01*
X390319Y-109347D01*
X390283Y-109369D01*
X390246Y-109391D01*
X390202Y-109409D01*
X390111Y-109446D01*
X390057Y-109460D01*
X390002Y-109471D01*
X389944Y-109478D01*
X389886Y-109482D01*
X389882D01*
X389875D01*
X389860D01*
X389846Y-109478D01*
X389824D01*
X389798Y-109475D01*
X389740Y-109467D01*
X389675Y-109453D01*
X389609Y-109431D01*
X389540Y-109398D01*
X389475Y-109358D01*
X389471D01*
X389467Y-109351D01*
X389449Y-109336D01*
X389420Y-109307D01*
X389384Y-109267D01*
X389347Y-109216D01*
X389307Y-109154D01*
X389274Y-109085D01*
X389249Y-109002D01*
Y-109005D01*
X389245Y-109009D01*
X389242Y-109020D01*
X389234Y-109034D01*
X389220Y-109067D01*
X389198Y-109111D01*
X389169Y-109158D01*
X389132Y-109205D01*
X389092Y-109249D01*
X389049Y-109289D01*
X389041Y-109293D01*
X389027Y-109304D01*
X388998Y-109318D01*
X388961Y-109333D01*
X388914Y-109351D01*
X388859Y-109366D01*
X388797Y-109377D01*
X388732Y-109380D01*
X388728D01*
X388721D01*
X388706D01*
X388685Y-109377D01*
X388663Y-109373D01*
X388634Y-109369D01*
X388572Y-109355D01*
X388499Y-109333D01*
X388422Y-109296D01*
X388383Y-109274D01*
X388342Y-109249D01*
X388306Y-109216D01*
X388270Y-109184D01*
X388266Y-109180D01*
X388262Y-109173D01*
X388251Y-109162D01*
X388241Y-109147D01*
X388226Y-109129D01*
X388211Y-109104D01*
X388193Y-109074D01*
X388175Y-109045D01*
X388157Y-109009D01*
X388139Y-108969D01*
X388124Y-108925D01*
X388109Y-108878D01*
X388088Y-108776D01*
X388084Y-108718D01*
X388080Y-108659D01*
Y-108627D01*
X388084Y-108605D01*
X388088Y-108576D01*
X388091Y-108543D01*
X388095Y-108507D01*
X388106Y-108470D01*
X388128Y-108383D01*
X388160Y-108295D01*
X388182Y-108252D01*
X388208Y-108208D01*
X388241Y-108168D01*
X388273Y-108128D01*
X388277Y-108124D01*
X388281Y-108121D01*
X388292Y-108110D01*
X388306Y-108095D01*
X388328Y-108081D01*
X388350Y-108062D01*
X388404Y-108026D01*
X388474Y-107990D01*
X388554Y-107957D01*
X388645Y-107931D01*
X388692Y-107928D01*
X388743Y-107924D01*
X388747D01*
X388750D01*
X388772D01*
X388805Y-107928D01*
X388845Y-107935D01*
X388896Y-107946D01*
X388947Y-107964D01*
X388998Y-107986D01*
X389049Y-108019D01*
X389056Y-108022D01*
X389070Y-108037D01*
X389092Y-108059D01*
X389121Y-108088D01*
X389154Y-108128D01*
X389187Y-108175D01*
X389220Y-108230D01*
X389249Y-108295D01*
Y-108292D01*
X389252Y-108284D01*
X389256Y-108274D01*
X389263Y-108259D01*
X389282Y-108215D01*
X389307Y-108164D01*
X389343Y-108110D01*
X389384Y-108052D01*
X389434Y-107997D01*
X389493Y-107946D01*
X389496D01*
X389500Y-107942D01*
X389522Y-107928D01*
X389558Y-107906D01*
X389605Y-107884D01*
X389664Y-107862D01*
X389733Y-107840D01*
X389809Y-107826D01*
X389893Y-107822D01*
X389897D01*
X389908D01*
X389926D01*
X389948Y-107826D01*
D02*
G37*
G36*
X389831Y-109766D02*
X389853Y-109773D01*
X389882Y-109784D01*
X389915Y-109795D01*
X389955Y-109810D01*
X389999Y-109828D01*
X390046Y-109850D01*
X390148Y-109901D01*
X390250Y-109966D01*
X390301Y-110006D01*
X390352Y-110046D01*
X390395Y-110090D01*
X390439Y-110141D01*
X390443Y-110144D01*
X390450Y-110152D01*
X390457Y-110170D01*
X390472Y-110188D01*
X390490Y-110217D01*
X390508Y-110246D01*
X390526Y-110286D01*
X390545Y-110327D01*
X390566Y-110374D01*
X390585Y-110425D01*
X390603Y-110479D01*
X390621Y-110538D01*
X390636Y-110600D01*
X390643Y-110665D01*
X390650Y-110734D01*
X390654Y-110807D01*
Y-110847D01*
X390650Y-110876D01*
Y-110909D01*
X390647Y-110949D01*
X390639Y-110993D01*
X390632Y-111044D01*
X390614Y-111149D01*
X390585Y-111258D01*
X390545Y-111368D01*
X390519Y-111418D01*
X390490Y-111469D01*
X390486Y-111473D01*
X390483Y-111480D01*
X390472Y-111495D01*
X390457Y-111510D01*
X390443Y-111531D01*
X390421Y-111557D01*
X390395Y-111586D01*
X390366Y-111615D01*
X390334Y-111644D01*
X390301Y-111677D01*
X390217Y-111742D01*
X390119Y-111804D01*
X390010Y-111859D01*
X390006D01*
X389995Y-111866D01*
X389977Y-111870D01*
X389955Y-111881D01*
X389926Y-111888D01*
X389889Y-111899D01*
X389849Y-111914D01*
X389806Y-111925D01*
X389758Y-111935D01*
X389704Y-111950D01*
X389591Y-111968D01*
X389464Y-111983D01*
X389333Y-111990D01*
X389329D01*
X389314D01*
X389293D01*
X389267Y-111986D01*
X389231D01*
X389194Y-111983D01*
X389147Y-111979D01*
X389100Y-111972D01*
X388994Y-111954D01*
X388878Y-111928D01*
X388761Y-111892D01*
X388648Y-111841D01*
X388645Y-111837D01*
X388634Y-111834D01*
X388619Y-111826D01*
X388601Y-111812D01*
X388575Y-111797D01*
X388546Y-111779D01*
X388481Y-111732D01*
X388408Y-111670D01*
X388335Y-111597D01*
X388262Y-111513D01*
X388200Y-111415D01*
X388197Y-111411D01*
X388193Y-111400D01*
X388186Y-111386D01*
X388175Y-111368D01*
X388164Y-111338D01*
X388153Y-111309D01*
X388139Y-111273D01*
X388124Y-111233D01*
X388109Y-111189D01*
X388095Y-111142D01*
X388073Y-111040D01*
X388055Y-110924D01*
X388048Y-110803D01*
Y-110767D01*
X388051Y-110741D01*
X388055Y-110709D01*
X388058Y-110669D01*
X388062Y-110629D01*
X388073Y-110581D01*
X388095Y-110483D01*
X388128Y-110374D01*
X388149Y-110319D01*
X388175Y-110268D01*
X388208Y-110217D01*
X388241Y-110166D01*
X388244Y-110163D01*
X388248Y-110155D01*
X388259Y-110141D01*
X388277Y-110123D01*
X388295Y-110105D01*
X388321Y-110079D01*
X388350Y-110054D01*
X388379Y-110024D01*
X388415Y-109995D01*
X388459Y-109966D01*
X388503Y-109933D01*
X388550Y-109904D01*
X388604Y-109879D01*
X388659Y-109850D01*
X388717Y-109828D01*
X388783Y-109806D01*
X388859Y-110134D01*
X388856D01*
X388848Y-110137D01*
X388834Y-110144D01*
X388816Y-110152D01*
X388794Y-110159D01*
X388765Y-110170D01*
X388706Y-110199D01*
X388641Y-110236D01*
X388575Y-110279D01*
X388513Y-110334D01*
X388459Y-110392D01*
X388452Y-110399D01*
X388437Y-110421D01*
X388419Y-110458D01*
X388393Y-110505D01*
X388372Y-110567D01*
X388350Y-110636D01*
X388335Y-110720D01*
X388332Y-110811D01*
Y-110840D01*
X388335Y-110858D01*
Y-110883D01*
X388339Y-110913D01*
X388350Y-110982D01*
X388364Y-111058D01*
X388390Y-111138D01*
X388426Y-111222D01*
X388474Y-111298D01*
Y-111302D01*
X388481Y-111306D01*
X388499Y-111331D01*
X388528Y-111364D01*
X388572Y-111404D01*
X388626Y-111451D01*
X388688Y-111495D01*
X388765Y-111535D01*
X388848Y-111571D01*
X388852D01*
X388859Y-111575D01*
X388870Y-111579D01*
X388888Y-111582D01*
X388910Y-111590D01*
X388936Y-111597D01*
X388998Y-111608D01*
X389070Y-111622D01*
X389151Y-111637D01*
X389238Y-111644D01*
X389333Y-111648D01*
X389336D01*
X389347D01*
X389365D01*
X389387D01*
X389413Y-111644D01*
X389445D01*
X389482Y-111641D01*
X389522Y-111637D01*
X389609Y-111626D01*
X389704Y-111608D01*
X389798Y-111586D01*
X389893Y-111557D01*
X389897D01*
X389904Y-111553D01*
X389915Y-111546D01*
X389933Y-111539D01*
X389977Y-111517D01*
X390028Y-111484D01*
X390086Y-111444D01*
X390148Y-111393D01*
X390202Y-111335D01*
X390253Y-111266D01*
Y-111262D01*
X390257Y-111255D01*
X390264Y-111244D01*
X390272Y-111229D01*
X390279Y-111211D01*
X390290Y-111189D01*
X390312Y-111138D01*
X390334Y-111073D01*
X390352Y-111000D01*
X390366Y-110920D01*
X390370Y-110836D01*
Y-110811D01*
X390366Y-110789D01*
Y-110763D01*
X390363Y-110738D01*
X390348Y-110672D01*
X390330Y-110596D01*
X390301Y-110519D01*
X390261Y-110439D01*
X390239Y-110399D01*
X390210Y-110363D01*
X390206Y-110359D01*
X390202Y-110356D01*
X390192Y-110345D01*
X390181Y-110330D01*
X390162Y-110316D01*
X390141Y-110297D01*
X390119Y-110275D01*
X390090Y-110257D01*
X390057Y-110236D01*
X390020Y-110210D01*
X389984Y-110188D01*
X389940Y-110166D01*
X389893Y-110148D01*
X389842Y-110130D01*
X389788Y-110112D01*
X389729Y-110097D01*
X389813Y-109762D01*
X389817D01*
X389831Y-109766D01*
D02*
G37*
G36*
X353753Y-113193D02*
X353785D01*
X353825Y-113196D01*
X353869Y-113204D01*
X353920Y-113211D01*
X354026Y-113229D01*
X354135Y-113258D01*
X354244Y-113298D01*
X354295Y-113324D01*
X354346Y-113353D01*
X354350Y-113356D01*
X354357Y-113360D01*
X354371Y-113371D01*
X354386Y-113385D01*
X354408Y-113400D01*
X354433Y-113422D01*
X354462Y-113447D01*
X354491Y-113477D01*
X354521Y-113509D01*
X354553Y-113542D01*
X354619Y-113626D01*
X354681Y-113724D01*
X354735Y-113833D01*
Y-113837D01*
X354743Y-113848D01*
X354746Y-113866D01*
X354757Y-113888D01*
X354765Y-113917D01*
X354776Y-113953D01*
X354790Y-113993D01*
X354801Y-114037D01*
X354812Y-114084D01*
X354826Y-114139D01*
X354845Y-114252D01*
X354859Y-114379D01*
X354867Y-114510D01*
Y-114514D01*
Y-114529D01*
Y-114550D01*
X354863Y-114576D01*
Y-114612D01*
X354859Y-114649D01*
X354855Y-114696D01*
X354848Y-114743D01*
X354830Y-114849D01*
X354805Y-114965D01*
X354768Y-115082D01*
X354717Y-115195D01*
X354714Y-115198D01*
X354710Y-115209D01*
X354703Y-115224D01*
X354688Y-115242D01*
X354674Y-115267D01*
X354655Y-115296D01*
X354608Y-115362D01*
X354546Y-115435D01*
X354473Y-115508D01*
X354390Y-115580D01*
X354291Y-115642D01*
X354288Y-115646D01*
X354277Y-115650D01*
X354262Y-115657D01*
X354244Y-115668D01*
X354215Y-115679D01*
X354186Y-115690D01*
X354149Y-115704D01*
X354109Y-115719D01*
X354066Y-115733D01*
X354018Y-115748D01*
X353916Y-115770D01*
X353800Y-115788D01*
X353680Y-115795D01*
X353643D01*
X353618Y-115792D01*
X353585Y-115788D01*
X353545Y-115784D01*
X353505Y-115781D01*
X353458Y-115770D01*
X353360Y-115748D01*
X353250Y-115715D01*
X353196Y-115693D01*
X353145Y-115668D01*
X353094Y-115635D01*
X353043Y-115602D01*
X353039Y-115599D01*
X353032Y-115595D01*
X353017Y-115584D01*
X352999Y-115566D01*
X352981Y-115548D01*
X352956Y-115522D01*
X352930Y-115493D01*
X352901Y-115464D01*
X352872Y-115427D01*
X352843Y-115384D01*
X352810Y-115340D01*
X352781Y-115293D01*
X352755Y-115238D01*
X352726Y-115184D01*
X352704Y-115125D01*
X352682Y-115060D01*
X353010Y-114983D01*
Y-114987D01*
X353014Y-114994D01*
X353021Y-115009D01*
X353028Y-115027D01*
X353035Y-115049D01*
X353046Y-115078D01*
X353076Y-115136D01*
X353112Y-115202D01*
X353156Y-115267D01*
X353210Y-115329D01*
X353269Y-115384D01*
X353276Y-115391D01*
X353298Y-115406D01*
X353334Y-115424D01*
X353381Y-115449D01*
X353443Y-115471D01*
X353512Y-115493D01*
X353596Y-115508D01*
X353687Y-115511D01*
X353716D01*
X353734Y-115508D01*
X353760D01*
X353789Y-115504D01*
X353858Y-115493D01*
X353935Y-115479D01*
X354015Y-115453D01*
X354098Y-115417D01*
X354175Y-115369D01*
X354179D01*
X354182Y-115362D01*
X354208Y-115344D01*
X354240Y-115315D01*
X354280Y-115271D01*
X354328Y-115216D01*
X354371Y-115155D01*
X354412Y-115078D01*
X354448Y-114994D01*
Y-114991D01*
X354451Y-114983D01*
X354455Y-114973D01*
X354459Y-114954D01*
X354466Y-114933D01*
X354473Y-114907D01*
X354484Y-114845D01*
X354499Y-114772D01*
X354513Y-114692D01*
X354521Y-114605D01*
X354524Y-114510D01*
Y-114507D01*
Y-114496D01*
Y-114478D01*
Y-114456D01*
X354521Y-114430D01*
Y-114397D01*
X354517Y-114361D01*
X354513Y-114321D01*
X354503Y-114234D01*
X354484Y-114139D01*
X354462Y-114044D01*
X354433Y-113950D01*
Y-113946D01*
X354430Y-113939D01*
X354422Y-113928D01*
X354415Y-113910D01*
X354393Y-113866D01*
X354361Y-113815D01*
X354321Y-113757D01*
X354270Y-113695D01*
X354211Y-113640D01*
X354142Y-113589D01*
X354138D01*
X354131Y-113586D01*
X354120Y-113578D01*
X354106Y-113571D01*
X354087Y-113564D01*
X354066Y-113553D01*
X354015Y-113531D01*
X353949Y-113509D01*
X353876Y-113491D01*
X353796Y-113477D01*
X353713Y-113473D01*
X353687D01*
X353665Y-113477D01*
X353640D01*
X353614Y-113480D01*
X353549Y-113495D01*
X353472Y-113513D01*
X353396Y-113542D01*
X353316Y-113582D01*
X353276Y-113604D01*
X353239Y-113633D01*
X353236Y-113637D01*
X353232Y-113640D01*
X353221Y-113651D01*
X353207Y-113662D01*
X353192Y-113680D01*
X353174Y-113702D01*
X353152Y-113724D01*
X353134Y-113753D01*
X353112Y-113786D01*
X353086Y-113822D01*
X353065Y-113859D01*
X353043Y-113902D01*
X353025Y-113950D01*
X353006Y-114001D01*
X352988Y-114055D01*
X352974Y-114113D01*
X352639Y-114030D01*
Y-114026D01*
X352642Y-114012D01*
X352650Y-113990D01*
X352661Y-113961D01*
X352672Y-113928D01*
X352686Y-113888D01*
X352704Y-113844D01*
X352726Y-113797D01*
X352777Y-113695D01*
X352843Y-113593D01*
X352883Y-113542D01*
X352923Y-113491D01*
X352966Y-113447D01*
X353017Y-113404D01*
X353021Y-113400D01*
X353028Y-113393D01*
X353046Y-113385D01*
X353065Y-113371D01*
X353094Y-113353D01*
X353123Y-113335D01*
X353163Y-113316D01*
X353203Y-113298D01*
X353250Y-113276D01*
X353301Y-113258D01*
X353356Y-113240D01*
X353414Y-113222D01*
X353476Y-113207D01*
X353541Y-113200D01*
X353611Y-113193D01*
X353683Y-113189D01*
X353724D01*
X353753Y-113193D01*
D02*
G37*
G36*
X351590D02*
X351623Y-113196D01*
X351660Y-113200D01*
X351700Y-113207D01*
X351743Y-113218D01*
X351842Y-113244D01*
X351893Y-113262D01*
X351940Y-113280D01*
X351991Y-113305D01*
X352042Y-113335D01*
X352089Y-113367D01*
X352133Y-113407D01*
X352136Y-113411D01*
X352144Y-113418D01*
X352155Y-113429D01*
X352169Y-113447D01*
X352184Y-113469D01*
X352206Y-113495D01*
X352224Y-113524D01*
X352246Y-113560D01*
X352268Y-113597D01*
X352286Y-113640D01*
X352322Y-113731D01*
X352337Y-113786D01*
X352348Y-113840D01*
X352355Y-113899D01*
X352359Y-113957D01*
Y-113961D01*
Y-113968D01*
Y-113982D01*
X352355Y-113997D01*
Y-114019D01*
X352351Y-114044D01*
X352344Y-114103D01*
X352329Y-114168D01*
X352308Y-114234D01*
X352275Y-114303D01*
X352235Y-114368D01*
Y-114372D01*
X352227Y-114376D01*
X352213Y-114394D01*
X352184Y-114423D01*
X352144Y-114459D01*
X352093Y-114496D01*
X352031Y-114536D01*
X351962Y-114568D01*
X351878Y-114594D01*
X351882D01*
X351885Y-114598D01*
X351896Y-114601D01*
X351911Y-114609D01*
X351943Y-114623D01*
X351987Y-114645D01*
X352034Y-114674D01*
X352082Y-114710D01*
X352126Y-114751D01*
X352166Y-114794D01*
X352169Y-114802D01*
X352180Y-114816D01*
X352195Y-114845D01*
X352209Y-114882D01*
X352227Y-114929D01*
X352242Y-114983D01*
X352253Y-115045D01*
X352257Y-115111D01*
Y-115114D01*
Y-115122D01*
Y-115136D01*
X352253Y-115158D01*
X352249Y-115180D01*
X352246Y-115209D01*
X352231Y-115271D01*
X352209Y-115344D01*
X352173Y-115420D01*
X352151Y-115460D01*
X352126Y-115500D01*
X352093Y-115537D01*
X352060Y-115573D01*
X352056Y-115577D01*
X352049Y-115580D01*
X352038Y-115591D01*
X352024Y-115602D01*
X352005Y-115617D01*
X351980Y-115631D01*
X351951Y-115650D01*
X351922Y-115668D01*
X351885Y-115686D01*
X351845Y-115704D01*
X351802Y-115719D01*
X351754Y-115733D01*
X351652Y-115755D01*
X351594Y-115759D01*
X351536Y-115762D01*
X351503D01*
X351481Y-115759D01*
X351452Y-115755D01*
X351419Y-115752D01*
X351383Y-115748D01*
X351347Y-115737D01*
X351259Y-115715D01*
X351172Y-115682D01*
X351128Y-115661D01*
X351084Y-115635D01*
X351045Y-115602D01*
X351004Y-115569D01*
X351001Y-115566D01*
X350997Y-115562D01*
X350986Y-115551D01*
X350972Y-115537D01*
X350957Y-115515D01*
X350939Y-115493D01*
X350903Y-115438D01*
X350866Y-115369D01*
X350833Y-115289D01*
X350808Y-115198D01*
X350804Y-115151D01*
X350801Y-115100D01*
Y-115096D01*
Y-115093D01*
Y-115071D01*
X350804Y-115038D01*
X350812Y-114998D01*
X350822Y-114947D01*
X350841Y-114896D01*
X350863Y-114845D01*
X350895Y-114794D01*
X350899Y-114787D01*
X350913Y-114772D01*
X350935Y-114751D01*
X350964Y-114721D01*
X351004Y-114689D01*
X351052Y-114656D01*
X351106Y-114623D01*
X351172Y-114594D01*
X351168D01*
X351161Y-114590D01*
X351150Y-114587D01*
X351135Y-114579D01*
X351092Y-114561D01*
X351041Y-114536D01*
X350986Y-114499D01*
X350928Y-114459D01*
X350873Y-114408D01*
X350822Y-114350D01*
Y-114347D01*
X350819Y-114343D01*
X350804Y-114321D01*
X350782Y-114285D01*
X350761Y-114237D01*
X350739Y-114179D01*
X350717Y-114110D01*
X350702Y-114033D01*
X350699Y-113950D01*
Y-113946D01*
Y-113935D01*
Y-113917D01*
X350702Y-113895D01*
X350706Y-113870D01*
X350710Y-113837D01*
X350717Y-113801D01*
X350728Y-113760D01*
X350753Y-113677D01*
X350771Y-113629D01*
X350797Y-113586D01*
X350822Y-113538D01*
X350851Y-113495D01*
X350888Y-113451D01*
X350928Y-113407D01*
X350932Y-113404D01*
X350939Y-113396D01*
X350950Y-113385D01*
X350968Y-113375D01*
X350993Y-113356D01*
X351019Y-113338D01*
X351052Y-113320D01*
X351088Y-113298D01*
X351128Y-113276D01*
X351175Y-113258D01*
X351226Y-113240D01*
X351277Y-113222D01*
X351336Y-113211D01*
X351397Y-113200D01*
X351459Y-113193D01*
X351529Y-113189D01*
X351565D01*
X351590Y-113193D01*
D02*
G37*
G36*
X349541Y-115202D02*
X349545Y-115198D01*
X349563Y-115184D01*
X349585Y-115162D01*
X349621Y-115136D01*
X349661Y-115104D01*
X349712Y-115067D01*
X349770Y-115027D01*
X349836Y-114987D01*
X349840D01*
X349843Y-114983D01*
X349865Y-114969D01*
X349902Y-114951D01*
X349945Y-114929D01*
X349996Y-114903D01*
X350051Y-114878D01*
X350105Y-114852D01*
X350160Y-114831D01*
Y-115129D01*
X350156D01*
X350149Y-115136D01*
X350134Y-115140D01*
X350116Y-115151D01*
X350094Y-115162D01*
X350069Y-115176D01*
X350007Y-115213D01*
X349934Y-115253D01*
X349862Y-115304D01*
X349785Y-115362D01*
X349709Y-115424D01*
X349705Y-115427D01*
X349701Y-115431D01*
X349690Y-115442D01*
X349676Y-115453D01*
X349643Y-115489D01*
X349599Y-115533D01*
X349556Y-115584D01*
X349508Y-115642D01*
X349468Y-115700D01*
X349432Y-115762D01*
X349232D01*
Y-113233D01*
X349541D01*
Y-115202D01*
D02*
G37*
G36*
X382096Y-105700D02*
X382139D01*
X382187Y-105703D01*
X382238Y-105707D01*
X382354Y-105718D01*
X382474Y-105736D01*
X382591Y-105758D01*
X382645Y-105772D01*
X382700Y-105790D01*
X382703D01*
X382711Y-105794D01*
X382725Y-105801D01*
X382744Y-105809D01*
X382769Y-105816D01*
X382794Y-105831D01*
X382856Y-105860D01*
X382922Y-105896D01*
X382995Y-105943D01*
X383060Y-105998D01*
X383122Y-106063D01*
Y-106067D01*
X383129Y-106071D01*
X383137Y-106082D01*
X383144Y-106096D01*
X383155Y-106114D01*
X383170Y-106133D01*
X383195Y-106187D01*
X383220Y-106253D01*
X383246Y-106329D01*
X383260Y-106420D01*
X383268Y-106518D01*
Y-106555D01*
X383264Y-106580D01*
X383260Y-106609D01*
X383253Y-106646D01*
X383246Y-106686D01*
X383235Y-106730D01*
X383220Y-106773D01*
X383206Y-106821D01*
X383184Y-106868D01*
X383158Y-106915D01*
X383129Y-106963D01*
X383093Y-107010D01*
X383053Y-107054D01*
X383009Y-107094D01*
X383006Y-107097D01*
X382995Y-107105D01*
X382977Y-107115D01*
X382947Y-107134D01*
X382915Y-107152D01*
X382871Y-107170D01*
X382820Y-107195D01*
X382762Y-107217D01*
X382696Y-107239D01*
X382620Y-107261D01*
X382536Y-107283D01*
X382441Y-107301D01*
X382340Y-107319D01*
X382230Y-107330D01*
X382110Y-107337D01*
X381983Y-107341D01*
X381979D01*
X381965D01*
X381939D01*
X381910D01*
X381870Y-107337D01*
X381826D01*
X381779Y-107334D01*
X381724Y-107330D01*
X381611Y-107319D01*
X381491Y-107301D01*
X381371Y-107279D01*
X381317Y-107265D01*
X381262Y-107250D01*
X381259D01*
X381251Y-107246D01*
X381237Y-107239D01*
X381218Y-107232D01*
X381193Y-107225D01*
X381168Y-107210D01*
X381106Y-107181D01*
X381040Y-107145D01*
X380971Y-107097D01*
X380902Y-107043D01*
X380843Y-106977D01*
Y-106974D01*
X380836Y-106970D01*
X380829Y-106959D01*
X380822Y-106944D01*
X380807Y-106926D01*
X380796Y-106904D01*
X380767Y-106850D01*
X380742Y-106784D01*
X380716Y-106708D01*
X380701Y-106617D01*
X380694Y-106518D01*
Y-106486D01*
X380698Y-106446D01*
X380705Y-106398D01*
X380716Y-106344D01*
X380731Y-106286D01*
X380749Y-106224D01*
X380778Y-106165D01*
Y-106162D01*
X380782Y-106158D01*
X380792Y-106140D01*
X380811Y-106111D01*
X380836Y-106074D01*
X380873Y-106034D01*
X380913Y-105991D01*
X380960Y-105951D01*
X381015Y-105911D01*
X381022Y-105907D01*
X381040Y-105892D01*
X381073Y-105878D01*
X381120Y-105852D01*
X381175Y-105831D01*
X381237Y-105801D01*
X381309Y-105776D01*
X381389Y-105754D01*
X381393D01*
X381400Y-105751D01*
X381411Y-105747D01*
X381430Y-105743D01*
X381451Y-105739D01*
X381477Y-105736D01*
X381510Y-105729D01*
X381546Y-105725D01*
X381586Y-105718D01*
X381630Y-105714D01*
X381681Y-105710D01*
X381732Y-105703D01*
X381790Y-105700D01*
X381848D01*
X381914Y-105696D01*
X381983D01*
X381986D01*
X382001D01*
X382027D01*
X382056D01*
X382096Y-105700D01*
D02*
G37*
G36*
X382562Y-107647D02*
X382587Y-107650D01*
X382620Y-107654D01*
X382656Y-107661D01*
X382696Y-107672D01*
X382780Y-107698D01*
X382827Y-107716D01*
X382871Y-107741D01*
X382918Y-107767D01*
X382962Y-107796D01*
X383006Y-107833D01*
X383049Y-107873D01*
X383053Y-107876D01*
X383060Y-107884D01*
X383071Y-107894D01*
X383082Y-107913D01*
X383100Y-107938D01*
X383119Y-107964D01*
X383137Y-107996D01*
X383158Y-108033D01*
X383180Y-108073D01*
X383199Y-108120D01*
X383217Y-108171D01*
X383235Y-108222D01*
X383246Y-108280D01*
X383257Y-108342D01*
X383264Y-108404D01*
X383268Y-108473D01*
Y-108510D01*
X383264Y-108535D01*
X383260Y-108568D01*
X383257Y-108604D01*
X383249Y-108644D01*
X383239Y-108688D01*
X383213Y-108786D01*
X383195Y-108837D01*
X383177Y-108885D01*
X383151Y-108935D01*
X383122Y-108986D01*
X383089Y-109034D01*
X383049Y-109077D01*
X383046Y-109081D01*
X383038Y-109088D01*
X383028Y-109099D01*
X383009Y-109114D01*
X382987Y-109128D01*
X382962Y-109150D01*
X382933Y-109168D01*
X382896Y-109190D01*
X382860Y-109212D01*
X382816Y-109230D01*
X382725Y-109267D01*
X382671Y-109281D01*
X382616Y-109292D01*
X382558Y-109300D01*
X382500Y-109303D01*
X382496D01*
X382489D01*
X382474D01*
X382460Y-109300D01*
X382438D01*
X382412Y-109296D01*
X382354Y-109289D01*
X382289Y-109274D01*
X382223Y-109252D01*
X382154Y-109219D01*
X382088Y-109179D01*
X382085D01*
X382081Y-109172D01*
X382063Y-109158D01*
X382034Y-109128D01*
X381997Y-109088D01*
X381961Y-109037D01*
X381921Y-108976D01*
X381888Y-108906D01*
X381863Y-108823D01*
Y-108826D01*
X381859Y-108830D01*
X381855Y-108841D01*
X381848Y-108855D01*
X381834Y-108888D01*
X381812Y-108932D01*
X381783Y-108979D01*
X381746Y-109027D01*
X381706Y-109070D01*
X381663Y-109110D01*
X381655Y-109114D01*
X381641Y-109125D01*
X381611Y-109139D01*
X381575Y-109154D01*
X381528Y-109172D01*
X381473Y-109187D01*
X381411Y-109197D01*
X381346Y-109201D01*
X381342D01*
X381335D01*
X381320D01*
X381298Y-109197D01*
X381277Y-109194D01*
X381247Y-109190D01*
X381186Y-109176D01*
X381113Y-109154D01*
X381036Y-109117D01*
X380996Y-109096D01*
X380956Y-109070D01*
X380920Y-109037D01*
X380884Y-109005D01*
X380880Y-109001D01*
X380876Y-108994D01*
X380865Y-108983D01*
X380854Y-108968D01*
X380840Y-108950D01*
X380825Y-108924D01*
X380807Y-108895D01*
X380789Y-108866D01*
X380771Y-108830D01*
X380752Y-108790D01*
X380738Y-108746D01*
X380723Y-108699D01*
X380701Y-108597D01*
X380698Y-108539D01*
X380694Y-108481D01*
Y-108448D01*
X380698Y-108426D01*
X380701Y-108397D01*
X380705Y-108364D01*
X380709Y-108328D01*
X380720Y-108291D01*
X380742Y-108204D01*
X380774Y-108116D01*
X380796Y-108073D01*
X380822Y-108029D01*
X380854Y-107989D01*
X380887Y-107949D01*
X380891Y-107945D01*
X380894Y-107942D01*
X380905Y-107931D01*
X380920Y-107916D01*
X380942Y-107902D01*
X380964Y-107884D01*
X381018Y-107847D01*
X381087Y-107811D01*
X381168Y-107778D01*
X381259Y-107753D01*
X381306Y-107749D01*
X381357Y-107745D01*
X381360D01*
X381364D01*
X381386D01*
X381419Y-107749D01*
X381459Y-107756D01*
X381510Y-107767D01*
X381561Y-107785D01*
X381611Y-107807D01*
X381663Y-107840D01*
X381670Y-107843D01*
X381684Y-107858D01*
X381706Y-107880D01*
X381735Y-107909D01*
X381768Y-107949D01*
X381801Y-107996D01*
X381834Y-108051D01*
X381863Y-108116D01*
Y-108113D01*
X381866Y-108106D01*
X381870Y-108095D01*
X381877Y-108080D01*
X381895Y-108036D01*
X381921Y-107985D01*
X381957Y-107931D01*
X381997Y-107873D01*
X382048Y-107818D01*
X382107Y-107767D01*
X382110D01*
X382114Y-107763D01*
X382136Y-107749D01*
X382172Y-107727D01*
X382219Y-107705D01*
X382278Y-107683D01*
X382347Y-107661D01*
X382423Y-107647D01*
X382507Y-107643D01*
X382511D01*
X382522D01*
X382540D01*
X382562Y-107647D01*
D02*
G37*
G36*
X382445Y-109587D02*
X382467Y-109594D01*
X382496Y-109605D01*
X382529Y-109616D01*
X382569Y-109631D01*
X382612Y-109649D01*
X382660Y-109671D01*
X382762Y-109722D01*
X382864Y-109787D01*
X382915Y-109827D01*
X382966Y-109867D01*
X383009Y-109911D01*
X383053Y-109962D01*
X383057Y-109966D01*
X383064Y-109973D01*
X383071Y-109991D01*
X383086Y-110009D01*
X383104Y-110038D01*
X383122Y-110067D01*
X383140Y-110108D01*
X383158Y-110148D01*
X383180Y-110195D01*
X383199Y-110246D01*
X383217Y-110301D01*
X383235Y-110359D01*
X383249Y-110421D01*
X383257Y-110486D01*
X383264Y-110555D01*
X383268Y-110628D01*
Y-110668D01*
X383264Y-110697D01*
Y-110730D01*
X383260Y-110770D01*
X383253Y-110814D01*
X383246Y-110865D01*
X383228Y-110970D01*
X383199Y-111079D01*
X383158Y-111189D01*
X383133Y-111240D01*
X383104Y-111291D01*
X383100Y-111294D01*
X383097Y-111302D01*
X383086Y-111316D01*
X383071Y-111331D01*
X383057Y-111352D01*
X383035Y-111378D01*
X383009Y-111407D01*
X382980Y-111436D01*
X382947Y-111465D01*
X382915Y-111498D01*
X382831Y-111564D01*
X382733Y-111625D01*
X382624Y-111680D01*
X382620D01*
X382609Y-111687D01*
X382591Y-111691D01*
X382569Y-111702D01*
X382540Y-111709D01*
X382503Y-111720D01*
X382463Y-111735D01*
X382420Y-111746D01*
X382372Y-111757D01*
X382318Y-111771D01*
X382205Y-111789D01*
X382078Y-111804D01*
X381946Y-111811D01*
X381943D01*
X381928D01*
X381906D01*
X381881Y-111807D01*
X381844D01*
X381808Y-111804D01*
X381761Y-111800D01*
X381714Y-111793D01*
X381608Y-111775D01*
X381491Y-111749D01*
X381375Y-111713D01*
X381262Y-111662D01*
X381259Y-111658D01*
X381247Y-111654D01*
X381233Y-111647D01*
X381215Y-111633D01*
X381189Y-111618D01*
X381160Y-111600D01*
X381095Y-111553D01*
X381022Y-111491D01*
X380949Y-111418D01*
X380876Y-111334D01*
X380814Y-111236D01*
X380811Y-111232D01*
X380807Y-111221D01*
X380800Y-111207D01*
X380789Y-111189D01*
X380778Y-111160D01*
X380767Y-111130D01*
X380752Y-111094D01*
X380738Y-111054D01*
X380723Y-111010D01*
X380709Y-110963D01*
X380687Y-110861D01*
X380669Y-110745D01*
X380662Y-110624D01*
Y-110588D01*
X380665Y-110563D01*
X380669Y-110530D01*
X380672Y-110490D01*
X380676Y-110450D01*
X380687Y-110402D01*
X380709Y-110304D01*
X380742Y-110195D01*
X380763Y-110140D01*
X380789Y-110089D01*
X380822Y-110038D01*
X380854Y-109987D01*
X380858Y-109984D01*
X380862Y-109976D01*
X380873Y-109962D01*
X380891Y-109944D01*
X380909Y-109925D01*
X380935Y-109900D01*
X380964Y-109875D01*
X380993Y-109845D01*
X381029Y-109816D01*
X381073Y-109787D01*
X381117Y-109755D01*
X381164Y-109725D01*
X381218Y-109700D01*
X381273Y-109671D01*
X381331Y-109649D01*
X381397Y-109627D01*
X381473Y-109955D01*
X381470D01*
X381462Y-109958D01*
X381448Y-109966D01*
X381430Y-109973D01*
X381408Y-109980D01*
X381379Y-109991D01*
X381320Y-110020D01*
X381255Y-110057D01*
X381189Y-110100D01*
X381127Y-110155D01*
X381073Y-110213D01*
X381066Y-110220D01*
X381051Y-110242D01*
X381033Y-110279D01*
X381007Y-110326D01*
X380985Y-110388D01*
X380964Y-110457D01*
X380949Y-110541D01*
X380945Y-110632D01*
Y-110661D01*
X380949Y-110679D01*
Y-110705D01*
X380953Y-110734D01*
X380964Y-110803D01*
X380978Y-110879D01*
X381004Y-110959D01*
X381040Y-111043D01*
X381087Y-111119D01*
Y-111123D01*
X381095Y-111127D01*
X381113Y-111152D01*
X381142Y-111185D01*
X381186Y-111225D01*
X381240Y-111272D01*
X381302Y-111316D01*
X381379Y-111356D01*
X381462Y-111392D01*
X381466D01*
X381473Y-111396D01*
X381484Y-111400D01*
X381502Y-111403D01*
X381524Y-111411D01*
X381550Y-111418D01*
X381611Y-111429D01*
X381684Y-111443D01*
X381764Y-111458D01*
X381852Y-111465D01*
X381946Y-111469D01*
X381950D01*
X381961D01*
X381979D01*
X382001D01*
X382027Y-111465D01*
X382059D01*
X382096Y-111462D01*
X382136Y-111458D01*
X382223Y-111447D01*
X382318Y-111429D01*
X382412Y-111407D01*
X382507Y-111378D01*
X382511D01*
X382518Y-111374D01*
X382529Y-111367D01*
X382547Y-111360D01*
X382591Y-111338D01*
X382642Y-111305D01*
X382700Y-111265D01*
X382762Y-111214D01*
X382816Y-111156D01*
X382867Y-111087D01*
Y-111083D01*
X382871Y-111076D01*
X382878Y-111065D01*
X382886Y-111050D01*
X382893Y-111032D01*
X382904Y-111010D01*
X382926Y-110959D01*
X382947Y-110894D01*
X382966Y-110821D01*
X382980Y-110741D01*
X382984Y-110657D01*
Y-110632D01*
X382980Y-110610D01*
Y-110584D01*
X382977Y-110559D01*
X382962Y-110493D01*
X382944Y-110417D01*
X382915Y-110340D01*
X382875Y-110260D01*
X382853Y-110220D01*
X382824Y-110184D01*
X382820Y-110180D01*
X382816Y-110177D01*
X382805Y-110166D01*
X382794Y-110151D01*
X382776Y-110137D01*
X382754Y-110118D01*
X382733Y-110097D01*
X382703Y-110078D01*
X382671Y-110057D01*
X382634Y-110031D01*
X382598Y-110009D01*
X382554Y-109987D01*
X382507Y-109969D01*
X382456Y-109951D01*
X382401Y-109933D01*
X382343Y-109918D01*
X382427Y-109583D01*
X382431D01*
X382445Y-109587D01*
D02*
G37*
G36*
X430122Y-197185D02*
X428666D01*
X428662D01*
X428651D01*
X428633D01*
X428611D01*
X428585Y-197189D01*
X428553D01*
X428484Y-197193D01*
X428404Y-197200D01*
X428324Y-197211D01*
X428247Y-197225D01*
X428214Y-197233D01*
X428182Y-197243D01*
X428174Y-197247D01*
X428156Y-197254D01*
X428130Y-197273D01*
X428094Y-197294D01*
X428058Y-197320D01*
X428018Y-197356D01*
X427978Y-197400D01*
X427945Y-197451D01*
X427941Y-197458D01*
X427930Y-197476D01*
X427919Y-197509D01*
X427905Y-197553D01*
X427887Y-197604D01*
X427876Y-197669D01*
X427865Y-197739D01*
X427861Y-197815D01*
Y-197851D01*
X427865Y-197873D01*
Y-197906D01*
X427869Y-197939D01*
X427883Y-198019D01*
X427901Y-198106D01*
X427930Y-198190D01*
X427970Y-198270D01*
X427996Y-198306D01*
X428025Y-198339D01*
X428029Y-198343D01*
X428032Y-198346D01*
X428043Y-198354D01*
X428058Y-198365D01*
X428080Y-198376D01*
X428101Y-198390D01*
X428134Y-198405D01*
X428167Y-198419D01*
X428207Y-198434D01*
X428254Y-198445D01*
X428309Y-198459D01*
X428367Y-198470D01*
X428433Y-198481D01*
X428502Y-198488D01*
X428582Y-198496D01*
X428666D01*
X430122D01*
Y-198831D01*
X428666D01*
X428662D01*
X428647D01*
X428629D01*
X428604D01*
X428571Y-198827D01*
X428535D01*
X428491Y-198823D01*
X428447Y-198820D01*
X428349Y-198809D01*
X428247Y-198794D01*
X428149Y-198772D01*
X428101Y-198758D01*
X428058Y-198743D01*
X428054D01*
X428047Y-198740D01*
X428036Y-198732D01*
X428021Y-198725D01*
X427981Y-198703D01*
X427930Y-198670D01*
X427872Y-198627D01*
X427814Y-198576D01*
X427752Y-198510D01*
X427697Y-198430D01*
Y-198426D01*
X427690Y-198419D01*
X427687Y-198408D01*
X427675Y-198390D01*
X427665Y-198368D01*
X427654Y-198339D01*
X427643Y-198310D01*
X427628Y-198274D01*
X427614Y-198234D01*
X427603Y-198190D01*
X427592Y-198143D01*
X427581Y-198088D01*
X427574Y-198033D01*
X427566Y-197975D01*
X427559Y-197844D01*
Y-197811D01*
X427563Y-197786D01*
Y-197757D01*
X427566Y-197720D01*
X427570Y-197680D01*
X427574Y-197640D01*
X427588Y-197549D01*
X427610Y-197451D01*
X427639Y-197356D01*
X427679Y-197265D01*
Y-197262D01*
X427687Y-197254D01*
X427694Y-197243D01*
X427701Y-197229D01*
X427730Y-197189D01*
X427770Y-197142D01*
X427821Y-197087D01*
X427879Y-197036D01*
X427952Y-196985D01*
X428032Y-196945D01*
X428036D01*
X428043Y-196941D01*
X428058Y-196938D01*
X428076Y-196931D01*
X428098Y-196923D01*
X428127Y-196916D01*
X428160Y-196905D01*
X428200Y-196898D01*
X428243Y-196890D01*
X428291Y-196879D01*
X428342Y-196872D01*
X428396Y-196865D01*
X428458Y-196858D01*
X428524Y-196854D01*
X428593Y-196850D01*
X428666D01*
X430122D01*
Y-197185D01*
D02*
G37*
G36*
X430089Y-200913D02*
X429845D01*
X429841Y-200909D01*
X429834Y-200902D01*
X429819Y-200887D01*
X429798Y-200873D01*
X429772Y-200851D01*
X429743Y-200822D01*
X429707Y-200793D01*
X429663Y-200760D01*
X429619Y-200727D01*
X429568Y-200687D01*
X429510Y-200647D01*
X429452Y-200607D01*
X429386Y-200563D01*
X429317Y-200519D01*
X429241Y-200476D01*
X429164Y-200432D01*
X429161Y-200429D01*
X429146Y-200421D01*
X429124Y-200410D01*
X429092Y-200392D01*
X429051Y-200374D01*
X429008Y-200352D01*
X428957Y-200327D01*
X428899Y-200301D01*
X428833Y-200272D01*
X428767Y-200239D01*
X428695Y-200210D01*
X428618Y-200181D01*
X428462Y-200123D01*
X428294Y-200068D01*
X428291D01*
X428280Y-200064D01*
X428262Y-200061D01*
X428240Y-200054D01*
X428211Y-200046D01*
X428174Y-200039D01*
X428134Y-200028D01*
X428090Y-200021D01*
X428040Y-200010D01*
X427985Y-199999D01*
X427869Y-199981D01*
X427741Y-199963D01*
X427603Y-199952D01*
Y-199635D01*
X427606D01*
X427617D01*
X427632D01*
X427654Y-199639D01*
X427683D01*
X427719Y-199642D01*
X427759Y-199646D01*
X427803Y-199650D01*
X427854Y-199657D01*
X427905Y-199664D01*
X427967Y-199675D01*
X428029Y-199686D01*
X428094Y-199697D01*
X428167Y-199711D01*
X428316Y-199748D01*
X428320D01*
X428334Y-199751D01*
X428356Y-199759D01*
X428389Y-199770D01*
X428425Y-199781D01*
X428469Y-199795D01*
X428520Y-199810D01*
X428575Y-199832D01*
X428637Y-199853D01*
X428698Y-199875D01*
X428837Y-199930D01*
X428982Y-199995D01*
X429128Y-200068D01*
X429132Y-200072D01*
X429146Y-200079D01*
X429164Y-200090D01*
X429193Y-200105D01*
X429226Y-200123D01*
X429266Y-200148D01*
X429310Y-200174D01*
X429357Y-200203D01*
X429463Y-200272D01*
X429572Y-200345D01*
X429685Y-200429D01*
X429790Y-200516D01*
Y-199282D01*
X430089D01*
Y-200913D01*
D02*
G37*
G36*
X61878Y14460D02*
X61911Y14456D01*
X61951Y14453D01*
X61991Y14449D01*
X62039Y14438D01*
X62137Y14416D01*
X62246Y14383D01*
X62301Y14362D01*
X62352Y14336D01*
X62403Y14303D01*
X62454Y14271D01*
X62457Y14267D01*
X62464Y14263D01*
X62479Y14252D01*
X62497Y14234D01*
X62515Y14216D01*
X62541Y14190D01*
X62566Y14161D01*
X62595Y14132D01*
X62625Y14096D01*
X62654Y14052D01*
X62687Y14008D01*
X62716Y13961D01*
X62741Y13907D01*
X62770Y13852D01*
X62792Y13794D01*
X62814Y13728D01*
X62486Y13652D01*
Y13656D01*
X62483Y13663D01*
X62475Y13677D01*
X62468Y13695D01*
X62461Y13717D01*
X62450Y13747D01*
X62421Y13805D01*
X62384Y13870D01*
X62341Y13936D01*
X62286Y13998D01*
X62228Y14052D01*
X62221Y14060D01*
X62199Y14074D01*
X62162Y14092D01*
X62115Y14118D01*
X62053Y14140D01*
X61984Y14161D01*
X61900Y14176D01*
X61809Y14180D01*
X61780D01*
X61762Y14176D01*
X61737D01*
X61707Y14172D01*
X61638Y14161D01*
X61562Y14147D01*
X61482Y14121D01*
X61398Y14085D01*
X61322Y14038D01*
X61318D01*
X61314Y14030D01*
X61289Y14012D01*
X61256Y13983D01*
X61216Y13939D01*
X61169Y13885D01*
X61125Y13823D01*
X61085Y13747D01*
X61049Y13663D01*
Y13659D01*
X61045Y13652D01*
X61041Y13641D01*
X61038Y13623D01*
X61030Y13601D01*
X61023Y13575D01*
X61012Y13513D01*
X60998Y13441D01*
X60983Y13361D01*
X60976Y13273D01*
X60972Y13179D01*
Y13175D01*
Y13164D01*
Y13146D01*
Y13124D01*
X60976Y13099D01*
Y13066D01*
X60979Y13029D01*
X60983Y12989D01*
X60994Y12902D01*
X61012Y12807D01*
X61034Y12713D01*
X61063Y12618D01*
Y12614D01*
X61067Y12607D01*
X61074Y12596D01*
X61081Y12578D01*
X61103Y12534D01*
X61136Y12483D01*
X61176Y12425D01*
X61227Y12363D01*
X61285Y12309D01*
X61354Y12258D01*
X61358D01*
X61365Y12254D01*
X61376Y12247D01*
X61391Y12240D01*
X61409Y12232D01*
X61431Y12221D01*
X61482Y12200D01*
X61547Y12178D01*
X61620Y12159D01*
X61700Y12145D01*
X61784Y12141D01*
X61809D01*
X61831Y12145D01*
X61857D01*
X61882Y12149D01*
X61948Y12163D01*
X62024Y12181D01*
X62100Y12210D01*
X62181Y12250D01*
X62221Y12272D01*
X62257Y12301D01*
X62261Y12305D01*
X62264Y12309D01*
X62275Y12320D01*
X62290Y12331D01*
X62304Y12349D01*
X62322Y12371D01*
X62344Y12392D01*
X62363Y12421D01*
X62384Y12454D01*
X62410Y12491D01*
X62432Y12527D01*
X62454Y12571D01*
X62472Y12618D01*
X62490Y12669D01*
X62508Y12724D01*
X62523Y12782D01*
X62858Y12698D01*
Y12695D01*
X62854Y12680D01*
X62847Y12658D01*
X62836Y12629D01*
X62825Y12596D01*
X62810Y12556D01*
X62792Y12513D01*
X62770Y12465D01*
X62719Y12363D01*
X62654Y12261D01*
X62614Y12210D01*
X62574Y12159D01*
X62530Y12116D01*
X62479Y12072D01*
X62475Y12068D01*
X62468Y12061D01*
X62450Y12054D01*
X62432Y12039D01*
X62403Y12021D01*
X62374Y12003D01*
X62333Y11985D01*
X62293Y11966D01*
X62246Y11945D01*
X62195Y11926D01*
X62141Y11908D01*
X62082Y11890D01*
X62020Y11875D01*
X61955Y11868D01*
X61886Y11861D01*
X61813Y11857D01*
X61773D01*
X61744Y11861D01*
X61711D01*
X61671Y11865D01*
X61627Y11872D01*
X61576Y11879D01*
X61471Y11897D01*
X61362Y11926D01*
X61252Y11966D01*
X61201Y11992D01*
X61150Y12021D01*
X61147Y12025D01*
X61140Y12028D01*
X61125Y12039D01*
X61110Y12054D01*
X61089Y12068D01*
X61063Y12090D01*
X61034Y12116D01*
X61005Y12145D01*
X60976Y12178D01*
X60943Y12210D01*
X60877Y12294D01*
X60816Y12392D01*
X60761Y12502D01*
Y12505D01*
X60754Y12516D01*
X60750Y12534D01*
X60739Y12556D01*
X60732Y12585D01*
X60721Y12622D01*
X60706Y12662D01*
X60695Y12705D01*
X60685Y12753D01*
X60670Y12807D01*
X60652Y12920D01*
X60637Y13048D01*
X60630Y13179D01*
Y13182D01*
Y13197D01*
Y13219D01*
X60634Y13244D01*
Y13281D01*
X60637Y13317D01*
X60641Y13364D01*
X60648Y13412D01*
X60666Y13517D01*
X60692Y13634D01*
X60728Y13750D01*
X60779Y13863D01*
X60783Y13867D01*
X60786Y13878D01*
X60794Y13892D01*
X60808Y13910D01*
X60823Y13936D01*
X60841Y13965D01*
X60888Y14030D01*
X60950Y14103D01*
X61023Y14176D01*
X61107Y14249D01*
X61205Y14311D01*
X61209Y14314D01*
X61220Y14318D01*
X61234Y14325D01*
X61252Y14336D01*
X61282Y14347D01*
X61311Y14358D01*
X61347Y14373D01*
X61387Y14387D01*
X61431Y14402D01*
X61478Y14416D01*
X61580Y14438D01*
X61696Y14456D01*
X61817Y14464D01*
X61853D01*
X61878Y14460D01*
D02*
G37*
G36*
X64306Y11901D02*
X63997D01*
Y13870D01*
X63993Y13867D01*
X63975Y13852D01*
X63953Y13830D01*
X63917Y13805D01*
X63877Y13772D01*
X63826Y13736D01*
X63768Y13695D01*
X63702Y13656D01*
X63698D01*
X63695Y13652D01*
X63673Y13637D01*
X63637Y13619D01*
X63593Y13597D01*
X63542Y13572D01*
X63487Y13546D01*
X63433Y13521D01*
X63378Y13499D01*
Y13797D01*
X63382D01*
X63389Y13805D01*
X63404Y13808D01*
X63422Y13819D01*
X63444Y13830D01*
X63469Y13845D01*
X63531Y13881D01*
X63604Y13921D01*
X63677Y13972D01*
X63753Y14030D01*
X63829Y14092D01*
X63833Y14096D01*
X63837Y14099D01*
X63848Y14110D01*
X63862Y14121D01*
X63895Y14158D01*
X63939Y14201D01*
X63982Y14252D01*
X64030Y14311D01*
X64070Y14369D01*
X64106Y14431D01*
X64306D01*
Y11901D01*
D02*
G37*
G36*
X65995Y14427D02*
X66043Y14420D01*
X66097Y14409D01*
X66155Y14394D01*
X66217Y14376D01*
X66276Y14347D01*
X66279D01*
X66283Y14343D01*
X66301Y14333D01*
X66330Y14314D01*
X66367Y14289D01*
X66407Y14252D01*
X66450Y14212D01*
X66490Y14165D01*
X66530Y14110D01*
X66534Y14103D01*
X66549Y14085D01*
X66563Y14052D01*
X66589Y14005D01*
X66610Y13950D01*
X66640Y13888D01*
X66665Y13816D01*
X66687Y13736D01*
Y13732D01*
X66690Y13725D01*
X66694Y13714D01*
X66698Y13695D01*
X66701Y13674D01*
X66705Y13648D01*
X66712Y13615D01*
X66716Y13579D01*
X66723Y13539D01*
X66727Y13495D01*
X66731Y13444D01*
X66738Y13393D01*
X66742Y13335D01*
Y13277D01*
X66745Y13211D01*
Y13142D01*
Y13139D01*
Y13124D01*
Y13099D01*
Y13069D01*
X66742Y13029D01*
Y12986D01*
X66738Y12938D01*
X66734Y12887D01*
X66723Y12771D01*
X66705Y12651D01*
X66683Y12534D01*
X66669Y12480D01*
X66650Y12425D01*
Y12421D01*
X66647Y12414D01*
X66640Y12400D01*
X66632Y12382D01*
X66625Y12356D01*
X66610Y12331D01*
X66581Y12269D01*
X66545Y12203D01*
X66498Y12130D01*
X66443Y12065D01*
X66378Y12003D01*
X66374D01*
X66370Y11996D01*
X66359Y11988D01*
X66345Y11981D01*
X66326Y11970D01*
X66308Y11956D01*
X66254Y11930D01*
X66188Y11905D01*
X66112Y11879D01*
X66021Y11865D01*
X65922Y11857D01*
X65886D01*
X65861Y11861D01*
X65832Y11865D01*
X65795Y11872D01*
X65755Y11879D01*
X65711Y11890D01*
X65668Y11905D01*
X65620Y11919D01*
X65573Y11941D01*
X65526Y11966D01*
X65478Y11996D01*
X65431Y12032D01*
X65387Y12072D01*
X65347Y12116D01*
X65344Y12119D01*
X65336Y12130D01*
X65325Y12149D01*
X65307Y12178D01*
X65289Y12210D01*
X65271Y12254D01*
X65245Y12305D01*
X65224Y12363D01*
X65202Y12429D01*
X65180Y12505D01*
X65158Y12589D01*
X65140Y12684D01*
X65122Y12786D01*
X65111Y12895D01*
X65104Y13015D01*
X65100Y13142D01*
Y13146D01*
Y13160D01*
Y13186D01*
Y13215D01*
X65104Y13255D01*
Y13299D01*
X65107Y13346D01*
X65111Y13401D01*
X65122Y13513D01*
X65140Y13634D01*
X65162Y13754D01*
X65176Y13808D01*
X65191Y13863D01*
Y13867D01*
X65194Y13874D01*
X65202Y13888D01*
X65209Y13907D01*
X65216Y13932D01*
X65231Y13958D01*
X65260Y14019D01*
X65296Y14085D01*
X65344Y14154D01*
X65398Y14223D01*
X65464Y14281D01*
X65468D01*
X65471Y14289D01*
X65482Y14296D01*
X65497Y14303D01*
X65515Y14318D01*
X65537Y14329D01*
X65591Y14358D01*
X65657Y14383D01*
X65733Y14409D01*
X65824Y14424D01*
X65922Y14431D01*
X65955D01*
X65995Y14427D01*
D02*
G37*
G36*
X379349Y-138861D02*
X379396D01*
X379451Y-138865D01*
X379505Y-138872D01*
X379629Y-138883D01*
X379760Y-138901D01*
X379884Y-138927D01*
X379946Y-138945D01*
X380000Y-138963D01*
X380004D01*
X380011Y-138967D01*
X380026Y-138974D01*
X380047Y-138981D01*
X380069Y-138992D01*
X380099Y-139007D01*
X380160Y-139043D01*
X380229Y-139087D01*
X380302Y-139138D01*
X380371Y-139204D01*
X380433Y-139276D01*
Y-139280D01*
X380441Y-139287D01*
X380448Y-139298D01*
X380455Y-139313D01*
X380466Y-139335D01*
X380481Y-139356D01*
X380495Y-139385D01*
X380506Y-139415D01*
X380535Y-139484D01*
X380561Y-139567D01*
X380575Y-139658D01*
X380583Y-139760D01*
Y-139790D01*
X380579Y-139808D01*
Y-139833D01*
X380575Y-139862D01*
X380561Y-139931D01*
X380543Y-140008D01*
X380514Y-140088D01*
X380473Y-140168D01*
X380448Y-140208D01*
X380419Y-140245D01*
X380415Y-140248D01*
X380412Y-140252D01*
X380401Y-140263D01*
X380390Y-140274D01*
X380371Y-140288D01*
X380350Y-140306D01*
X380299Y-140343D01*
X380233Y-140379D01*
X380153Y-140416D01*
X380062Y-140445D01*
X379957Y-140467D01*
X379931Y-140168D01*
X379935D01*
X379942Y-140164D01*
X379949D01*
X379964Y-140161D01*
X380004Y-140150D01*
X380047Y-140135D01*
X380099Y-140117D01*
X380149Y-140092D01*
X380197Y-140063D01*
X380237Y-140026D01*
X380241Y-140023D01*
X380251Y-140008D01*
X380266Y-139982D01*
X380280Y-139953D01*
X380299Y-139913D01*
X380313Y-139866D01*
X380324Y-139811D01*
X380328Y-139753D01*
Y-139728D01*
X380324Y-139702D01*
X380321Y-139670D01*
X380313Y-139629D01*
X380302Y-139589D01*
X380288Y-139546D01*
X380266Y-139506D01*
X380262Y-139502D01*
X380255Y-139488D01*
X380241Y-139466D01*
X380219Y-139444D01*
X380193Y-139415D01*
X380164Y-139385D01*
X380131Y-139356D01*
X380091Y-139327D01*
X380088Y-139324D01*
X380069Y-139316D01*
X380044Y-139302D01*
X380011Y-139287D01*
X379967Y-139269D01*
X379917Y-139251D01*
X379858Y-139233D01*
X379793Y-139215D01*
X379789D01*
X379785Y-139211D01*
X379774D01*
X379760Y-139207D01*
X379724Y-139200D01*
X379676Y-139189D01*
X379618Y-139182D01*
X379556Y-139174D01*
X379487Y-139171D01*
X379414Y-139167D01*
X379411D01*
X379400D01*
X379381D01*
X379352D01*
X379360Y-139171D01*
X379378Y-139185D01*
X379403Y-139207D01*
X379440Y-139233D01*
X379476Y-139269D01*
X379516Y-139313D01*
X379556Y-139364D01*
X379592Y-139422D01*
X379596Y-139429D01*
X379607Y-139451D01*
X379622Y-139484D01*
X379636Y-139524D01*
X379654Y-139578D01*
X379669Y-139637D01*
X379680Y-139702D01*
X379683Y-139771D01*
Y-139801D01*
X379680Y-139822D01*
X379676Y-139851D01*
X379673Y-139881D01*
X379665Y-139917D01*
X379654Y-139953D01*
X379629Y-140037D01*
X379611Y-140081D01*
X379589Y-140124D01*
X379563Y-140172D01*
X379531Y-140216D01*
X379498Y-140259D01*
X379458Y-140299D01*
X379454Y-140303D01*
X379447Y-140310D01*
X379436Y-140317D01*
X379418Y-140332D01*
X379392Y-140350D01*
X379367Y-140368D01*
X379334Y-140386D01*
X379298Y-140405D01*
X379258Y-140427D01*
X379214Y-140445D01*
X379163Y-140463D01*
X379112Y-140481D01*
X379054Y-140496D01*
X378992Y-140503D01*
X378930Y-140510D01*
X378861Y-140514D01*
X378857D01*
X378843D01*
X378824D01*
X378799Y-140510D01*
X378766Y-140507D01*
X378726Y-140503D01*
X378686Y-140496D01*
X378639Y-140485D01*
X378544Y-140459D01*
X378493Y-140441D01*
X378439Y-140419D01*
X378388Y-140394D01*
X378340Y-140361D01*
X378289Y-140328D01*
X378246Y-140288D01*
X378242Y-140285D01*
X378235Y-140277D01*
X378224Y-140266D01*
X378209Y-140248D01*
X378191Y-140226D01*
X378169Y-140197D01*
X378151Y-140168D01*
X378126Y-140132D01*
X378104Y-140095D01*
X378086Y-140052D01*
X378046Y-139953D01*
X378031Y-139902D01*
X378020Y-139844D01*
X378013Y-139786D01*
X378009Y-139724D01*
Y-139699D01*
X378013Y-139680D01*
Y-139662D01*
X378016Y-139637D01*
X378027Y-139575D01*
X378042Y-139506D01*
X378067Y-139429D01*
X378100Y-139353D01*
X378144Y-139276D01*
Y-139273D01*
X378151Y-139269D01*
X378158Y-139258D01*
X378169Y-139244D01*
X378198Y-139207D01*
X378239Y-139160D01*
X378293Y-139112D01*
X378359Y-139058D01*
X378435Y-139011D01*
X378522Y-138967D01*
X378526D01*
X378533Y-138963D01*
X378548Y-138956D01*
X378566Y-138949D01*
X378591Y-138942D01*
X378624Y-138930D01*
X378661Y-138923D01*
X378701Y-138912D01*
X378748Y-138901D01*
X378803Y-138891D01*
X378861Y-138883D01*
X378923Y-138876D01*
X378992Y-138869D01*
X379065Y-138861D01*
X379145Y-138858D01*
X379228D01*
X379232D01*
X379250D01*
X379276D01*
X379309D01*
X379349Y-138861D01*
D02*
G37*
G36*
X380539Y-141617D02*
X378570D01*
X378573Y-141621D01*
X378588Y-141639D01*
X378610Y-141660D01*
X378635Y-141697D01*
X378668Y-141737D01*
X378704Y-141788D01*
X378744Y-141846D01*
X378784Y-141912D01*
Y-141915D01*
X378788Y-141919D01*
X378803Y-141941D01*
X378821Y-141977D01*
X378843Y-142021D01*
X378868Y-142072D01*
X378894Y-142127D01*
X378919Y-142181D01*
X378941Y-142236D01*
X378643D01*
Y-142232D01*
X378635Y-142225D01*
X378632Y-142210D01*
X378621Y-142192D01*
X378610Y-142170D01*
X378595Y-142145D01*
X378559Y-142083D01*
X378519Y-142010D01*
X378468Y-141937D01*
X378410Y-141861D01*
X378348Y-141784D01*
X378344Y-141781D01*
X378340Y-141777D01*
X378329Y-141766D01*
X378319Y-141752D01*
X378282Y-141719D01*
X378239Y-141675D01*
X378187Y-141631D01*
X378129Y-141584D01*
X378071Y-141544D01*
X378009Y-141508D01*
Y-141307D01*
X380539D01*
Y-141617D01*
D02*
G37*
G36*
X379571Y-142905D02*
X379607D01*
X379651Y-142909D01*
X379695Y-142913D01*
X379793Y-142924D01*
X379895Y-142938D01*
X379993Y-142960D01*
X380040Y-142975D01*
X380084Y-142989D01*
X380088D01*
X380095Y-142993D01*
X380106Y-143000D01*
X380120Y-143007D01*
X380160Y-143029D01*
X380211Y-143062D01*
X380270Y-143106D01*
X380328Y-143157D01*
X380390Y-143222D01*
X380444Y-143302D01*
Y-143306D01*
X380452Y-143313D01*
X380455Y-143324D01*
X380466Y-143342D01*
X380477Y-143364D01*
X380488Y-143393D01*
X380499Y-143422D01*
X380514Y-143459D01*
X380528Y-143499D01*
X380539Y-143542D01*
X380550Y-143590D01*
X380561Y-143644D01*
X380568Y-143699D01*
X380575Y-143757D01*
X380583Y-143888D01*
Y-143921D01*
X380579Y-143947D01*
Y-143976D01*
X380575Y-144012D01*
X380572Y-144052D01*
X380568Y-144092D01*
X380554Y-144183D01*
X380532Y-144281D01*
X380503Y-144376D01*
X380463Y-144467D01*
Y-144471D01*
X380455Y-144478D01*
X380448Y-144489D01*
X380441Y-144503D01*
X380412Y-144543D01*
X380371Y-144591D01*
X380321Y-144645D01*
X380262Y-144696D01*
X380189Y-144747D01*
X380109Y-144787D01*
X380106D01*
X380099Y-144791D01*
X380084Y-144795D01*
X380066Y-144802D01*
X380044Y-144809D01*
X380015Y-144816D01*
X379982Y-144827D01*
X379942Y-144835D01*
X379898Y-144842D01*
X379851Y-144853D01*
X379800Y-144860D01*
X379745Y-144867D01*
X379683Y-144875D01*
X379618Y-144878D01*
X379549Y-144882D01*
X379476D01*
X378020D01*
Y-144547D01*
X379476D01*
X379480D01*
X379491D01*
X379509D01*
X379531D01*
X379556Y-144543D01*
X379589D01*
X379658Y-144540D01*
X379738Y-144533D01*
X379818Y-144522D01*
X379895Y-144507D01*
X379927Y-144500D01*
X379960Y-144489D01*
X379967Y-144485D01*
X379986Y-144478D01*
X380011Y-144460D01*
X380047Y-144438D01*
X380084Y-144412D01*
X380124Y-144376D01*
X380164Y-144332D01*
X380197Y-144281D01*
X380200Y-144274D01*
X380211Y-144256D01*
X380222Y-144223D01*
X380237Y-144179D01*
X380255Y-144129D01*
X380266Y-144063D01*
X380277Y-143994D01*
X380280Y-143917D01*
Y-143881D01*
X380277Y-143859D01*
Y-143826D01*
X380273Y-143794D01*
X380259Y-143713D01*
X380241Y-143626D01*
X380211Y-143542D01*
X380171Y-143462D01*
X380146Y-143426D01*
X380117Y-143393D01*
X380113Y-143389D01*
X380109Y-143386D01*
X380099Y-143379D01*
X380084Y-143368D01*
X380062Y-143357D01*
X380040Y-143342D01*
X380008Y-143328D01*
X379975Y-143313D01*
X379935Y-143298D01*
X379887Y-143288D01*
X379833Y-143273D01*
X379774Y-143262D01*
X379709Y-143251D01*
X379640Y-143244D01*
X379560Y-143237D01*
X379476D01*
X378020D01*
Y-142902D01*
X379476D01*
X379480D01*
X379494D01*
X379512D01*
X379538D01*
X379571Y-142905D01*
D02*
G37*
G36*
X57453Y-49749D02*
Y-49753D01*
Y-49767D01*
Y-49785D01*
Y-49811D01*
X57449Y-49843D01*
Y-49880D01*
X57445Y-49924D01*
X57442Y-49967D01*
X57431Y-50066D01*
X57416Y-50168D01*
X57394Y-50266D01*
X57380Y-50313D01*
X57365Y-50357D01*
Y-50360D01*
X57362Y-50368D01*
X57354Y-50379D01*
X57347Y-50393D01*
X57325Y-50433D01*
X57292Y-50484D01*
X57249Y-50542D01*
X57198Y-50601D01*
X57132Y-50662D01*
X57052Y-50717D01*
X57048D01*
X57041Y-50724D01*
X57030Y-50728D01*
X57012Y-50739D01*
X56990Y-50750D01*
X56961Y-50761D01*
X56932Y-50772D01*
X56896Y-50786D01*
X56856Y-50801D01*
X56812Y-50812D01*
X56765Y-50823D01*
X56710Y-50834D01*
X56655Y-50841D01*
X56597Y-50848D01*
X56466Y-50855D01*
X56433D01*
X56408Y-50852D01*
X56379D01*
X56342Y-50848D01*
X56302Y-50845D01*
X56262Y-50841D01*
X56171Y-50826D01*
X56073Y-50805D01*
X55978Y-50775D01*
X55887Y-50735D01*
X55884D01*
X55876Y-50728D01*
X55866Y-50721D01*
X55851Y-50713D01*
X55811Y-50684D01*
X55764Y-50644D01*
X55709Y-50593D01*
X55658Y-50535D01*
X55607Y-50462D01*
X55567Y-50382D01*
Y-50379D01*
X55563Y-50371D01*
X55560Y-50357D01*
X55553Y-50339D01*
X55545Y-50317D01*
X55538Y-50288D01*
X55527Y-50255D01*
X55520Y-50215D01*
X55512Y-50171D01*
X55502Y-50124D01*
X55494Y-50073D01*
X55487Y-50018D01*
X55480Y-49956D01*
X55476Y-49891D01*
X55472Y-49822D01*
Y-49749D01*
Y-48293D01*
X55807D01*
Y-49749D01*
Y-49753D01*
Y-49763D01*
Y-49782D01*
Y-49804D01*
X55811Y-49829D01*
Y-49862D01*
X55815Y-49931D01*
X55822Y-50011D01*
X55833Y-50091D01*
X55847Y-50168D01*
X55855Y-50200D01*
X55866Y-50233D01*
X55869Y-50240D01*
X55876Y-50258D01*
X55895Y-50284D01*
X55917Y-50320D01*
X55942Y-50357D01*
X55978Y-50397D01*
X56022Y-50437D01*
X56073Y-50470D01*
X56080Y-50473D01*
X56099Y-50484D01*
X56131Y-50495D01*
X56175Y-50510D01*
X56226Y-50528D01*
X56291Y-50539D01*
X56361Y-50550D01*
X56437Y-50553D01*
X56473D01*
X56495Y-50550D01*
X56528D01*
X56561Y-50546D01*
X56641Y-50532D01*
X56728Y-50513D01*
X56812Y-50484D01*
X56892Y-50444D01*
X56928Y-50419D01*
X56961Y-50389D01*
X56965Y-50386D01*
X56968Y-50382D01*
X56976Y-50371D01*
X56987Y-50357D01*
X56998Y-50335D01*
X57012Y-50313D01*
X57027Y-50280D01*
X57041Y-50248D01*
X57056Y-50208D01*
X57067Y-50160D01*
X57081Y-50106D01*
X57092Y-50047D01*
X57103Y-49982D01*
X57110Y-49913D01*
X57118Y-49833D01*
Y-49749D01*
Y-48293D01*
X57453D01*
Y-49749D01*
D02*
G37*
G36*
X61493Y-48570D02*
X61489Y-48573D01*
X61482Y-48580D01*
X61467Y-48595D01*
X61453Y-48617D01*
X61431Y-48642D01*
X61402Y-48671D01*
X61373Y-48708D01*
X61340Y-48752D01*
X61307Y-48795D01*
X61267Y-48846D01*
X61227Y-48904D01*
X61187Y-48963D01*
X61143Y-49028D01*
X61100Y-49097D01*
X61056Y-49174D01*
X61013Y-49250D01*
X61009Y-49254D01*
X61002Y-49268D01*
X60991Y-49290D01*
X60972Y-49323D01*
X60954Y-49363D01*
X60932Y-49407D01*
X60907Y-49458D01*
X60881Y-49516D01*
X60852Y-49581D01*
X60820Y-49647D01*
X60790Y-49720D01*
X60761Y-49796D01*
X60703Y-49953D01*
X60649Y-50120D01*
Y-50124D01*
X60645Y-50135D01*
X60641Y-50153D01*
X60634Y-50175D01*
X60627Y-50204D01*
X60619Y-50240D01*
X60608Y-50280D01*
X60601Y-50324D01*
X60590Y-50375D01*
X60579Y-50430D01*
X60561Y-50546D01*
X60543Y-50673D01*
X60532Y-50812D01*
X60215D01*
Y-50808D01*
Y-50797D01*
Y-50783D01*
X60219Y-50761D01*
Y-50732D01*
X60223Y-50695D01*
X60226Y-50655D01*
X60230Y-50612D01*
X60237Y-50561D01*
X60244Y-50510D01*
X60255Y-50448D01*
X60266Y-50386D01*
X60277Y-50320D01*
X60292Y-50248D01*
X60328Y-50098D01*
Y-50095D01*
X60332Y-50080D01*
X60339Y-50058D01*
X60350Y-50025D01*
X60361Y-49989D01*
X60375Y-49945D01*
X60390Y-49894D01*
X60412Y-49840D01*
X60434Y-49778D01*
X60456Y-49716D01*
X60510Y-49578D01*
X60576Y-49432D01*
X60649Y-49287D01*
X60652Y-49283D01*
X60659Y-49268D01*
X60670Y-49250D01*
X60685Y-49221D01*
X60703Y-49188D01*
X60729Y-49148D01*
X60754Y-49105D01*
X60783Y-49057D01*
X60852Y-48952D01*
X60925Y-48842D01*
X61009Y-48730D01*
X61096Y-48624D01*
X59862D01*
Y-48326D01*
X61493D01*
Y-48570D01*
D02*
G37*
G36*
X59047Y-50812D02*
X58737D01*
Y-48842D01*
X58734Y-48846D01*
X58716Y-48861D01*
X58694Y-48882D01*
X58657Y-48908D01*
X58617Y-48941D01*
X58566Y-48977D01*
X58508Y-49017D01*
X58443Y-49057D01*
X58439D01*
X58435Y-49061D01*
X58413Y-49075D01*
X58377Y-49094D01*
X58333Y-49115D01*
X58283Y-49141D01*
X58228Y-49167D01*
X58173Y-49192D01*
X58119Y-49214D01*
Y-48915D01*
X58122D01*
X58130Y-48908D01*
X58144Y-48904D01*
X58162Y-48893D01*
X58184Y-48882D01*
X58210Y-48868D01*
X58272Y-48832D01*
X58344Y-48792D01*
X58417Y-48741D01*
X58494Y-48682D01*
X58570Y-48621D01*
X58574Y-48617D01*
X58577Y-48613D01*
X58588Y-48602D01*
X58603Y-48591D01*
X58636Y-48555D01*
X58679Y-48511D01*
X58723Y-48460D01*
X58770Y-48402D01*
X58810Y-48344D01*
X58847Y-48282D01*
X59047D01*
Y-50812D01*
D02*
G37*
G36*
X29595Y-18901D02*
X29628D01*
X29668Y-18905D01*
X29711Y-18912D01*
X29762Y-18920D01*
X29868Y-18938D01*
X29977Y-18967D01*
X30086Y-19007D01*
X30137Y-19032D01*
X30188Y-19061D01*
X30192Y-19065D01*
X30199Y-19069D01*
X30214Y-19080D01*
X30228Y-19094D01*
X30250Y-19109D01*
X30275Y-19131D01*
X30305Y-19156D01*
X30334Y-19185D01*
X30363Y-19218D01*
X30396Y-19251D01*
X30461Y-19334D01*
X30523Y-19433D01*
X30578Y-19542D01*
Y-19545D01*
X30585Y-19557D01*
X30589Y-19575D01*
X30599Y-19597D01*
X30607Y-19626D01*
X30618Y-19662D01*
X30632Y-19702D01*
X30643Y-19746D01*
X30654Y-19793D01*
X30669Y-19848D01*
X30687Y-19961D01*
X30701Y-20088D01*
X30709Y-20219D01*
Y-20223D01*
Y-20237D01*
Y-20259D01*
X30705Y-20285D01*
Y-20321D01*
X30701Y-20357D01*
X30698Y-20405D01*
X30691Y-20452D01*
X30672Y-20558D01*
X30647Y-20674D01*
X30610Y-20790D01*
X30560Y-20903D01*
X30556Y-20907D01*
X30552Y-20918D01*
X30545Y-20932D01*
X30530Y-20951D01*
X30516Y-20976D01*
X30498Y-21005D01*
X30450Y-21071D01*
X30388Y-21144D01*
X30316Y-21216D01*
X30232Y-21289D01*
X30134Y-21351D01*
X30130Y-21355D01*
X30119Y-21358D01*
X30105Y-21365D01*
X30086Y-21376D01*
X30057Y-21387D01*
X30028Y-21398D01*
X29992Y-21413D01*
X29952Y-21427D01*
X29908Y-21442D01*
X29861Y-21456D01*
X29759Y-21478D01*
X29642Y-21497D01*
X29522Y-21504D01*
X29486D01*
X29460Y-21500D01*
X29427Y-21497D01*
X29387Y-21493D01*
X29347Y-21489D01*
X29300Y-21478D01*
X29202Y-21456D01*
X29092Y-21424D01*
X29038Y-21402D01*
X28987Y-21376D01*
X28936Y-21344D01*
X28885Y-21311D01*
X28881Y-21307D01*
X28874Y-21304D01*
X28860Y-21293D01*
X28841Y-21274D01*
X28823Y-21256D01*
X28798Y-21231D01*
X28772Y-21202D01*
X28743Y-21173D01*
X28714Y-21136D01*
X28685Y-21092D01*
X28652Y-21049D01*
X28623Y-21001D01*
X28598Y-20947D01*
X28568Y-20892D01*
X28547Y-20834D01*
X28525Y-20769D01*
X28852Y-20692D01*
Y-20696D01*
X28856Y-20703D01*
X28863Y-20718D01*
X28870Y-20736D01*
X28878Y-20758D01*
X28889Y-20787D01*
X28918Y-20845D01*
X28954Y-20910D01*
X28998Y-20976D01*
X29052Y-21038D01*
X29111Y-21092D01*
X29118Y-21100D01*
X29140Y-21114D01*
X29176Y-21133D01*
X29224Y-21158D01*
X29285Y-21180D01*
X29355Y-21202D01*
X29438Y-21216D01*
X29529Y-21220D01*
X29559D01*
X29577Y-21216D01*
X29602D01*
X29631Y-21213D01*
X29700Y-21202D01*
X29777Y-21187D01*
X29857Y-21162D01*
X29941Y-21125D01*
X30017Y-21078D01*
X30021D01*
X30024Y-21071D01*
X30050Y-21053D01*
X30083Y-21023D01*
X30123Y-20980D01*
X30170Y-20925D01*
X30214Y-20863D01*
X30254Y-20787D01*
X30290Y-20703D01*
Y-20699D01*
X30294Y-20692D01*
X30297Y-20681D01*
X30301Y-20663D01*
X30308Y-20641D01*
X30316Y-20616D01*
X30327Y-20554D01*
X30341Y-20481D01*
X30356Y-20401D01*
X30363Y-20314D01*
X30367Y-20219D01*
Y-20215D01*
Y-20204D01*
Y-20186D01*
Y-20164D01*
X30363Y-20139D01*
Y-20106D01*
X30359Y-20070D01*
X30356Y-20030D01*
X30345Y-19942D01*
X30327Y-19848D01*
X30305Y-19753D01*
X30275Y-19658D01*
Y-19655D01*
X30272Y-19647D01*
X30265Y-19636D01*
X30257Y-19618D01*
X30235Y-19575D01*
X30203Y-19524D01*
X30163Y-19466D01*
X30112Y-19404D01*
X30053Y-19349D01*
X29984Y-19298D01*
X29981D01*
X29973Y-19294D01*
X29963Y-19287D01*
X29948Y-19280D01*
X29930Y-19273D01*
X29908Y-19262D01*
X29857Y-19240D01*
X29791Y-19218D01*
X29719Y-19200D01*
X29638Y-19185D01*
X29555Y-19182D01*
X29529D01*
X29507Y-19185D01*
X29482D01*
X29456Y-19189D01*
X29391Y-19203D01*
X29315Y-19222D01*
X29238Y-19251D01*
X29158Y-19291D01*
X29118Y-19313D01*
X29082Y-19342D01*
X29078Y-19345D01*
X29074Y-19349D01*
X29063Y-19360D01*
X29049Y-19371D01*
X29034Y-19389D01*
X29016Y-19411D01*
X28994Y-19433D01*
X28976Y-19462D01*
X28954Y-19495D01*
X28929Y-19531D01*
X28907Y-19567D01*
X28885Y-19611D01*
X28867Y-19658D01*
X28849Y-19709D01*
X28831Y-19764D01*
X28816Y-19822D01*
X28481Y-19738D01*
Y-19735D01*
X28485Y-19720D01*
X28492Y-19698D01*
X28503Y-19669D01*
X28514Y-19636D01*
X28528Y-19597D01*
X28547Y-19553D01*
X28568Y-19505D01*
X28619Y-19404D01*
X28685Y-19302D01*
X28725Y-19251D01*
X28765Y-19200D01*
X28809Y-19156D01*
X28860Y-19112D01*
X28863Y-19109D01*
X28870Y-19101D01*
X28889Y-19094D01*
X28907Y-19080D01*
X28936Y-19061D01*
X28965Y-19043D01*
X29005Y-19025D01*
X29045Y-19007D01*
X29092Y-18985D01*
X29144Y-18967D01*
X29198Y-18949D01*
X29256Y-18930D01*
X29318Y-18916D01*
X29384Y-18909D01*
X29453Y-18901D01*
X29526Y-18898D01*
X29566D01*
X29595Y-18901D01*
D02*
G37*
G36*
X27342Y-20910D02*
X27345Y-20907D01*
X27363Y-20892D01*
X27385Y-20870D01*
X27422Y-20845D01*
X27462Y-20812D01*
X27513Y-20776D01*
X27571Y-20736D01*
X27637Y-20696D01*
X27640D01*
X27644Y-20692D01*
X27666Y-20678D01*
X27702Y-20659D01*
X27746Y-20638D01*
X27797Y-20612D01*
X27851Y-20587D01*
X27906Y-20561D01*
X27961Y-20539D01*
Y-20838D01*
X27957D01*
X27950Y-20845D01*
X27935Y-20849D01*
X27917Y-20860D01*
X27895Y-20870D01*
X27869Y-20885D01*
X27808Y-20921D01*
X27735Y-20962D01*
X27662Y-21012D01*
X27586Y-21071D01*
X27509Y-21133D01*
X27505Y-21136D01*
X27502Y-21140D01*
X27491Y-21151D01*
X27476Y-21162D01*
X27444Y-21198D01*
X27400Y-21242D01*
X27356Y-21293D01*
X27309Y-21351D01*
X27269Y-21409D01*
X27233Y-21471D01*
X27032D01*
Y-18941D01*
X27342D01*
Y-20910D01*
D02*
G37*
G36*
X25383D02*
X25387Y-20907D01*
X25405Y-20892D01*
X25427Y-20870D01*
X25464Y-20845D01*
X25504Y-20812D01*
X25554Y-20776D01*
X25613Y-20736D01*
X25678Y-20696D01*
X25682D01*
X25686Y-20692D01*
X25707Y-20678D01*
X25744Y-20659D01*
X25787Y-20638D01*
X25838Y-20612D01*
X25893Y-20587D01*
X25948Y-20561D01*
X26002Y-20539D01*
Y-20838D01*
X25999D01*
X25991Y-20845D01*
X25977Y-20849D01*
X25958Y-20860D01*
X25937Y-20870D01*
X25911Y-20885D01*
X25849Y-20921D01*
X25776Y-20962D01*
X25704Y-21012D01*
X25627Y-21071D01*
X25551Y-21133D01*
X25547Y-21136D01*
X25543Y-21140D01*
X25533Y-21151D01*
X25518Y-21162D01*
X25485Y-21198D01*
X25442Y-21242D01*
X25398Y-21293D01*
X25351Y-21351D01*
X25311Y-21409D01*
X25274Y-21471D01*
X25074D01*
Y-18941D01*
X25383D01*
Y-20910D01*
D02*
G37*
G36*
X442510Y-111204D02*
X442532D01*
X442590Y-111215D01*
X442659Y-111226D01*
X442732Y-111244D01*
X442812Y-111270D01*
X442888Y-111306D01*
X442892D01*
X442896Y-111310D01*
X442907Y-111317D01*
X442921Y-111324D01*
X442958Y-111346D01*
X443005Y-111379D01*
X443056Y-111419D01*
X443107Y-111466D01*
X443158Y-111524D01*
X443202Y-111586D01*
Y-111590D01*
X443205Y-111593D01*
X443213Y-111604D01*
X443216Y-111619D01*
X443234Y-111655D01*
X443253Y-111703D01*
X443274Y-111765D01*
X443289Y-111834D01*
X443303Y-111910D01*
X443307Y-111994D01*
Y-112012D01*
X443303Y-112030D01*
Y-112059D01*
X443300Y-112092D01*
X443293Y-112129D01*
X443282Y-112172D01*
X443271Y-112216D01*
X443256Y-112267D01*
X443238Y-112318D01*
X443216Y-112369D01*
X443187Y-112424D01*
X443154Y-112474D01*
X443118Y-112525D01*
X443074Y-112576D01*
X443023Y-112624D01*
X443020Y-112627D01*
X443009Y-112635D01*
X442994Y-112645D01*
X442969Y-112660D01*
X442936Y-112682D01*
X442899Y-112700D01*
X442852Y-112722D01*
X442801Y-112744D01*
X442739Y-112769D01*
X442670Y-112791D01*
X442594Y-112809D01*
X442510Y-112828D01*
X442415Y-112846D01*
X442313Y-112857D01*
X442204Y-112864D01*
X442088Y-112867D01*
X442084D01*
X442080D01*
X442069D01*
X442055D01*
X442019Y-112864D01*
X441968D01*
X441909Y-112860D01*
X441840Y-112853D01*
X441764Y-112846D01*
X441680Y-112835D01*
X441596Y-112820D01*
X441505Y-112802D01*
X441418Y-112780D01*
X441331Y-112755D01*
X441247Y-112722D01*
X441167Y-112686D01*
X441090Y-112645D01*
X441025Y-112598D01*
X441021Y-112594D01*
X441014Y-112587D01*
X440999Y-112573D01*
X440977Y-112555D01*
X440956Y-112533D01*
X440934Y-112504D01*
X440905Y-112467D01*
X440879Y-112431D01*
X440854Y-112387D01*
X440825Y-112340D01*
X440803Y-112285D01*
X440777Y-112231D01*
X440759Y-112169D01*
X440745Y-112103D01*
X440737Y-112034D01*
X440734Y-111961D01*
Y-111932D01*
X440737Y-111910D01*
Y-111885D01*
X440741Y-111856D01*
X440756Y-111786D01*
X440774Y-111710D01*
X440803Y-111630D01*
X440846Y-111550D01*
X440872Y-111510D01*
X440901Y-111473D01*
X440905Y-111470D01*
X440908Y-111466D01*
X440919Y-111455D01*
X440930Y-111444D01*
X440948Y-111426D01*
X440970Y-111411D01*
X441021Y-111372D01*
X441087Y-111331D01*
X441167Y-111295D01*
X441258Y-111262D01*
X441360Y-111240D01*
X441385Y-111550D01*
X441382D01*
X441378Y-111554D01*
X441356Y-111557D01*
X441323Y-111568D01*
X441283Y-111583D01*
X441240Y-111597D01*
X441196Y-111619D01*
X441156Y-111644D01*
X441123Y-111670D01*
X441116Y-111677D01*
X441101Y-111692D01*
X441079Y-111717D01*
X441054Y-111754D01*
X441032Y-111801D01*
X441010Y-111852D01*
X440996Y-111914D01*
X440988Y-111979D01*
Y-112005D01*
X440992Y-112034D01*
X440999Y-112067D01*
X441010Y-112110D01*
X441025Y-112154D01*
X441043Y-112198D01*
X441072Y-112241D01*
X441076Y-112249D01*
X441090Y-112267D01*
X441116Y-112292D01*
X441152Y-112325D01*
X441196Y-112362D01*
X441247Y-112402D01*
X441312Y-112438D01*
X441385Y-112474D01*
X441389D01*
X441396Y-112478D01*
X441407Y-112482D01*
X441422Y-112489D01*
X441443Y-112493D01*
X441469Y-112500D01*
X441498Y-112507D01*
X441535Y-112514D01*
X441574Y-112525D01*
X441618Y-112533D01*
X441666Y-112540D01*
X441716Y-112544D01*
X441775Y-112551D01*
X441833Y-112555D01*
X441898Y-112558D01*
X441964D01*
X441960Y-112555D01*
X441938Y-112540D01*
X441909Y-112514D01*
X441873Y-112482D01*
X441829Y-112445D01*
X441789Y-112398D01*
X441749Y-112347D01*
X441713Y-112289D01*
Y-112285D01*
X441709Y-112282D01*
X441698Y-112260D01*
X441687Y-112227D01*
X441669Y-112183D01*
X441655Y-112132D01*
X441644Y-112074D01*
X441633Y-112012D01*
X441629Y-111947D01*
Y-111917D01*
X441633Y-111896D01*
X441636Y-111866D01*
X441640Y-111837D01*
X441647Y-111801D01*
X441658Y-111765D01*
X441684Y-111681D01*
X441702Y-111637D01*
X441727Y-111593D01*
X441753Y-111550D01*
X441782Y-111503D01*
X441818Y-111459D01*
X441858Y-111419D01*
X441862Y-111415D01*
X441869Y-111408D01*
X441880Y-111397D01*
X441898Y-111386D01*
X441924Y-111368D01*
X441949Y-111350D01*
X441982Y-111331D01*
X442019Y-111310D01*
X442059Y-111288D01*
X442102Y-111270D01*
X442153Y-111251D01*
X442204Y-111233D01*
X442259Y-111222D01*
X442321Y-111211D01*
X442383Y-111204D01*
X442448Y-111200D01*
X442452D01*
X442459D01*
X442470D01*
X442488D01*
X442510Y-111204D01*
D02*
G37*
G36*
X441025Y-113162D02*
X441032Y-113170D01*
X441047Y-113184D01*
X441069Y-113199D01*
X441094Y-113221D01*
X441123Y-113250D01*
X441159Y-113279D01*
X441203Y-113312D01*
X441247Y-113344D01*
X441298Y-113384D01*
X441356Y-113425D01*
X441414Y-113464D01*
X441480Y-113508D01*
X441549Y-113552D01*
X441625Y-113595D01*
X441702Y-113639D01*
X441706Y-113643D01*
X441720Y-113650D01*
X441742Y-113661D01*
X441775Y-113679D01*
X441815Y-113698D01*
X441858Y-113719D01*
X441909Y-113745D01*
X441968Y-113770D01*
X442033Y-113799D01*
X442099Y-113832D01*
X442171Y-113861D01*
X442248Y-113890D01*
X442404Y-113949D01*
X442572Y-114003D01*
X442576D01*
X442586Y-114007D01*
X442605Y-114011D01*
X442626Y-114018D01*
X442656Y-114025D01*
X442692Y-114032D01*
X442732Y-114043D01*
X442776Y-114050D01*
X442827Y-114061D01*
X442881Y-114072D01*
X442998Y-114091D01*
X443125Y-114109D01*
X443263Y-114120D01*
Y-114436D01*
X443260D01*
X443249D01*
X443234D01*
X443213Y-114433D01*
X443183D01*
X443147Y-114429D01*
X443107Y-114426D01*
X443063Y-114422D01*
X443012Y-114415D01*
X442961Y-114407D01*
X442899Y-114396D01*
X442838Y-114385D01*
X442772Y-114374D01*
X442699Y-114360D01*
X442550Y-114323D01*
X442546D01*
X442532Y-114320D01*
X442510Y-114313D01*
X442477Y-114302D01*
X442441Y-114291D01*
X442397Y-114276D01*
X442346Y-114262D01*
X442292Y-114240D01*
X442230Y-114218D01*
X442168Y-114196D01*
X442029Y-114141D01*
X441884Y-114076D01*
X441738Y-114003D01*
X441735Y-114000D01*
X441720Y-113992D01*
X441702Y-113981D01*
X441673Y-113967D01*
X441640Y-113949D01*
X441600Y-113923D01*
X441556Y-113898D01*
X441509Y-113868D01*
X441403Y-113799D01*
X441294Y-113727D01*
X441181Y-113643D01*
X441076Y-113556D01*
Y-114789D01*
X440777D01*
Y-113159D01*
X441021D01*
X441025Y-113162D01*
D02*
G37*
G36*
X442485Y-115099D02*
X442506Y-115106D01*
X442535Y-115117D01*
X442568Y-115128D01*
X442608Y-115143D01*
X442652Y-115161D01*
X442699Y-115183D01*
X442801Y-115234D01*
X442903Y-115299D01*
X442954Y-115339D01*
X443005Y-115379D01*
X443049Y-115423D01*
X443092Y-115474D01*
X443096Y-115477D01*
X443103Y-115485D01*
X443111Y-115503D01*
X443125Y-115521D01*
X443143Y-115550D01*
X443161Y-115579D01*
X443180Y-115619D01*
X443198Y-115659D01*
X443220Y-115707D01*
X443238Y-115758D01*
X443256Y-115812D01*
X443274Y-115870D01*
X443289Y-115932D01*
X443296Y-115998D01*
X443303Y-116067D01*
X443307Y-116140D01*
Y-116180D01*
X443303Y-116209D01*
Y-116242D01*
X443300Y-116282D01*
X443293Y-116325D01*
X443285Y-116376D01*
X443267Y-116482D01*
X443238Y-116591D01*
X443198Y-116700D01*
X443173Y-116751D01*
X443143Y-116802D01*
X443140Y-116806D01*
X443136Y-116813D01*
X443125Y-116828D01*
X443111Y-116842D01*
X443096Y-116864D01*
X443074Y-116890D01*
X443049Y-116919D01*
X443020Y-116948D01*
X442987Y-116977D01*
X442954Y-117010D01*
X442870Y-117075D01*
X442772Y-117137D01*
X442663Y-117192D01*
X442659D01*
X442648Y-117199D01*
X442630Y-117203D01*
X442608Y-117214D01*
X442579Y-117221D01*
X442543Y-117232D01*
X442503Y-117246D01*
X442459Y-117257D01*
X442412Y-117268D01*
X442357Y-117283D01*
X442244Y-117301D01*
X442117Y-117316D01*
X441986Y-117323D01*
X441982D01*
X441968D01*
X441946D01*
X441920Y-117319D01*
X441884D01*
X441848Y-117316D01*
X441800Y-117312D01*
X441753Y-117305D01*
X441647Y-117287D01*
X441531Y-117261D01*
X441414Y-117225D01*
X441301Y-117174D01*
X441298Y-117170D01*
X441287Y-117166D01*
X441272Y-117159D01*
X441254Y-117145D01*
X441229Y-117130D01*
X441200Y-117112D01*
X441134Y-117064D01*
X441061Y-117003D01*
X440988Y-116930D01*
X440916Y-116846D01*
X440854Y-116748D01*
X440850Y-116744D01*
X440846Y-116733D01*
X440839Y-116719D01*
X440828Y-116700D01*
X440817Y-116671D01*
X440806Y-116642D01*
X440792Y-116606D01*
X440777Y-116566D01*
X440763Y-116522D01*
X440748Y-116475D01*
X440726Y-116373D01*
X440708Y-116256D01*
X440701Y-116136D01*
Y-116100D01*
X440704Y-116074D01*
X440708Y-116042D01*
X440712Y-116002D01*
X440715Y-115962D01*
X440726Y-115914D01*
X440748Y-115816D01*
X440781Y-115707D01*
X440803Y-115652D01*
X440828Y-115601D01*
X440861Y-115550D01*
X440894Y-115499D01*
X440898Y-115496D01*
X440901Y-115488D01*
X440912Y-115474D01*
X440930Y-115456D01*
X440948Y-115437D01*
X440974Y-115412D01*
X441003Y-115386D01*
X441032Y-115357D01*
X441069Y-115328D01*
X441112Y-115299D01*
X441156Y-115266D01*
X441203Y-115237D01*
X441258Y-115212D01*
X441312Y-115183D01*
X441371Y-115161D01*
X441436Y-115139D01*
X441513Y-115466D01*
X441509D01*
X441502Y-115470D01*
X441487Y-115477D01*
X441469Y-115485D01*
X441447Y-115492D01*
X441418Y-115503D01*
X441360Y-115532D01*
X441294Y-115568D01*
X441229Y-115612D01*
X441167Y-115667D01*
X441112Y-115725D01*
X441105Y-115732D01*
X441090Y-115754D01*
X441072Y-115790D01*
X441047Y-115838D01*
X441025Y-115900D01*
X441003Y-115969D01*
X440988Y-116052D01*
X440985Y-116144D01*
Y-116173D01*
X440988Y-116191D01*
Y-116216D01*
X440992Y-116245D01*
X441003Y-116315D01*
X441018Y-116391D01*
X441043Y-116471D01*
X441079Y-116555D01*
X441127Y-116631D01*
Y-116635D01*
X441134Y-116639D01*
X441152Y-116664D01*
X441181Y-116697D01*
X441225Y-116737D01*
X441280Y-116784D01*
X441341Y-116828D01*
X441418Y-116868D01*
X441502Y-116904D01*
X441505D01*
X441513Y-116908D01*
X441524Y-116912D01*
X441542Y-116915D01*
X441564Y-116922D01*
X441589Y-116930D01*
X441651Y-116941D01*
X441724Y-116955D01*
X441804Y-116970D01*
X441891Y-116977D01*
X441986Y-116981D01*
X441990D01*
X442000D01*
X442019D01*
X442040D01*
X442066Y-116977D01*
X442099D01*
X442135Y-116973D01*
X442175Y-116970D01*
X442262Y-116959D01*
X442357Y-116941D01*
X442452Y-116919D01*
X442546Y-116890D01*
X442550D01*
X442557Y-116886D01*
X442568Y-116879D01*
X442586Y-116872D01*
X442630Y-116850D01*
X442681Y-116817D01*
X442739Y-116777D01*
X442801Y-116726D01*
X442856Y-116668D01*
X442907Y-116598D01*
Y-116595D01*
X442910Y-116588D01*
X442918Y-116577D01*
X442925Y-116562D01*
X442932Y-116544D01*
X442943Y-116522D01*
X442965Y-116471D01*
X442987Y-116406D01*
X443005Y-116333D01*
X443020Y-116253D01*
X443023Y-116169D01*
Y-116144D01*
X443020Y-116122D01*
Y-116096D01*
X443016Y-116071D01*
X443001Y-116005D01*
X442983Y-115929D01*
X442954Y-115852D01*
X442914Y-115772D01*
X442892Y-115732D01*
X442863Y-115696D01*
X442859Y-115692D01*
X442856Y-115689D01*
X442845Y-115678D01*
X442834Y-115663D01*
X442816Y-115648D01*
X442794Y-115630D01*
X442772Y-115608D01*
X442743Y-115590D01*
X442710Y-115568D01*
X442674Y-115543D01*
X442637Y-115521D01*
X442594Y-115499D01*
X442546Y-115481D01*
X442495Y-115463D01*
X442441Y-115445D01*
X442383Y-115430D01*
X442466Y-115095D01*
X442470D01*
X442485Y-115099D01*
D02*
G37*
G36*
X461186Y-122594D02*
X461219Y-122598D01*
X461259Y-122602D01*
X461299Y-122605D01*
X461346Y-122616D01*
X461445Y-122638D01*
X461554Y-122671D01*
X461609Y-122693D01*
X461659Y-122718D01*
X461711Y-122751D01*
X461762Y-122784D01*
X461765Y-122787D01*
X461772Y-122791D01*
X461787Y-122802D01*
X461805Y-122820D01*
X461823Y-122838D01*
X461849Y-122864D01*
X461874Y-122893D01*
X461903Y-122922D01*
X461933Y-122958D01*
X461962Y-123002D01*
X461994Y-123046D01*
X462023Y-123093D01*
X462049Y-123148D01*
X462078Y-123202D01*
X462100Y-123260D01*
X462122Y-123326D01*
X461794Y-123402D01*
Y-123399D01*
X461791Y-123391D01*
X461783Y-123377D01*
X461776Y-123359D01*
X461769Y-123337D01*
X461758Y-123308D01*
X461729Y-123249D01*
X461692Y-123184D01*
X461649Y-123118D01*
X461594Y-123057D01*
X461536Y-123002D01*
X461528Y-122995D01*
X461507Y-122980D01*
X461470Y-122962D01*
X461423Y-122936D01*
X461361Y-122915D01*
X461292Y-122893D01*
X461208Y-122878D01*
X461117Y-122875D01*
X461088D01*
X461070Y-122878D01*
X461044D01*
X461015Y-122882D01*
X460946Y-122893D01*
X460870Y-122907D01*
X460790Y-122933D01*
X460706Y-122969D01*
X460629Y-123017D01*
X460626D01*
X460622Y-123024D01*
X460597Y-123042D01*
X460564Y-123071D01*
X460524Y-123115D01*
X460476Y-123169D01*
X460433Y-123231D01*
X460393Y-123308D01*
X460356Y-123391D01*
Y-123395D01*
X460353Y-123402D01*
X460349Y-123413D01*
X460346Y-123432D01*
X460338Y-123453D01*
X460331Y-123479D01*
X460320Y-123541D01*
X460306Y-123614D01*
X460291Y-123694D01*
X460284Y-123781D01*
X460280Y-123876D01*
Y-123879D01*
Y-123890D01*
Y-123908D01*
Y-123930D01*
X460284Y-123956D01*
Y-123988D01*
X460287Y-124025D01*
X460291Y-124065D01*
X460302Y-124152D01*
X460320Y-124247D01*
X460342Y-124341D01*
X460371Y-124436D01*
Y-124440D01*
X460375Y-124447D01*
X460382Y-124458D01*
X460389Y-124476D01*
X460411Y-124520D01*
X460444Y-124571D01*
X460484Y-124629D01*
X460535Y-124691D01*
X460593Y-124746D01*
X460662Y-124796D01*
X460666D01*
X460673Y-124800D01*
X460684Y-124807D01*
X460699Y-124815D01*
X460717Y-124822D01*
X460739Y-124833D01*
X460790Y-124855D01*
X460855Y-124877D01*
X460928Y-124895D01*
X461008Y-124909D01*
X461092Y-124913D01*
X461117D01*
X461139Y-124909D01*
X461165D01*
X461190Y-124906D01*
X461256Y-124891D01*
X461332Y-124873D01*
X461408Y-124844D01*
X461488Y-124804D01*
X461528Y-124782D01*
X461565Y-124753D01*
X461568Y-124749D01*
X461572Y-124746D01*
X461583Y-124735D01*
X461598Y-124724D01*
X461612Y-124706D01*
X461630Y-124684D01*
X461652Y-124662D01*
X461670Y-124633D01*
X461692Y-124600D01*
X461718Y-124564D01*
X461740Y-124527D01*
X461762Y-124484D01*
X461780Y-124436D01*
X461798Y-124385D01*
X461816Y-124331D01*
X461831Y-124272D01*
X462165Y-124356D01*
Y-124360D01*
X462162Y-124374D01*
X462155Y-124396D01*
X462144Y-124425D01*
X462133Y-124458D01*
X462118Y-124498D01*
X462100Y-124542D01*
X462078Y-124589D01*
X462027Y-124691D01*
X461962Y-124793D01*
X461922Y-124844D01*
X461882Y-124895D01*
X461838Y-124938D01*
X461787Y-124982D01*
X461783Y-124986D01*
X461776Y-124993D01*
X461758Y-125000D01*
X461740Y-125015D01*
X461711Y-125033D01*
X461681Y-125051D01*
X461641Y-125069D01*
X461601Y-125088D01*
X461554Y-125110D01*
X461503Y-125128D01*
X461448Y-125146D01*
X461390Y-125164D01*
X461328Y-125179D01*
X461263Y-125186D01*
X461194Y-125193D01*
X461121Y-125197D01*
X461081D01*
X461052Y-125193D01*
X461019D01*
X460979Y-125190D01*
X460935Y-125182D01*
X460884Y-125175D01*
X460779Y-125157D01*
X460670Y-125128D01*
X460560Y-125088D01*
X460509Y-125062D01*
X460458Y-125033D01*
X460455Y-125030D01*
X460447Y-125026D01*
X460433Y-125015D01*
X460418Y-125000D01*
X460396Y-124986D01*
X460371Y-124964D01*
X460342Y-124938D01*
X460313Y-124909D01*
X460284Y-124877D01*
X460251Y-124844D01*
X460185Y-124760D01*
X460123Y-124662D01*
X460069Y-124553D01*
Y-124549D01*
X460062Y-124538D01*
X460058Y-124520D01*
X460047Y-124498D01*
X460040Y-124469D01*
X460029Y-124433D01*
X460014Y-124392D01*
X460003Y-124349D01*
X459992Y-124302D01*
X459978Y-124247D01*
X459960Y-124134D01*
X459945Y-124007D01*
X459938Y-123876D01*
Y-123872D01*
Y-123857D01*
Y-123836D01*
X459941Y-123810D01*
Y-123774D01*
X459945Y-123737D01*
X459949Y-123690D01*
X459956Y-123643D01*
X459974Y-123537D01*
X460000Y-123421D01*
X460036Y-123304D01*
X460087Y-123191D01*
X460091Y-123188D01*
X460094Y-123177D01*
X460102Y-123162D01*
X460116Y-123144D01*
X460131Y-123118D01*
X460149Y-123089D01*
X460196Y-123024D01*
X460258Y-122951D01*
X460331Y-122878D01*
X460415Y-122805D01*
X460513Y-122743D01*
X460517Y-122740D01*
X460528Y-122736D01*
X460542Y-122729D01*
X460560Y-122718D01*
X460589Y-122707D01*
X460618Y-122696D01*
X460655Y-122682D01*
X460695Y-122667D01*
X460739Y-122652D01*
X460786Y-122638D01*
X460888Y-122616D01*
X461004Y-122598D01*
X461125Y-122591D01*
X461161D01*
X461186Y-122594D01*
D02*
G37*
G36*
X466060Y-122911D02*
X466057Y-122915D01*
X466049Y-122922D01*
X466035Y-122936D01*
X466020Y-122958D01*
X465998Y-122984D01*
X465969Y-123013D01*
X465940Y-123049D01*
X465907Y-123093D01*
X465875Y-123137D01*
X465835Y-123188D01*
X465795Y-123246D01*
X465755Y-123304D01*
X465711Y-123370D01*
X465667Y-123439D01*
X465624Y-123515D01*
X465580Y-123592D01*
X465576Y-123595D01*
X465569Y-123610D01*
X465558Y-123632D01*
X465540Y-123664D01*
X465522Y-123705D01*
X465500Y-123748D01*
X465474Y-123799D01*
X465449Y-123857D01*
X465420Y-123923D01*
X465387Y-123988D01*
X465358Y-124061D01*
X465329Y-124138D01*
X465270Y-124294D01*
X465216Y-124462D01*
Y-124465D01*
X465212Y-124476D01*
X465208Y-124494D01*
X465201Y-124516D01*
X465194Y-124545D01*
X465187Y-124582D01*
X465176Y-124622D01*
X465169Y-124665D01*
X465158Y-124716D01*
X465147Y-124771D01*
X465129Y-124888D01*
X465110Y-125015D01*
X465099Y-125153D01*
X464783D01*
Y-125150D01*
Y-125139D01*
Y-125124D01*
X464786Y-125102D01*
Y-125073D01*
X464790Y-125037D01*
X464794Y-124997D01*
X464797Y-124953D01*
X464805Y-124902D01*
X464812Y-124851D01*
X464823Y-124789D01*
X464834Y-124727D01*
X464845Y-124662D01*
X464859Y-124589D01*
X464895Y-124440D01*
Y-124436D01*
X464899Y-124422D01*
X464906Y-124400D01*
X464917Y-124367D01*
X464928Y-124331D01*
X464943Y-124287D01*
X464957Y-124236D01*
X464979Y-124181D01*
X465001Y-124119D01*
X465023Y-124058D01*
X465077Y-123919D01*
X465143Y-123774D01*
X465216Y-123628D01*
X465219Y-123624D01*
X465227Y-123610D01*
X465238Y-123592D01*
X465252Y-123563D01*
X465270Y-123530D01*
X465296Y-123490D01*
X465321Y-123446D01*
X465350Y-123399D01*
X465420Y-123293D01*
X465492Y-123184D01*
X465576Y-123071D01*
X465663Y-122966D01*
X464430D01*
Y-122667D01*
X466060D01*
Y-122911D01*
D02*
G37*
G36*
X464102D02*
X464098Y-122915D01*
X464091Y-122922D01*
X464077Y-122936D01*
X464062Y-122958D01*
X464040Y-122984D01*
X464011Y-123013D01*
X463982Y-123049D01*
X463949Y-123093D01*
X463916Y-123137D01*
X463876Y-123188D01*
X463836Y-123246D01*
X463796Y-123304D01*
X463753Y-123370D01*
X463709Y-123439D01*
X463665Y-123515D01*
X463622Y-123592D01*
X463618Y-123595D01*
X463611Y-123610D01*
X463600Y-123632D01*
X463582Y-123664D01*
X463563Y-123705D01*
X463541Y-123748D01*
X463516Y-123799D01*
X463490Y-123857D01*
X463461Y-123923D01*
X463429Y-123988D01*
X463400Y-124061D01*
X463370Y-124138D01*
X463312Y-124294D01*
X463258Y-124462D01*
Y-124465D01*
X463254Y-124476D01*
X463250Y-124494D01*
X463243Y-124516D01*
X463236Y-124545D01*
X463228Y-124582D01*
X463217Y-124622D01*
X463210Y-124665D01*
X463199Y-124716D01*
X463188Y-124771D01*
X463170Y-124888D01*
X463152Y-125015D01*
X463141Y-125153D01*
X462824D01*
Y-125150D01*
Y-125139D01*
Y-125124D01*
X462828Y-125102D01*
Y-125073D01*
X462832Y-125037D01*
X462835Y-124997D01*
X462839Y-124953D01*
X462846Y-124902D01*
X462853Y-124851D01*
X462864Y-124789D01*
X462875Y-124727D01*
X462886Y-124662D01*
X462901Y-124589D01*
X462937Y-124440D01*
Y-124436D01*
X462941Y-124422D01*
X462948Y-124400D01*
X462959Y-124367D01*
X462970Y-124331D01*
X462985Y-124287D01*
X462999Y-124236D01*
X463021Y-124181D01*
X463043Y-124119D01*
X463065Y-124058D01*
X463119Y-123919D01*
X463185Y-123774D01*
X463258Y-123628D01*
X463261Y-123624D01*
X463268Y-123610D01*
X463279Y-123592D01*
X463294Y-123563D01*
X463312Y-123530D01*
X463338Y-123490D01*
X463363Y-123446D01*
X463392Y-123399D01*
X463461Y-123293D01*
X463534Y-123184D01*
X463618Y-123071D01*
X463705Y-122966D01*
X462471D01*
Y-122667D01*
X464102D01*
Y-122911D01*
D02*
G37*
G36*
X367784Y-111815D02*
X367817D01*
X367857Y-111818D01*
X367900Y-111826D01*
X367951Y-111833D01*
X368057Y-111851D01*
X368166Y-111880D01*
X368275Y-111920D01*
X368326Y-111946D01*
X368377Y-111975D01*
X368381Y-111978D01*
X368388Y-111982D01*
X368403Y-111993D01*
X368417Y-112007D01*
X368439Y-112022D01*
X368464Y-112044D01*
X368494Y-112069D01*
X368523Y-112099D01*
X368552Y-112131D01*
X368585Y-112164D01*
X368650Y-112248D01*
X368712Y-112346D01*
X368767Y-112455D01*
Y-112459D01*
X368774Y-112470D01*
X368778Y-112488D01*
X368789Y-112510D01*
X368796Y-112539D01*
X368807Y-112575D01*
X368821Y-112615D01*
X368832Y-112659D01*
X368843Y-112706D01*
X368858Y-112761D01*
X368876Y-112874D01*
X368890Y-113001D01*
X368898Y-113132D01*
Y-113136D01*
Y-113151D01*
Y-113172D01*
X368894Y-113198D01*
Y-113234D01*
X368890Y-113271D01*
X368887Y-113318D01*
X368880Y-113365D01*
X368861Y-113471D01*
X368836Y-113587D01*
X368799Y-113704D01*
X368748Y-113817D01*
X368745Y-113820D01*
X368741Y-113831D01*
X368734Y-113846D01*
X368719Y-113864D01*
X368705Y-113889D01*
X368687Y-113919D01*
X368639Y-113984D01*
X368577Y-114057D01*
X368505Y-114130D01*
X368421Y-114202D01*
X368323Y-114264D01*
X368319Y-114268D01*
X368308Y-114272D01*
X368293Y-114279D01*
X368275Y-114290D01*
X368246Y-114301D01*
X368217Y-114312D01*
X368181Y-114326D01*
X368141Y-114341D01*
X368097Y-114355D01*
X368050Y-114370D01*
X367948Y-114392D01*
X367831Y-114410D01*
X367711Y-114417D01*
X367675D01*
X367649Y-114414D01*
X367616Y-114410D01*
X367576Y-114406D01*
X367536Y-114403D01*
X367489Y-114392D01*
X367391Y-114370D01*
X367282Y-114337D01*
X367227Y-114315D01*
X367176Y-114290D01*
X367125Y-114257D01*
X367074Y-114224D01*
X367070Y-114221D01*
X367063Y-114217D01*
X367049Y-114206D01*
X367030Y-114188D01*
X367012Y-114170D01*
X366987Y-114144D01*
X366961Y-114115D01*
X366932Y-114086D01*
X366903Y-114050D01*
X366874Y-114006D01*
X366841Y-113962D01*
X366812Y-113915D01*
X366787Y-113860D01*
X366757Y-113806D01*
X366736Y-113748D01*
X366714Y-113682D01*
X367041Y-113605D01*
Y-113609D01*
X367045Y-113616D01*
X367052Y-113631D01*
X367059Y-113649D01*
X367067Y-113671D01*
X367078Y-113700D01*
X367107Y-113758D01*
X367143Y-113824D01*
X367187Y-113889D01*
X367242Y-113951D01*
X367300Y-114006D01*
X367307Y-114013D01*
X367329Y-114028D01*
X367365Y-114046D01*
X367413Y-114071D01*
X367474Y-114093D01*
X367544Y-114115D01*
X367627Y-114130D01*
X367718Y-114133D01*
X367747D01*
X367766Y-114130D01*
X367791D01*
X367820Y-114126D01*
X367889Y-114115D01*
X367966Y-114101D01*
X368046Y-114075D01*
X368130Y-114039D01*
X368206Y-113991D01*
X368210D01*
X368213Y-113984D01*
X368239Y-113966D01*
X368272Y-113937D01*
X368312Y-113893D01*
X368359Y-113839D01*
X368403Y-113777D01*
X368443Y-113700D01*
X368479Y-113616D01*
Y-113613D01*
X368483Y-113605D01*
X368486Y-113595D01*
X368490Y-113576D01*
X368497Y-113555D01*
X368505Y-113529D01*
X368515Y-113467D01*
X368530Y-113394D01*
X368545Y-113314D01*
X368552Y-113227D01*
X368555Y-113132D01*
Y-113129D01*
Y-113118D01*
Y-113100D01*
Y-113078D01*
X368552Y-113052D01*
Y-113020D01*
X368548Y-112983D01*
X368545Y-112943D01*
X368534Y-112856D01*
X368515Y-112761D01*
X368494Y-112666D01*
X368464Y-112572D01*
Y-112568D01*
X368461Y-112561D01*
X368454Y-112550D01*
X368446Y-112532D01*
X368425Y-112488D01*
X368392Y-112437D01*
X368352Y-112379D01*
X368301Y-112317D01*
X368243Y-112262D01*
X368173Y-112211D01*
X368170D01*
X368162Y-112208D01*
X368151Y-112200D01*
X368137Y-112193D01*
X368119Y-112186D01*
X368097Y-112175D01*
X368046Y-112153D01*
X367980Y-112131D01*
X367908Y-112113D01*
X367828Y-112099D01*
X367744Y-112095D01*
X367718D01*
X367696Y-112099D01*
X367671D01*
X367646Y-112102D01*
X367580Y-112117D01*
X367504Y-112135D01*
X367427Y-112164D01*
X367347Y-112204D01*
X367307Y-112226D01*
X367271Y-112255D01*
X367267Y-112259D01*
X367263Y-112262D01*
X367252Y-112273D01*
X367238Y-112284D01*
X367223Y-112302D01*
X367205Y-112324D01*
X367183Y-112346D01*
X367165Y-112375D01*
X367143Y-112408D01*
X367118Y-112444D01*
X367096Y-112481D01*
X367074Y-112524D01*
X367056Y-112572D01*
X367038Y-112623D01*
X367020Y-112677D01*
X367005Y-112735D01*
X366670Y-112652D01*
Y-112648D01*
X366674Y-112634D01*
X366681Y-112612D01*
X366692Y-112583D01*
X366703Y-112550D01*
X366717Y-112510D01*
X366736Y-112466D01*
X366757Y-112419D01*
X366808Y-112317D01*
X366874Y-112215D01*
X366914Y-112164D01*
X366954Y-112113D01*
X366998Y-112069D01*
X367049Y-112026D01*
X367052Y-112022D01*
X367059Y-112015D01*
X367078Y-112007D01*
X367096Y-111993D01*
X367125Y-111975D01*
X367154Y-111957D01*
X367194Y-111938D01*
X367234Y-111920D01*
X367282Y-111898D01*
X367333Y-111880D01*
X367387Y-111862D01*
X367445Y-111844D01*
X367507Y-111829D01*
X367573Y-111822D01*
X367642Y-111815D01*
X367715Y-111811D01*
X367755D01*
X367784Y-111815D01*
D02*
G37*
G36*
X366011Y-111858D02*
Y-111869D01*
Y-111884D01*
X366007Y-111906D01*
Y-111935D01*
X366004Y-111971D01*
X366000Y-112011D01*
X365997Y-112055D01*
X365989Y-112106D01*
X365982Y-112157D01*
X365971Y-112219D01*
X365960Y-112280D01*
X365949Y-112346D01*
X365935Y-112419D01*
X365898Y-112568D01*
Y-112572D01*
X365895Y-112586D01*
X365887Y-112608D01*
X365877Y-112641D01*
X365866Y-112677D01*
X365851Y-112721D01*
X365837Y-112772D01*
X365815Y-112827D01*
X365793Y-112888D01*
X365771Y-112950D01*
X365716Y-113089D01*
X365651Y-113234D01*
X365578Y-113380D01*
X365574Y-113383D01*
X365567Y-113398D01*
X365556Y-113416D01*
X365542Y-113445D01*
X365523Y-113478D01*
X365498Y-113518D01*
X365472Y-113562D01*
X365443Y-113609D01*
X365374Y-113715D01*
X365301Y-113824D01*
X365218Y-113937D01*
X365130Y-114042D01*
X366364D01*
Y-114341D01*
X364734D01*
Y-114097D01*
X364737Y-114093D01*
X364744Y-114086D01*
X364759Y-114071D01*
X364774Y-114050D01*
X364795Y-114024D01*
X364825Y-113995D01*
X364854Y-113959D01*
X364886Y-113915D01*
X364919Y-113871D01*
X364959Y-113820D01*
X364999Y-113762D01*
X365039Y-113704D01*
X365083Y-113638D01*
X365127Y-113569D01*
X365170Y-113493D01*
X365214Y-113416D01*
X365218Y-113413D01*
X365225Y-113398D01*
X365236Y-113376D01*
X365254Y-113343D01*
X365272Y-113303D01*
X365294Y-113260D01*
X365320Y-113209D01*
X365345Y-113151D01*
X365374Y-113085D01*
X365407Y-113020D01*
X365436Y-112947D01*
X365465Y-112870D01*
X365523Y-112714D01*
X365578Y-112546D01*
Y-112543D01*
X365582Y-112532D01*
X365585Y-112513D01*
X365593Y-112492D01*
X365600Y-112463D01*
X365607Y-112426D01*
X365618Y-112386D01*
X365625Y-112342D01*
X365636Y-112292D01*
X365647Y-112237D01*
X365665Y-112120D01*
X365684Y-111993D01*
X365694Y-111855D01*
X366011D01*
Y-111858D01*
D02*
G37*
G36*
X363663Y-111815D02*
X363696Y-111818D01*
X363733Y-111822D01*
X363773Y-111829D01*
X363816Y-111840D01*
X363914Y-111866D01*
X363966Y-111884D01*
X364013Y-111902D01*
X364064Y-111927D01*
X364115Y-111957D01*
X364162Y-111989D01*
X364206Y-112029D01*
X364209Y-112033D01*
X364217Y-112040D01*
X364228Y-112051D01*
X364242Y-112069D01*
X364257Y-112091D01*
X364279Y-112117D01*
X364297Y-112146D01*
X364319Y-112182D01*
X364340Y-112219D01*
X364359Y-112262D01*
X364395Y-112353D01*
X364410Y-112408D01*
X364421Y-112463D01*
X364428Y-112521D01*
X364431Y-112579D01*
Y-112583D01*
Y-112590D01*
Y-112604D01*
X364428Y-112619D01*
Y-112641D01*
X364424Y-112666D01*
X364417Y-112725D01*
X364402Y-112790D01*
X364381Y-112856D01*
X364348Y-112925D01*
X364308Y-112990D01*
Y-112994D01*
X364300Y-112998D01*
X364286Y-113016D01*
X364257Y-113045D01*
X364217Y-113081D01*
X364166Y-113118D01*
X364104Y-113158D01*
X364035Y-113191D01*
X363951Y-113216D01*
X363955D01*
X363958Y-113220D01*
X363969Y-113223D01*
X363984Y-113231D01*
X364016Y-113245D01*
X364060Y-113267D01*
X364107Y-113296D01*
X364155Y-113332D01*
X364198Y-113373D01*
X364239Y-113416D01*
X364242Y-113424D01*
X364253Y-113438D01*
X364268Y-113467D01*
X364282Y-113504D01*
X364300Y-113551D01*
X364315Y-113605D01*
X364326Y-113667D01*
X364330Y-113733D01*
Y-113737D01*
Y-113744D01*
Y-113758D01*
X364326Y-113780D01*
X364322Y-113802D01*
X364319Y-113831D01*
X364304Y-113893D01*
X364282Y-113966D01*
X364246Y-114042D01*
X364224Y-114082D01*
X364198Y-114122D01*
X364166Y-114159D01*
X364133Y-114195D01*
X364129Y-114199D01*
X364122Y-114202D01*
X364111Y-114213D01*
X364096Y-114224D01*
X364078Y-114239D01*
X364053Y-114253D01*
X364024Y-114272D01*
X363995Y-114290D01*
X363958Y-114308D01*
X363918Y-114326D01*
X363875Y-114341D01*
X363827Y-114355D01*
X363725Y-114377D01*
X363667Y-114381D01*
X363609Y-114384D01*
X363576D01*
X363554Y-114381D01*
X363525Y-114377D01*
X363492Y-114374D01*
X363456Y-114370D01*
X363420Y-114359D01*
X363332Y-114337D01*
X363245Y-114304D01*
X363201Y-114283D01*
X363157Y-114257D01*
X363117Y-114224D01*
X363077Y-114192D01*
X363074Y-114188D01*
X363070Y-114184D01*
X363059Y-114173D01*
X363045Y-114159D01*
X363030Y-114137D01*
X363012Y-114115D01*
X362975Y-114060D01*
X362939Y-113991D01*
X362906Y-113911D01*
X362881Y-113820D01*
X362877Y-113773D01*
X362874Y-113722D01*
Y-113718D01*
Y-113715D01*
Y-113693D01*
X362877Y-113660D01*
X362884Y-113620D01*
X362895Y-113569D01*
X362913Y-113518D01*
X362935Y-113467D01*
X362968Y-113416D01*
X362972Y-113409D01*
X362986Y-113394D01*
X363008Y-113373D01*
X363037Y-113343D01*
X363077Y-113311D01*
X363125Y-113278D01*
X363179Y-113245D01*
X363245Y-113216D01*
X363241D01*
X363234Y-113212D01*
X363223Y-113209D01*
X363208Y-113201D01*
X363165Y-113183D01*
X363114Y-113158D01*
X363059Y-113121D01*
X363001Y-113081D01*
X362946Y-113030D01*
X362895Y-112972D01*
Y-112969D01*
X362892Y-112965D01*
X362877Y-112943D01*
X362855Y-112907D01*
X362833Y-112859D01*
X362812Y-112801D01*
X362790Y-112732D01*
X362775Y-112655D01*
X362772Y-112572D01*
Y-112568D01*
Y-112557D01*
Y-112539D01*
X362775Y-112517D01*
X362779Y-112492D01*
X362783Y-112459D01*
X362790Y-112423D01*
X362801Y-112382D01*
X362826Y-112299D01*
X362844Y-112251D01*
X362870Y-112208D01*
X362895Y-112160D01*
X362924Y-112117D01*
X362961Y-112073D01*
X363001Y-112029D01*
X363004Y-112026D01*
X363012Y-112019D01*
X363023Y-112007D01*
X363041Y-111997D01*
X363066Y-111978D01*
X363092Y-111960D01*
X363125Y-111942D01*
X363161Y-111920D01*
X363201Y-111898D01*
X363248Y-111880D01*
X363299Y-111862D01*
X363350Y-111844D01*
X363409Y-111833D01*
X363470Y-111822D01*
X363532Y-111815D01*
X363601Y-111811D01*
X363638D01*
X363663Y-111815D01*
D02*
G37*
G36*
X347705Y-152076D02*
X347738Y-152079D01*
X347778Y-152083D01*
X347818Y-152086D01*
X347865Y-152097D01*
X347964Y-152119D01*
X348073Y-152152D01*
X348128Y-152174D01*
X348178Y-152199D01*
X348229Y-152232D01*
X348280Y-152265D01*
X348284Y-152269D01*
X348291Y-152272D01*
X348306Y-152283D01*
X348324Y-152301D01*
X348342Y-152319D01*
X348368Y-152345D01*
X348393Y-152374D01*
X348422Y-152403D01*
X348451Y-152439D01*
X348481Y-152483D01*
X348513Y-152527D01*
X348542Y-152574D01*
X348568Y-152629D01*
X348597Y-152683D01*
X348619Y-152742D01*
X348641Y-152807D01*
X348313Y-152884D01*
Y-152880D01*
X348309Y-152873D01*
X348302Y-152858D01*
X348295Y-152840D01*
X348288Y-152818D01*
X348277Y-152789D01*
X348248Y-152731D01*
X348211Y-152665D01*
X348167Y-152600D01*
X348113Y-152538D01*
X348055Y-152483D01*
X348047Y-152476D01*
X348025Y-152461D01*
X347989Y-152443D01*
X347942Y-152418D01*
X347880Y-152396D01*
X347811Y-152374D01*
X347727Y-152359D01*
X347636Y-152356D01*
X347607D01*
X347589Y-152359D01*
X347563D01*
X347534Y-152363D01*
X347465Y-152374D01*
X347389Y-152389D01*
X347308Y-152414D01*
X347225Y-152451D01*
X347148Y-152498D01*
X347145D01*
X347141Y-152505D01*
X347115Y-152523D01*
X347083Y-152552D01*
X347043Y-152596D01*
X346995Y-152651D01*
X346952Y-152713D01*
X346912Y-152789D01*
X346875Y-152873D01*
Y-152876D01*
X346872Y-152884D01*
X346868Y-152894D01*
X346864Y-152913D01*
X346857Y-152935D01*
X346850Y-152960D01*
X346839Y-153022D01*
X346824Y-153095D01*
X346810Y-153175D01*
X346802Y-153262D01*
X346799Y-153357D01*
Y-153360D01*
Y-153371D01*
Y-153390D01*
Y-153411D01*
X346802Y-153437D01*
Y-153470D01*
X346806Y-153506D01*
X346810Y-153546D01*
X346821Y-153633D01*
X346839Y-153728D01*
X346861Y-153823D01*
X346890Y-153917D01*
Y-153921D01*
X346894Y-153928D01*
X346901Y-153939D01*
X346908Y-153957D01*
X346930Y-154001D01*
X346963Y-154052D01*
X347003Y-154110D01*
X347054Y-154172D01*
X347112Y-154227D01*
X347181Y-154278D01*
X347185D01*
X347192Y-154281D01*
X347203Y-154289D01*
X347217Y-154296D01*
X347236Y-154303D01*
X347257Y-154314D01*
X347308Y-154336D01*
X347374Y-154358D01*
X347447Y-154376D01*
X347527Y-154391D01*
X347611Y-154394D01*
X347636D01*
X347658Y-154391D01*
X347683D01*
X347709Y-154387D01*
X347774Y-154372D01*
X347851Y-154354D01*
X347927Y-154325D01*
X348007Y-154285D01*
X348047Y-154263D01*
X348084Y-154234D01*
X348087Y-154230D01*
X348091Y-154227D01*
X348102Y-154216D01*
X348116Y-154205D01*
X348131Y-154187D01*
X348149Y-154165D01*
X348171Y-154143D01*
X348189Y-154114D01*
X348211Y-154081D01*
X348237Y-154045D01*
X348258Y-154008D01*
X348280Y-153965D01*
X348299Y-153917D01*
X348317Y-153866D01*
X348335Y-153812D01*
X348349Y-153754D01*
X348684Y-153837D01*
Y-153841D01*
X348681Y-153856D01*
X348674Y-153877D01*
X348662Y-153906D01*
X348652Y-153939D01*
X348637Y-153979D01*
X348619Y-154023D01*
X348597Y-154070D01*
X348546Y-154172D01*
X348481Y-154274D01*
X348441Y-154325D01*
X348400Y-154376D01*
X348357Y-154420D01*
X348306Y-154463D01*
X348302Y-154467D01*
X348295Y-154474D01*
X348277Y-154482D01*
X348258Y-154496D01*
X348229Y-154514D01*
X348200Y-154533D01*
X348160Y-154551D01*
X348120Y-154569D01*
X348073Y-154591D01*
X348022Y-154609D01*
X347967Y-154627D01*
X347909Y-154645D01*
X347847Y-154660D01*
X347782Y-154667D01*
X347712Y-154674D01*
X347640Y-154678D01*
X347600D01*
X347570Y-154674D01*
X347538D01*
X347498Y-154671D01*
X347454Y-154664D01*
X347403Y-154656D01*
X347298Y-154638D01*
X347188Y-154609D01*
X347079Y-154569D01*
X347028Y-154543D01*
X346977Y-154514D01*
X346974Y-154511D01*
X346966Y-154507D01*
X346952Y-154496D01*
X346937Y-154482D01*
X346915Y-154467D01*
X346890Y-154445D01*
X346861Y-154420D01*
X346832Y-154391D01*
X346802Y-154358D01*
X346770Y-154325D01*
X346704Y-154241D01*
X346642Y-154143D01*
X346588Y-154034D01*
Y-154030D01*
X346581Y-154019D01*
X346577Y-154001D01*
X346566Y-153979D01*
X346559Y-153950D01*
X346548Y-153914D01*
X346533Y-153874D01*
X346522Y-153830D01*
X346511Y-153783D01*
X346497Y-153728D01*
X346479Y-153615D01*
X346464Y-153488D01*
X346457Y-153357D01*
Y-153353D01*
Y-153339D01*
Y-153317D01*
X346460Y-153291D01*
Y-153255D01*
X346464Y-153218D01*
X346468Y-153171D01*
X346475Y-153124D01*
X346493Y-153018D01*
X346519Y-152902D01*
X346555Y-152785D01*
X346606Y-152673D01*
X346610Y-152669D01*
X346613Y-152658D01*
X346620Y-152643D01*
X346635Y-152625D01*
X346650Y-152600D01*
X346668Y-152571D01*
X346715Y-152505D01*
X346777Y-152432D01*
X346850Y-152359D01*
X346934Y-152287D01*
X347032Y-152225D01*
X347036Y-152221D01*
X347046Y-152217D01*
X347061Y-152210D01*
X347079Y-152199D01*
X347108Y-152188D01*
X347137Y-152177D01*
X347174Y-152163D01*
X347214Y-152148D01*
X347257Y-152134D01*
X347305Y-152119D01*
X347407Y-152097D01*
X347523Y-152079D01*
X347643Y-152072D01*
X347680D01*
X347705Y-152076D01*
D02*
G37*
G36*
X350268Y-153746D02*
X350610D01*
Y-154030D01*
X350268D01*
Y-154634D01*
X349958D01*
Y-154030D01*
X348863D01*
Y-153746D01*
X350017Y-152116D01*
X350268D01*
Y-153746D01*
D02*
G37*
G36*
X347666Y-131997D02*
X347699Y-132000D01*
X347739Y-132004D01*
X347779Y-132008D01*
X347826Y-132019D01*
X347924Y-132041D01*
X348033Y-132073D01*
X348088Y-132095D01*
X348139Y-132121D01*
X348190Y-132153D01*
X348241Y-132186D01*
X348245Y-132190D01*
X348252Y-132193D01*
X348266Y-132204D01*
X348285Y-132222D01*
X348303Y-132241D01*
X348328Y-132266D01*
X348354Y-132295D01*
X348383Y-132324D01*
X348412Y-132361D01*
X348441Y-132404D01*
X348474Y-132448D01*
X348503Y-132495D01*
X348529Y-132550D01*
X348558Y-132605D01*
X348580Y-132663D01*
X348601Y-132728D01*
X348274Y-132805D01*
Y-132801D01*
X348270Y-132794D01*
X348263Y-132779D01*
X348255Y-132761D01*
X348248Y-132739D01*
X348237Y-132710D01*
X348208Y-132652D01*
X348172Y-132587D01*
X348128Y-132521D01*
X348074Y-132459D01*
X348015Y-132404D01*
X348008Y-132397D01*
X347986Y-132383D01*
X347950Y-132364D01*
X347902Y-132339D01*
X347841Y-132317D01*
X347771Y-132295D01*
X347688Y-132281D01*
X347597Y-132277D01*
X347568D01*
X347549Y-132281D01*
X347524D01*
X347495Y-132284D01*
X347426Y-132295D01*
X347349Y-132310D01*
X347269Y-132335D01*
X347185Y-132372D01*
X347109Y-132419D01*
X347105D01*
X347102Y-132426D01*
X347076Y-132445D01*
X347043Y-132474D01*
X347003Y-132517D01*
X346956Y-132572D01*
X346912Y-132634D01*
X346872Y-132710D01*
X346836Y-132794D01*
Y-132798D01*
X346832Y-132805D01*
X346829Y-132816D01*
X346825Y-132834D01*
X346818Y-132856D01*
X346810Y-132881D01*
X346799Y-132943D01*
X346785Y-133016D01*
X346770Y-133096D01*
X346763Y-133183D01*
X346760Y-133278D01*
Y-133282D01*
Y-133293D01*
Y-133311D01*
Y-133333D01*
X346763Y-133358D01*
Y-133391D01*
X346767Y-133427D01*
X346770Y-133467D01*
X346781Y-133555D01*
X346799Y-133649D01*
X346821Y-133744D01*
X346850Y-133839D01*
Y-133842D01*
X346854Y-133850D01*
X346861Y-133861D01*
X346869Y-133879D01*
X346890Y-133922D01*
X346923Y-133973D01*
X346963Y-134031D01*
X347014Y-134093D01*
X347073Y-134148D01*
X347142Y-134199D01*
X347145D01*
X347153Y-134203D01*
X347164Y-134210D01*
X347178Y-134217D01*
X347196Y-134224D01*
X347218Y-134235D01*
X347269Y-134257D01*
X347335Y-134279D01*
X347407Y-134297D01*
X347487Y-134312D01*
X347571Y-134316D01*
X347597D01*
X347619Y-134312D01*
X347644D01*
X347670Y-134308D01*
X347735Y-134294D01*
X347812Y-134275D01*
X347888Y-134246D01*
X347968Y-134206D01*
X348008Y-134184D01*
X348044Y-134155D01*
X348048Y-134152D01*
X348052Y-134148D01*
X348063Y-134137D01*
X348077Y-134126D01*
X348092Y-134108D01*
X348110Y-134086D01*
X348132Y-134064D01*
X348150Y-134035D01*
X348172Y-134002D01*
X348197Y-133966D01*
X348219Y-133930D01*
X348241Y-133886D01*
X348259Y-133839D01*
X348277Y-133788D01*
X348296Y-133733D01*
X348310Y-133675D01*
X348645Y-133758D01*
Y-133762D01*
X348641Y-133777D01*
X348634Y-133799D01*
X348623Y-133828D01*
X348612Y-133861D01*
X348598Y-133900D01*
X348580Y-133944D01*
X348558Y-133992D01*
X348507Y-134093D01*
X348441Y-134195D01*
X348401Y-134246D01*
X348361Y-134297D01*
X348317Y-134341D01*
X348266Y-134385D01*
X348263Y-134388D01*
X348255Y-134396D01*
X348237Y-134403D01*
X348219Y-134417D01*
X348190Y-134436D01*
X348161Y-134454D01*
X348121Y-134472D01*
X348081Y-134490D01*
X348033Y-134512D01*
X347983Y-134530D01*
X347928Y-134548D01*
X347870Y-134567D01*
X347808Y-134581D01*
X347742Y-134589D01*
X347673Y-134596D01*
X347600Y-134599D01*
X347560D01*
X347531Y-134596D01*
X347498D01*
X347458Y-134592D01*
X347415Y-134585D01*
X347364Y-134578D01*
X347258Y-134559D01*
X347149Y-134530D01*
X347040Y-134490D01*
X346989Y-134465D01*
X346938Y-134436D01*
X346934Y-134432D01*
X346927Y-134428D01*
X346912Y-134417D01*
X346898Y-134403D01*
X346876Y-134388D01*
X346850Y-134366D01*
X346821Y-134341D01*
X346792Y-134312D01*
X346763Y-134279D01*
X346730Y-134246D01*
X346665Y-134163D01*
X346603Y-134064D01*
X346548Y-133955D01*
Y-133951D01*
X346541Y-133941D01*
X346537Y-133922D01*
X346527Y-133900D01*
X346519Y-133871D01*
X346508Y-133835D01*
X346494Y-133795D01*
X346483Y-133751D01*
X346472Y-133704D01*
X346457Y-133649D01*
X346439Y-133537D01*
X346425Y-133409D01*
X346417Y-133278D01*
Y-133274D01*
Y-133260D01*
Y-133238D01*
X346421Y-133213D01*
Y-133176D01*
X346425Y-133140D01*
X346428Y-133092D01*
X346435Y-133045D01*
X346454Y-132940D01*
X346479Y-132823D01*
X346516Y-132707D01*
X346567Y-132594D01*
X346570Y-132590D01*
X346574Y-132579D01*
X346581Y-132565D01*
X346596Y-132546D01*
X346610Y-132521D01*
X346628Y-132492D01*
X346676Y-132426D01*
X346738Y-132353D01*
X346810Y-132281D01*
X346894Y-132208D01*
X346992Y-132146D01*
X346996Y-132142D01*
X347007Y-132139D01*
X347022Y-132132D01*
X347040Y-132121D01*
X347069Y-132110D01*
X347098Y-132099D01*
X347134Y-132084D01*
X347174Y-132070D01*
X347218Y-132055D01*
X347266Y-132041D01*
X347367Y-132019D01*
X347484Y-132000D01*
X347604Y-131993D01*
X347640D01*
X347666Y-131997D01*
D02*
G37*
G36*
X351721Y-132029D02*
X351739D01*
X351764Y-132033D01*
X351826Y-132044D01*
X351895Y-132059D01*
X351972Y-132084D01*
X352048Y-132117D01*
X352125Y-132161D01*
X352129D01*
X352132Y-132168D01*
X352143Y-132175D01*
X352158Y-132186D01*
X352194Y-132215D01*
X352241Y-132255D01*
X352289Y-132310D01*
X352343Y-132375D01*
X352391Y-132452D01*
X352434Y-132539D01*
Y-132543D01*
X352438Y-132550D01*
X352445Y-132565D01*
X352452Y-132583D01*
X352460Y-132608D01*
X352471Y-132641D01*
X352478Y-132677D01*
X352489Y-132718D01*
X352500Y-132765D01*
X352511Y-132819D01*
X352518Y-132878D01*
X352525Y-132940D01*
X352533Y-133009D01*
X352540Y-133081D01*
X352543Y-133162D01*
Y-133245D01*
Y-133249D01*
Y-133267D01*
Y-133293D01*
Y-133325D01*
X352540Y-133365D01*
Y-133413D01*
X352536Y-133467D01*
X352529Y-133522D01*
X352518Y-133646D01*
X352500Y-133777D01*
X352474Y-133900D01*
X352456Y-133962D01*
X352438Y-134017D01*
Y-134021D01*
X352434Y-134028D01*
X352427Y-134043D01*
X352420Y-134064D01*
X352409Y-134086D01*
X352394Y-134115D01*
X352358Y-134177D01*
X352314Y-134246D01*
X352263Y-134319D01*
X352198Y-134388D01*
X352125Y-134450D01*
X352121D01*
X352114Y-134457D01*
X352103Y-134465D01*
X352088Y-134472D01*
X352067Y-134483D01*
X352045Y-134497D01*
X352016Y-134512D01*
X351987Y-134523D01*
X351917Y-134552D01*
X351834Y-134578D01*
X351743Y-134592D01*
X351641Y-134599D01*
X351612D01*
X351593Y-134596D01*
X351568D01*
X351539Y-134592D01*
X351470Y-134578D01*
X351393Y-134559D01*
X351313Y-134530D01*
X351233Y-134490D01*
X351193Y-134465D01*
X351157Y-134436D01*
X351153Y-134432D01*
X351149Y-134428D01*
X351138Y-134417D01*
X351128Y-134406D01*
X351113Y-134388D01*
X351095Y-134366D01*
X351058Y-134316D01*
X351022Y-134250D01*
X350986Y-134170D01*
X350956Y-134079D01*
X350935Y-133973D01*
X351233Y-133948D01*
Y-133951D01*
X351237Y-133959D01*
Y-133966D01*
X351240Y-133981D01*
X351251Y-134021D01*
X351266Y-134064D01*
X351284Y-134115D01*
X351309Y-134166D01*
X351339Y-134214D01*
X351375Y-134254D01*
X351379Y-134257D01*
X351393Y-134268D01*
X351419Y-134283D01*
X351448Y-134297D01*
X351488Y-134316D01*
X351535Y-134330D01*
X351590Y-134341D01*
X351648Y-134345D01*
X351674D01*
X351699Y-134341D01*
X351732Y-134337D01*
X351772Y-134330D01*
X351812Y-134319D01*
X351855Y-134304D01*
X351895Y-134283D01*
X351899Y-134279D01*
X351914Y-134272D01*
X351936Y-134257D01*
X351957Y-134235D01*
X351987Y-134210D01*
X352016Y-134181D01*
X352045Y-134148D01*
X352074Y-134108D01*
X352078Y-134104D01*
X352085Y-134086D01*
X352099Y-134061D01*
X352114Y-134028D01*
X352132Y-133984D01*
X352150Y-133933D01*
X352168Y-133875D01*
X352187Y-133809D01*
Y-133806D01*
X352190Y-133802D01*
Y-133791D01*
X352194Y-133777D01*
X352201Y-133740D01*
X352212Y-133693D01*
X352220Y-133635D01*
X352227Y-133573D01*
X352230Y-133504D01*
X352234Y-133431D01*
Y-133427D01*
Y-133416D01*
Y-133398D01*
Y-133369D01*
X352230Y-133376D01*
X352216Y-133395D01*
X352194Y-133420D01*
X352168Y-133456D01*
X352132Y-133493D01*
X352088Y-133533D01*
X352038Y-133573D01*
X351979Y-133609D01*
X351972Y-133613D01*
X351950Y-133624D01*
X351917Y-133638D01*
X351877Y-133653D01*
X351823Y-133671D01*
X351764Y-133686D01*
X351699Y-133697D01*
X351630Y-133700D01*
X351601D01*
X351579Y-133697D01*
X351550Y-133693D01*
X351521Y-133689D01*
X351484Y-133682D01*
X351448Y-133671D01*
X351364Y-133646D01*
X351320Y-133627D01*
X351277Y-133606D01*
X351229Y-133580D01*
X351186Y-133547D01*
X351142Y-133515D01*
X351102Y-133475D01*
X351098Y-133471D01*
X351091Y-133464D01*
X351084Y-133453D01*
X351069Y-133435D01*
X351051Y-133409D01*
X351033Y-133384D01*
X351015Y-133351D01*
X350996Y-133315D01*
X350975Y-133274D01*
X350956Y-133231D01*
X350938Y-133180D01*
X350920Y-133129D01*
X350905Y-133071D01*
X350898Y-133009D01*
X350891Y-132947D01*
X350887Y-132878D01*
Y-132874D01*
Y-132860D01*
Y-132841D01*
X350891Y-132816D01*
X350894Y-132783D01*
X350898Y-132743D01*
X350905Y-132703D01*
X350916Y-132656D01*
X350942Y-132561D01*
X350960Y-132510D01*
X350982Y-132455D01*
X351007Y-132404D01*
X351040Y-132357D01*
X351073Y-132306D01*
X351113Y-132263D01*
X351117Y-132259D01*
X351124Y-132252D01*
X351135Y-132241D01*
X351153Y-132226D01*
X351175Y-132208D01*
X351204Y-132186D01*
X351233Y-132168D01*
X351270Y-132142D01*
X351306Y-132121D01*
X351349Y-132102D01*
X351448Y-132062D01*
X351499Y-132048D01*
X351557Y-132037D01*
X351615Y-132029D01*
X351677Y-132026D01*
X351703D01*
X351721Y-132029D01*
D02*
G37*
G36*
X350582Y-132314D02*
X350578Y-132317D01*
X350571Y-132324D01*
X350556Y-132339D01*
X350541Y-132361D01*
X350520Y-132386D01*
X350490Y-132415D01*
X350461Y-132452D01*
X350429Y-132495D01*
X350396Y-132539D01*
X350356Y-132590D01*
X350316Y-132648D01*
X350276Y-132707D01*
X350232Y-132772D01*
X350188Y-132841D01*
X350145Y-132918D01*
X350101Y-132994D01*
X350097Y-132998D01*
X350090Y-133012D01*
X350079Y-133034D01*
X350061Y-133067D01*
X350043Y-133107D01*
X350021Y-133151D01*
X349995Y-133202D01*
X349970Y-133260D01*
X349941Y-133325D01*
X349908Y-133391D01*
X349879Y-133464D01*
X349850Y-133540D01*
X349792Y-133697D01*
X349737Y-133864D01*
Y-133868D01*
X349733Y-133879D01*
X349730Y-133897D01*
X349722Y-133919D01*
X349715Y-133948D01*
X349708Y-133984D01*
X349697Y-134024D01*
X349690Y-134068D01*
X349679Y-134119D01*
X349668Y-134174D01*
X349650Y-134290D01*
X349631Y-134417D01*
X349621Y-134556D01*
X349304D01*
Y-134552D01*
Y-134541D01*
Y-134527D01*
X349307Y-134505D01*
Y-134476D01*
X349311Y-134439D01*
X349315Y-134399D01*
X349318Y-134355D01*
X349326Y-134304D01*
X349333Y-134254D01*
X349344Y-134192D01*
X349355Y-134130D01*
X349366Y-134064D01*
X349380Y-133992D01*
X349417Y-133842D01*
Y-133839D01*
X349420Y-133824D01*
X349428Y-133802D01*
X349439Y-133770D01*
X349449Y-133733D01*
X349464Y-133689D01*
X349479Y-133638D01*
X349500Y-133584D01*
X349522Y-133522D01*
X349544Y-133460D01*
X349599Y-133322D01*
X349664Y-133176D01*
X349737Y-133030D01*
X349741Y-133027D01*
X349748Y-133012D01*
X349759Y-132994D01*
X349773Y-132965D01*
X349792Y-132932D01*
X349817Y-132892D01*
X349843Y-132849D01*
X349872Y-132801D01*
X349941Y-132696D01*
X350014Y-132587D01*
X350097Y-132474D01*
X350185Y-132368D01*
X348951D01*
Y-132070D01*
X350582D01*
Y-132314D01*
D02*
G37*
G36*
X60580Y-12459D02*
X60609Y-12462D01*
X60642Y-12466D01*
X60682Y-12473D01*
X60722Y-12481D01*
X60817Y-12502D01*
X60915Y-12539D01*
X60966Y-12561D01*
X61013Y-12590D01*
X61064Y-12619D01*
X61112Y-12655D01*
X61115Y-12659D01*
X61126Y-12666D01*
X61141Y-12681D01*
X61159Y-12699D01*
X61181Y-12724D01*
X61210Y-12754D01*
X61235Y-12790D01*
X61264Y-12830D01*
X61294Y-12874D01*
X61319Y-12925D01*
X61345Y-12979D01*
X61370Y-13037D01*
X61388Y-13099D01*
X61403Y-13169D01*
X61414Y-13241D01*
X61417Y-13318D01*
Y-13351D01*
X61414Y-13376D01*
X61410Y-13405D01*
X61406Y-13438D01*
X61403Y-13478D01*
X61392Y-13518D01*
X61370Y-13609D01*
X61337Y-13700D01*
X61315Y-13747D01*
X61290Y-13795D01*
X61261Y-13838D01*
X61228Y-13882D01*
X61225Y-13886D01*
X61221Y-13893D01*
X61206Y-13900D01*
X61192Y-13915D01*
X61173Y-13933D01*
X61152Y-13951D01*
X61123Y-13973D01*
X61090Y-13991D01*
X61057Y-14013D01*
X61017Y-14035D01*
X60930Y-14075D01*
X60828Y-14108D01*
X60773Y-14119D01*
X60715Y-14126D01*
X60689Y-13802D01*
X60693D01*
X60700D01*
X60711Y-13798D01*
X60729Y-13795D01*
X60769Y-13784D01*
X60824Y-13769D01*
X60879Y-13747D01*
X60940Y-13718D01*
X60995Y-13682D01*
X61046Y-13638D01*
X61050Y-13631D01*
X61064Y-13616D01*
X61083Y-13587D01*
X61104Y-13547D01*
X61126Y-13503D01*
X61144Y-13449D01*
X61159Y-13387D01*
X61163Y-13318D01*
Y-13296D01*
X61159Y-13281D01*
X61155Y-13238D01*
X61141Y-13187D01*
X61123Y-13125D01*
X61093Y-13063D01*
X61050Y-12997D01*
X61024Y-12968D01*
X60995Y-12939D01*
X60992Y-12935D01*
X60988Y-12932D01*
X60977Y-12925D01*
X60966Y-12914D01*
X60926Y-12888D01*
X60875Y-12859D01*
X60813Y-12834D01*
X60737Y-12808D01*
X60646Y-12790D01*
X60598Y-12783D01*
X60547D01*
X60544D01*
X60536D01*
X60522D01*
X60504Y-12786D01*
X60482D01*
X60456Y-12790D01*
X60398Y-12801D01*
X60329Y-12819D01*
X60260Y-12844D01*
X60194Y-12881D01*
X60132Y-12932D01*
X60129D01*
X60125Y-12939D01*
X60107Y-12957D01*
X60081Y-12990D01*
X60052Y-13034D01*
X60027Y-13092D01*
X60001Y-13158D01*
X59983Y-13234D01*
X59976Y-13278D01*
Y-13347D01*
X59980Y-13376D01*
X59983Y-13412D01*
X59994Y-13456D01*
X60005Y-13500D01*
X60023Y-13547D01*
X60045Y-13594D01*
X60049Y-13598D01*
X60056Y-13613D01*
X60074Y-13634D01*
X60092Y-13664D01*
X60118Y-13693D01*
X60151Y-13722D01*
X60183Y-13755D01*
X60224Y-13780D01*
X60183Y-14071D01*
X58888Y-13827D01*
Y-12575D01*
X59182D01*
Y-13583D01*
X59863Y-13718D01*
X59860Y-13714D01*
X59856Y-13707D01*
X59848Y-13696D01*
X59838Y-13678D01*
X59827Y-13656D01*
X59812Y-13631D01*
X59783Y-13573D01*
X59754Y-13500D01*
X59728Y-13420D01*
X59710Y-13332D01*
X59703Y-13289D01*
Y-13208D01*
X59707Y-13187D01*
X59710Y-13158D01*
X59714Y-13125D01*
X59721Y-13088D01*
X59732Y-13048D01*
X59758Y-12961D01*
X59776Y-12914D01*
X59801Y-12866D01*
X59827Y-12819D01*
X59856Y-12772D01*
X59892Y-12728D01*
X59932Y-12684D01*
X59936Y-12681D01*
X59943Y-12673D01*
X59954Y-12663D01*
X59972Y-12648D01*
X59998Y-12630D01*
X60023Y-12612D01*
X60056Y-12590D01*
X60092Y-12568D01*
X60132Y-12550D01*
X60176Y-12528D01*
X60227Y-12510D01*
X60278Y-12491D01*
X60333Y-12477D01*
X60395Y-12466D01*
X60456Y-12459D01*
X60522Y-12455D01*
X60526D01*
X60536D01*
X60555D01*
X60580Y-12459D01*
D02*
G37*
G36*
X60405Y-14559D02*
X60442D01*
X60486Y-14563D01*
X60529Y-14566D01*
X60628Y-14577D01*
X60729Y-14592D01*
X60828Y-14614D01*
X60875Y-14628D01*
X60919Y-14643D01*
X60922D01*
X60930Y-14646D01*
X60940Y-14654D01*
X60955Y-14661D01*
X60995Y-14683D01*
X61046Y-14716D01*
X61104Y-14759D01*
X61163Y-14810D01*
X61225Y-14876D01*
X61279Y-14956D01*
Y-14959D01*
X61286Y-14967D01*
X61290Y-14978D01*
X61301Y-14996D01*
X61312Y-15018D01*
X61323Y-15047D01*
X61334Y-15076D01*
X61348Y-15112D01*
X61363Y-15152D01*
X61374Y-15196D01*
X61385Y-15243D01*
X61396Y-15298D01*
X61403Y-15352D01*
X61410Y-15411D01*
X61417Y-15542D01*
Y-15574D01*
X61414Y-15600D01*
Y-15629D01*
X61410Y-15665D01*
X61406Y-15706D01*
X61403Y-15746D01*
X61388Y-15837D01*
X61366Y-15935D01*
X61337Y-16029D01*
X61297Y-16120D01*
Y-16124D01*
X61290Y-16131D01*
X61283Y-16142D01*
X61275Y-16157D01*
X61246Y-16197D01*
X61206Y-16244D01*
X61155Y-16299D01*
X61097Y-16350D01*
X61024Y-16401D01*
X60944Y-16441D01*
X60940D01*
X60933Y-16444D01*
X60919Y-16448D01*
X60900Y-16455D01*
X60879Y-16463D01*
X60849Y-16470D01*
X60817Y-16481D01*
X60777Y-16488D01*
X60733Y-16495D01*
X60686Y-16506D01*
X60635Y-16514D01*
X60580Y-16521D01*
X60518Y-16528D01*
X60453Y-16532D01*
X60384Y-16535D01*
X60311D01*
X58855D01*
Y-16201D01*
X60311D01*
X60314D01*
X60325D01*
X60344D01*
X60365D01*
X60391Y-16197D01*
X60424D01*
X60493Y-16193D01*
X60573Y-16186D01*
X60653Y-16175D01*
X60729Y-16161D01*
X60762Y-16153D01*
X60795Y-16142D01*
X60802Y-16139D01*
X60820Y-16131D01*
X60846Y-16113D01*
X60882Y-16091D01*
X60919Y-16066D01*
X60959Y-16029D01*
X60999Y-15986D01*
X61032Y-15935D01*
X61035Y-15928D01*
X61046Y-15909D01*
X61057Y-15877D01*
X61072Y-15833D01*
X61090Y-15782D01*
X61101Y-15717D01*
X61112Y-15647D01*
X61115Y-15571D01*
Y-15534D01*
X61112Y-15513D01*
Y-15480D01*
X61108Y-15447D01*
X61093Y-15367D01*
X61075Y-15280D01*
X61046Y-15196D01*
X61006Y-15116D01*
X60981Y-15079D01*
X60951Y-15047D01*
X60948Y-15043D01*
X60944Y-15039D01*
X60933Y-15032D01*
X60919Y-15021D01*
X60897Y-15010D01*
X60875Y-14996D01*
X60842Y-14981D01*
X60809Y-14967D01*
X60769Y-14952D01*
X60722Y-14941D01*
X60668Y-14927D01*
X60609Y-14916D01*
X60544Y-14905D01*
X60475Y-14897D01*
X60395Y-14890D01*
X60311D01*
X58855D01*
Y-14555D01*
X60311D01*
X60314D01*
X60329D01*
X60347D01*
X60373D01*
X60405Y-14559D01*
D02*
G37*
G36*
X94555Y-76428D02*
X94588D01*
X94628Y-76432D01*
X94672Y-76439D01*
X94723Y-76446D01*
X94828Y-76464D01*
X94938Y-76493D01*
X95047Y-76534D01*
X95098Y-76559D01*
X95149Y-76588D01*
X95152Y-76592D01*
X95160Y-76595D01*
X95174Y-76606D01*
X95189Y-76621D01*
X95211Y-76635D01*
X95236Y-76657D01*
X95265Y-76683D01*
X95294Y-76712D01*
X95323Y-76745D01*
X95356Y-76777D01*
X95422Y-76861D01*
X95484Y-76959D01*
X95538Y-77069D01*
Y-77072D01*
X95546Y-77083D01*
X95549Y-77101D01*
X95560Y-77123D01*
X95567Y-77152D01*
X95578Y-77189D01*
X95593Y-77229D01*
X95604Y-77272D01*
X95615Y-77320D01*
X95629Y-77374D01*
X95648Y-77487D01*
X95662Y-77614D01*
X95669Y-77746D01*
Y-77749D01*
Y-77764D01*
Y-77786D01*
X95666Y-77811D01*
Y-77847D01*
X95662Y-77884D01*
X95658Y-77931D01*
X95651Y-77978D01*
X95633Y-78084D01*
X95607Y-78201D01*
X95571Y-78317D01*
X95520Y-78430D01*
X95516Y-78434D01*
X95513Y-78444D01*
X95505Y-78459D01*
X95491Y-78477D01*
X95476Y-78503D01*
X95458Y-78532D01*
X95411Y-78597D01*
X95349Y-78670D01*
X95276Y-78743D01*
X95192Y-78816D01*
X95094Y-78878D01*
X95091Y-78881D01*
X95080Y-78885D01*
X95065Y-78892D01*
X95047Y-78903D01*
X95018Y-78914D01*
X94989Y-78925D01*
X94952Y-78939D01*
X94912Y-78954D01*
X94868Y-78969D01*
X94821Y-78983D01*
X94719Y-79005D01*
X94603Y-79023D01*
X94483Y-79031D01*
X94446D01*
X94421Y-79027D01*
X94388Y-79023D01*
X94348Y-79020D01*
X94308Y-79016D01*
X94261Y-79005D01*
X94162Y-78983D01*
X94053Y-78950D01*
X93998Y-78929D01*
X93948Y-78903D01*
X93897Y-78870D01*
X93846Y-78838D01*
X93842Y-78834D01*
X93835Y-78830D01*
X93820Y-78819D01*
X93802Y-78801D01*
X93784Y-78783D01*
X93758Y-78758D01*
X93733Y-78728D01*
X93704Y-78699D01*
X93675Y-78663D01*
X93646Y-78619D01*
X93613Y-78575D01*
X93584Y-78528D01*
X93558Y-78474D01*
X93529Y-78419D01*
X93507Y-78361D01*
X93485Y-78295D01*
X93813Y-78219D01*
Y-78222D01*
X93817Y-78230D01*
X93824Y-78244D01*
X93831Y-78263D01*
X93838Y-78284D01*
X93849Y-78313D01*
X93878Y-78372D01*
X93915Y-78437D01*
X93958Y-78503D01*
X94013Y-78565D01*
X94071Y-78619D01*
X94079Y-78626D01*
X94100Y-78641D01*
X94137Y-78659D01*
X94184Y-78685D01*
X94246Y-78707D01*
X94315Y-78728D01*
X94399Y-78743D01*
X94490Y-78747D01*
X94519D01*
X94537Y-78743D01*
X94563D01*
X94592Y-78739D01*
X94661Y-78728D01*
X94737Y-78714D01*
X94818Y-78688D01*
X94901Y-78652D01*
X94978Y-78605D01*
X94981D01*
X94985Y-78597D01*
X95011Y-78579D01*
X95043Y-78550D01*
X95083Y-78506D01*
X95131Y-78452D01*
X95174Y-78390D01*
X95214Y-78313D01*
X95251Y-78230D01*
Y-78226D01*
X95254Y-78219D01*
X95258Y-78208D01*
X95262Y-78190D01*
X95269Y-78168D01*
X95276Y-78142D01*
X95287Y-78080D01*
X95302Y-78008D01*
X95316Y-77928D01*
X95323Y-77840D01*
X95327Y-77746D01*
Y-77742D01*
Y-77731D01*
Y-77713D01*
Y-77691D01*
X95323Y-77666D01*
Y-77633D01*
X95320Y-77596D01*
X95316Y-77556D01*
X95305Y-77469D01*
X95287Y-77374D01*
X95265Y-77280D01*
X95236Y-77185D01*
Y-77181D01*
X95232Y-77174D01*
X95225Y-77163D01*
X95218Y-77145D01*
X95196Y-77101D01*
X95163Y-77050D01*
X95123Y-76992D01*
X95072Y-76930D01*
X95014Y-76876D01*
X94945Y-76825D01*
X94941D01*
X94934Y-76821D01*
X94923Y-76814D01*
X94908Y-76806D01*
X94890Y-76799D01*
X94868Y-76788D01*
X94818Y-76766D01*
X94752Y-76745D01*
X94679Y-76726D01*
X94599Y-76712D01*
X94515Y-76708D01*
X94490D01*
X94468Y-76712D01*
X94443D01*
X94417Y-76715D01*
X94352Y-76730D01*
X94275Y-76748D01*
X94199Y-76777D01*
X94119Y-76817D01*
X94079Y-76839D01*
X94042Y-76868D01*
X94039Y-76872D01*
X94035Y-76876D01*
X94024Y-76886D01*
X94010Y-76898D01*
X93995Y-76916D01*
X93977Y-76938D01*
X93955Y-76959D01*
X93937Y-76989D01*
X93915Y-77021D01*
X93889Y-77058D01*
X93867Y-77094D01*
X93846Y-77138D01*
X93827Y-77185D01*
X93809Y-77236D01*
X93791Y-77291D01*
X93777Y-77349D01*
X93442Y-77265D01*
Y-77262D01*
X93445Y-77247D01*
X93453Y-77225D01*
X93463Y-77196D01*
X93474Y-77163D01*
X93489Y-77123D01*
X93507Y-77079D01*
X93529Y-77032D01*
X93580Y-76930D01*
X93646Y-76828D01*
X93686Y-76777D01*
X93726Y-76726D01*
X93769Y-76683D01*
X93820Y-76639D01*
X93824Y-76635D01*
X93831Y-76628D01*
X93849Y-76621D01*
X93867Y-76606D01*
X93897Y-76588D01*
X93926Y-76570D01*
X93966Y-76552D01*
X94006Y-76534D01*
X94053Y-76512D01*
X94104Y-76493D01*
X94159Y-76475D01*
X94217Y-76457D01*
X94279Y-76442D01*
X94344Y-76435D01*
X94414Y-76428D01*
X94486Y-76424D01*
X94526D01*
X94555Y-76428D01*
D02*
G37*
G36*
X90209Y-77072D02*
X91305D01*
Y-77356D01*
X90151Y-78987D01*
X89900D01*
Y-77356D01*
X89558D01*
Y-77072D01*
X89900D01*
Y-76468D01*
X90209D01*
Y-77072D01*
D02*
G37*
G36*
X92302Y-78437D02*
X92306Y-78434D01*
X92324Y-78419D01*
X92346Y-78397D01*
X92382Y-78372D01*
X92422Y-78339D01*
X92473Y-78303D01*
X92532Y-78263D01*
X92597Y-78222D01*
X92601D01*
X92604Y-78219D01*
X92626Y-78204D01*
X92663Y-78186D01*
X92706Y-78164D01*
X92757Y-78139D01*
X92812Y-78113D01*
X92866Y-78088D01*
X92921Y-78066D01*
Y-78364D01*
X92917D01*
X92910Y-78372D01*
X92896Y-78375D01*
X92877Y-78386D01*
X92856Y-78397D01*
X92830Y-78412D01*
X92768Y-78448D01*
X92695Y-78488D01*
X92623Y-78539D01*
X92546Y-78597D01*
X92470Y-78659D01*
X92466Y-78663D01*
X92462Y-78667D01*
X92452Y-78677D01*
X92437Y-78688D01*
X92404Y-78725D01*
X92361Y-78768D01*
X92317Y-78819D01*
X92269Y-78878D01*
X92229Y-78936D01*
X92193Y-78998D01*
X91993D01*
Y-76468D01*
X92302D01*
Y-78437D01*
D02*
G37*
G36*
X104241Y-44675D02*
X102271D01*
X102275Y-44678D01*
X102290Y-44697D01*
X102312Y-44718D01*
X102337Y-44755D01*
X102370Y-44795D01*
X102406Y-44846D01*
X102446Y-44904D01*
X102486Y-44969D01*
Y-44973D01*
X102490Y-44977D01*
X102505Y-44999D01*
X102523Y-45035D01*
X102544Y-45079D01*
X102570Y-45130D01*
X102595Y-45184D01*
X102621Y-45239D01*
X102643Y-45294D01*
X102344D01*
Y-45290D01*
X102337Y-45283D01*
X102333Y-45268D01*
X102322Y-45250D01*
X102312Y-45228D01*
X102297Y-45202D01*
X102261Y-45141D01*
X102221Y-45068D01*
X102170Y-44995D01*
X102111Y-44919D01*
X102050Y-44842D01*
X102046Y-44839D01*
X102042Y-44835D01*
X102031Y-44824D01*
X102020Y-44809D01*
X101984Y-44777D01*
X101940Y-44733D01*
X101889Y-44689D01*
X101831Y-44642D01*
X101773Y-44602D01*
X101711Y-44565D01*
Y-44365D01*
X104241D01*
Y-44675D01*
D02*
G37*
G36*
X102002Y-45840D02*
X102009Y-45847D01*
X102024Y-45861D01*
X102046Y-45876D01*
X102071Y-45898D01*
X102100Y-45927D01*
X102137Y-45956D01*
X102181Y-45989D01*
X102224Y-46022D01*
X102275Y-46062D01*
X102333Y-46102D01*
X102392Y-46142D01*
X102457Y-46185D01*
X102526Y-46229D01*
X102603Y-46273D01*
X102679Y-46316D01*
X102683Y-46320D01*
X102697Y-46327D01*
X102719Y-46338D01*
X102752Y-46356D01*
X102792Y-46375D01*
X102836Y-46396D01*
X102887Y-46422D01*
X102945Y-46447D01*
X103010Y-46477D01*
X103076Y-46509D01*
X103149Y-46538D01*
X103225Y-46567D01*
X103382Y-46626D01*
X103549Y-46680D01*
X103553D01*
X103564Y-46684D01*
X103582Y-46688D01*
X103604Y-46695D01*
X103633Y-46702D01*
X103669Y-46709D01*
X103709Y-46720D01*
X103753Y-46728D01*
X103804Y-46739D01*
X103858Y-46749D01*
X103975Y-46768D01*
X104102Y-46786D01*
X104241Y-46797D01*
Y-47113D01*
X104237D01*
X104226D01*
X104212D01*
X104190Y-47110D01*
X104161D01*
X104124Y-47106D01*
X104084Y-47103D01*
X104041Y-47099D01*
X103990Y-47092D01*
X103939Y-47084D01*
X103877Y-47073D01*
X103815Y-47063D01*
X103749Y-47052D01*
X103676Y-47037D01*
X103527Y-47001D01*
X103524D01*
X103509Y-46997D01*
X103487Y-46990D01*
X103454Y-46979D01*
X103418Y-46968D01*
X103374Y-46953D01*
X103323Y-46939D01*
X103269Y-46917D01*
X103207Y-46895D01*
X103145Y-46873D01*
X103007Y-46819D01*
X102861Y-46753D01*
X102716Y-46680D01*
X102712Y-46677D01*
X102697Y-46669D01*
X102679Y-46659D01*
X102650Y-46644D01*
X102617Y-46626D01*
X102577Y-46600D01*
X102534Y-46575D01*
X102486Y-46546D01*
X102381Y-46477D01*
X102271Y-46404D01*
X102159Y-46320D01*
X102053Y-46233D01*
Y-47467D01*
X101755D01*
Y-45836D01*
X101998D01*
X102002Y-45840D01*
D02*
G37*
G36*
X103462Y-47776D02*
X103484Y-47783D01*
X103513Y-47794D01*
X103545Y-47805D01*
X103586Y-47820D01*
X103629Y-47838D01*
X103676Y-47860D01*
X103779Y-47911D01*
X103880Y-47976D01*
X103931Y-48016D01*
X103982Y-48056D01*
X104026Y-48100D01*
X104070Y-48151D01*
X104073Y-48155D01*
X104081Y-48162D01*
X104088Y-48180D01*
X104102Y-48198D01*
X104121Y-48227D01*
X104139Y-48256D01*
X104157Y-48296D01*
X104175Y-48336D01*
X104197Y-48384D01*
X104215Y-48435D01*
X104234Y-48489D01*
X104252Y-48548D01*
X104266Y-48610D01*
X104273Y-48675D01*
X104281Y-48744D01*
X104284Y-48817D01*
Y-48857D01*
X104281Y-48886D01*
Y-48919D01*
X104277Y-48959D01*
X104270Y-49003D01*
X104263Y-49054D01*
X104244Y-49159D01*
X104215Y-49268D01*
X104175Y-49378D01*
X104150Y-49428D01*
X104121Y-49479D01*
X104117Y-49483D01*
X104113Y-49490D01*
X104102Y-49505D01*
X104088Y-49520D01*
X104073Y-49541D01*
X104051Y-49567D01*
X104026Y-49596D01*
X103997Y-49625D01*
X103964Y-49654D01*
X103931Y-49687D01*
X103848Y-49753D01*
X103749Y-49814D01*
X103640Y-49869D01*
X103637D01*
X103626Y-49876D01*
X103607Y-49880D01*
X103586Y-49891D01*
X103556Y-49898D01*
X103520Y-49909D01*
X103480Y-49924D01*
X103436Y-49935D01*
X103389Y-49945D01*
X103334Y-49960D01*
X103222Y-49978D01*
X103094Y-49993D01*
X102963Y-50000D01*
X102960D01*
X102945D01*
X102923D01*
X102898Y-49996D01*
X102861D01*
X102825Y-49993D01*
X102778Y-49989D01*
X102730Y-49982D01*
X102625Y-49964D01*
X102508Y-49938D01*
X102392Y-49902D01*
X102279Y-49851D01*
X102275Y-49847D01*
X102264Y-49843D01*
X102250Y-49836D01*
X102232Y-49822D01*
X102206Y-49807D01*
X102177Y-49789D01*
X102111Y-49742D01*
X102039Y-49680D01*
X101966Y-49607D01*
X101893Y-49523D01*
X101831Y-49425D01*
X101827Y-49421D01*
X101824Y-49410D01*
X101816Y-49396D01*
X101806Y-49378D01*
X101795Y-49348D01*
X101784Y-49319D01*
X101769Y-49283D01*
X101755Y-49243D01*
X101740Y-49199D01*
X101725Y-49152D01*
X101704Y-49050D01*
X101686Y-48934D01*
X101678Y-48813D01*
Y-48777D01*
X101682Y-48752D01*
X101686Y-48719D01*
X101689Y-48679D01*
X101693Y-48639D01*
X101704Y-48591D01*
X101725Y-48493D01*
X101758Y-48384D01*
X101780Y-48329D01*
X101806Y-48278D01*
X101838Y-48227D01*
X101871Y-48176D01*
X101875Y-48173D01*
X101878Y-48165D01*
X101889Y-48151D01*
X101908Y-48133D01*
X101926Y-48114D01*
X101951Y-48089D01*
X101980Y-48063D01*
X102009Y-48034D01*
X102046Y-48005D01*
X102090Y-47976D01*
X102133Y-47943D01*
X102181Y-47914D01*
X102235Y-47889D01*
X102290Y-47860D01*
X102348Y-47838D01*
X102413Y-47816D01*
X102490Y-48144D01*
X102486D01*
X102479Y-48147D01*
X102464Y-48155D01*
X102446Y-48162D01*
X102424Y-48169D01*
X102395Y-48180D01*
X102337Y-48209D01*
X102271Y-48245D01*
X102206Y-48289D01*
X102144Y-48344D01*
X102090Y-48402D01*
X102082Y-48409D01*
X102068Y-48431D01*
X102050Y-48468D01*
X102024Y-48515D01*
X102002Y-48577D01*
X101980Y-48646D01*
X101966Y-48730D01*
X101962Y-48821D01*
Y-48850D01*
X101966Y-48868D01*
Y-48893D01*
X101969Y-48923D01*
X101980Y-48992D01*
X101995Y-49068D01*
X102020Y-49148D01*
X102057Y-49232D01*
X102104Y-49308D01*
Y-49312D01*
X102111Y-49316D01*
X102129Y-49341D01*
X102159Y-49374D01*
X102202Y-49414D01*
X102257Y-49461D01*
X102319Y-49505D01*
X102395Y-49545D01*
X102479Y-49581D01*
X102483D01*
X102490Y-49585D01*
X102501Y-49589D01*
X102519Y-49592D01*
X102541Y-49600D01*
X102566Y-49607D01*
X102628Y-49618D01*
X102701Y-49632D01*
X102781Y-49647D01*
X102868Y-49654D01*
X102963Y-49658D01*
X102967D01*
X102978D01*
X102996D01*
X103018D01*
X103043Y-49654D01*
X103076D01*
X103112Y-49651D01*
X103152Y-49647D01*
X103240Y-49636D01*
X103334Y-49618D01*
X103429Y-49596D01*
X103524Y-49567D01*
X103527D01*
X103535Y-49563D01*
X103545Y-49556D01*
X103564Y-49549D01*
X103607Y-49527D01*
X103658Y-49494D01*
X103717Y-49454D01*
X103779Y-49403D01*
X103833Y-49345D01*
X103884Y-49276D01*
Y-49272D01*
X103888Y-49265D01*
X103895Y-49254D01*
X103902Y-49239D01*
X103910Y-49221D01*
X103920Y-49199D01*
X103942Y-49148D01*
X103964Y-49083D01*
X103982Y-49010D01*
X103997Y-48930D01*
X104000Y-48846D01*
Y-48821D01*
X103997Y-48799D01*
Y-48773D01*
X103993Y-48748D01*
X103979Y-48682D01*
X103961Y-48606D01*
X103931Y-48529D01*
X103891Y-48449D01*
X103869Y-48409D01*
X103840Y-48373D01*
X103837Y-48369D01*
X103833Y-48366D01*
X103822Y-48355D01*
X103811Y-48340D01*
X103793Y-48326D01*
X103771Y-48307D01*
X103749Y-48286D01*
X103720Y-48267D01*
X103688Y-48245D01*
X103651Y-48220D01*
X103615Y-48198D01*
X103571Y-48176D01*
X103524Y-48158D01*
X103473Y-48140D01*
X103418Y-48122D01*
X103360Y-48107D01*
X103444Y-47772D01*
X103447D01*
X103462Y-47776D01*
D02*
G37*
G36*
X75896Y-61726D02*
X75925Y-61730D01*
X75957Y-61734D01*
X75994Y-61741D01*
X76034Y-61748D01*
X76121Y-61770D01*
X76212Y-61806D01*
X76259Y-61828D01*
X76303Y-61854D01*
X76347Y-61887D01*
X76390Y-61919D01*
X76394Y-61923D01*
X76401Y-61930D01*
X76412Y-61941D01*
X76423Y-61956D01*
X76442Y-61974D01*
X76460Y-61999D01*
X76481Y-62025D01*
X76503Y-62058D01*
X76525Y-62094D01*
X76547Y-62130D01*
X76587Y-62218D01*
X76620Y-62320D01*
X76631Y-62374D01*
X76638Y-62432D01*
X76329Y-62472D01*
Y-62469D01*
X76325Y-62462D01*
X76321Y-62447D01*
X76318Y-62429D01*
X76314Y-62407D01*
X76307Y-62382D01*
X76289Y-62327D01*
X76263Y-62261D01*
X76230Y-62199D01*
X76194Y-62141D01*
X76150Y-62090D01*
X76143Y-62087D01*
X76128Y-62072D01*
X76099Y-62054D01*
X76063Y-62036D01*
X76019Y-62014D01*
X75965Y-61996D01*
X75903Y-61981D01*
X75837Y-61977D01*
X75815D01*
X75801Y-61981D01*
X75761Y-61985D01*
X75710Y-61996D01*
X75652Y-62014D01*
X75590Y-62039D01*
X75528Y-62076D01*
X75470Y-62127D01*
X75462Y-62134D01*
X75444Y-62156D01*
X75422Y-62189D01*
X75393Y-62232D01*
X75364Y-62287D01*
X75342Y-62349D01*
X75324Y-62422D01*
X75317Y-62502D01*
Y-62505D01*
Y-62512D01*
Y-62524D01*
X75320Y-62538D01*
X75324Y-62578D01*
X75335Y-62625D01*
X75349Y-62684D01*
X75375Y-62742D01*
X75411Y-62800D01*
X75459Y-62855D01*
X75466Y-62862D01*
X75484Y-62876D01*
X75513Y-62898D01*
X75553Y-62924D01*
X75604Y-62949D01*
X75666Y-62971D01*
X75735Y-62986D01*
X75812Y-62993D01*
X75845D01*
X75870Y-62989D01*
X75903Y-62986D01*
X75939Y-62979D01*
X75983Y-62971D01*
X76030Y-62960D01*
X75994Y-63233D01*
X75976D01*
X75961Y-63230D01*
X75914D01*
X75874Y-63237D01*
X75826Y-63244D01*
X75772Y-63255D01*
X75710Y-63273D01*
X75652Y-63299D01*
X75590Y-63332D01*
X75586D01*
X75582Y-63335D01*
X75564Y-63350D01*
X75539Y-63375D01*
X75510Y-63408D01*
X75481Y-63455D01*
X75455Y-63510D01*
X75437Y-63572D01*
X75430Y-63608D01*
Y-63648D01*
Y-63652D01*
Y-63656D01*
Y-63677D01*
X75437Y-63706D01*
X75444Y-63747D01*
X75459Y-63790D01*
X75477Y-63837D01*
X75506Y-63885D01*
X75546Y-63929D01*
X75550Y-63932D01*
X75568Y-63947D01*
X75593Y-63965D01*
X75626Y-63987D01*
X75670Y-64005D01*
X75721Y-64023D01*
X75779Y-64038D01*
X75845Y-64041D01*
X75874D01*
X75906Y-64034D01*
X75950Y-64027D01*
X75997Y-64012D01*
X76045Y-63994D01*
X76096Y-63965D01*
X76143Y-63929D01*
X76147Y-63925D01*
X76161Y-63907D01*
X76183Y-63881D01*
X76209Y-63845D01*
X76234Y-63797D01*
X76259Y-63739D01*
X76281Y-63670D01*
X76296Y-63590D01*
X76605Y-63645D01*
Y-63648D01*
X76602Y-63659D01*
X76598Y-63674D01*
X76594Y-63696D01*
X76587Y-63721D01*
X76576Y-63750D01*
X76554Y-63819D01*
X76518Y-63899D01*
X76474Y-63980D01*
X76420Y-64056D01*
X76350Y-64125D01*
X76347Y-64129D01*
X76340Y-64132D01*
X76329Y-64140D01*
X76314Y-64151D01*
X76296Y-64165D01*
X76270Y-64180D01*
X76245Y-64194D01*
X76212Y-64212D01*
X76139Y-64241D01*
X76056Y-64271D01*
X75957Y-64289D01*
X75906Y-64296D01*
X75815D01*
X75775Y-64293D01*
X75728Y-64285D01*
X75670Y-64274D01*
X75604Y-64256D01*
X75539Y-64234D01*
X75473Y-64205D01*
X75470D01*
X75466Y-64201D01*
X75444Y-64191D01*
X75411Y-64169D01*
X75375Y-64143D01*
X75331Y-64107D01*
X75288Y-64067D01*
X75244Y-64020D01*
X75208Y-63965D01*
X75204Y-63958D01*
X75193Y-63939D01*
X75178Y-63907D01*
X75160Y-63867D01*
X75142Y-63819D01*
X75127Y-63765D01*
X75116Y-63703D01*
X75113Y-63641D01*
Y-63634D01*
Y-63612D01*
X75116Y-63583D01*
X75124Y-63543D01*
X75135Y-63495D01*
X75153Y-63444D01*
X75175Y-63393D01*
X75204Y-63342D01*
X75208Y-63335D01*
X75218Y-63321D01*
X75240Y-63295D01*
X75269Y-63266D01*
X75306Y-63233D01*
X75349Y-63197D01*
X75400Y-63164D01*
X75462Y-63131D01*
X75459D01*
X75451Y-63128D01*
X75441Y-63124D01*
X75426Y-63120D01*
X75386Y-63106D01*
X75335Y-63084D01*
X75277Y-63055D01*
X75218Y-63019D01*
X75164Y-62971D01*
X75113Y-62917D01*
X75109Y-62909D01*
X75095Y-62888D01*
X75073Y-62851D01*
X75051Y-62804D01*
X75029Y-62745D01*
X75007Y-62676D01*
X74993Y-62596D01*
X74989Y-62509D01*
Y-62505D01*
Y-62494D01*
Y-62476D01*
X74993Y-62454D01*
X74996Y-62425D01*
X75004Y-62392D01*
X75011Y-62356D01*
X75018Y-62316D01*
X75047Y-62229D01*
X75069Y-62181D01*
X75091Y-62138D01*
X75120Y-62090D01*
X75153Y-62043D01*
X75189Y-61996D01*
X75233Y-61952D01*
X75237Y-61948D01*
X75244Y-61941D01*
X75258Y-61930D01*
X75277Y-61916D01*
X75299Y-61897D01*
X75328Y-61879D01*
X75360Y-61857D01*
X75400Y-61839D01*
X75441Y-61817D01*
X75488Y-61796D01*
X75535Y-61777D01*
X75590Y-61759D01*
X75648Y-61744D01*
X75710Y-61734D01*
X75772Y-61726D01*
X75841Y-61723D01*
X75874D01*
X75896Y-61726D01*
D02*
G37*
G36*
X79998D02*
X80031D01*
X80071Y-61730D01*
X80114Y-61737D01*
X80165Y-61744D01*
X80271Y-61763D01*
X80380Y-61792D01*
X80489Y-61832D01*
X80540Y-61857D01*
X80591Y-61887D01*
X80595Y-61890D01*
X80602Y-61894D01*
X80617Y-61905D01*
X80631Y-61919D01*
X80653Y-61934D01*
X80678Y-61956D01*
X80708Y-61981D01*
X80737Y-62010D01*
X80766Y-62043D01*
X80799Y-62076D01*
X80864Y-62160D01*
X80926Y-62258D01*
X80981Y-62367D01*
Y-62371D01*
X80988Y-62382D01*
X80992Y-62400D01*
X81002Y-62422D01*
X81010Y-62451D01*
X81021Y-62487D01*
X81035Y-62527D01*
X81046Y-62571D01*
X81057Y-62618D01*
X81072Y-62673D01*
X81090Y-62786D01*
X81104Y-62913D01*
X81112Y-63044D01*
Y-63048D01*
Y-63062D01*
Y-63084D01*
X81108Y-63109D01*
Y-63146D01*
X81104Y-63182D01*
X81101Y-63230D01*
X81093Y-63277D01*
X81075Y-63383D01*
X81050Y-63499D01*
X81013Y-63616D01*
X80962Y-63728D01*
X80959Y-63732D01*
X80955Y-63743D01*
X80948Y-63757D01*
X80933Y-63776D01*
X80919Y-63801D01*
X80901Y-63830D01*
X80853Y-63896D01*
X80791Y-63968D01*
X80718Y-64041D01*
X80635Y-64114D01*
X80537Y-64176D01*
X80533Y-64180D01*
X80522Y-64183D01*
X80507Y-64191D01*
X80489Y-64201D01*
X80460Y-64212D01*
X80431Y-64223D01*
X80395Y-64238D01*
X80354Y-64253D01*
X80311Y-64267D01*
X80264Y-64282D01*
X80162Y-64303D01*
X80045Y-64322D01*
X79925Y-64329D01*
X79889D01*
X79863Y-64325D01*
X79830Y-64322D01*
X79790Y-64318D01*
X79750Y-64314D01*
X79703Y-64303D01*
X79605Y-64282D01*
X79495Y-64249D01*
X79441Y-64227D01*
X79390Y-64201D01*
X79339Y-64169D01*
X79288Y-64136D01*
X79284Y-64132D01*
X79277Y-64129D01*
X79263Y-64118D01*
X79244Y-64100D01*
X79226Y-64081D01*
X79201Y-64056D01*
X79175Y-64027D01*
X79146Y-63998D01*
X79117Y-63961D01*
X79088Y-63918D01*
X79055Y-63874D01*
X79026Y-63827D01*
X79000Y-63772D01*
X78971Y-63717D01*
X78949Y-63659D01*
X78928Y-63594D01*
X79255Y-63517D01*
Y-63521D01*
X79259Y-63528D01*
X79266Y-63543D01*
X79273Y-63561D01*
X79281Y-63583D01*
X79292Y-63612D01*
X79321Y-63670D01*
X79357Y-63736D01*
X79401Y-63801D01*
X79455Y-63863D01*
X79514Y-63918D01*
X79521Y-63925D01*
X79543Y-63939D01*
X79579Y-63958D01*
X79627Y-63983D01*
X79688Y-64005D01*
X79757Y-64027D01*
X79841Y-64041D01*
X79932Y-64045D01*
X79961D01*
X79980Y-64041D01*
X80005D01*
X80034Y-64038D01*
X80103Y-64027D01*
X80180Y-64012D01*
X80260Y-63987D01*
X80344Y-63950D01*
X80420Y-63903D01*
X80424D01*
X80427Y-63896D01*
X80453Y-63877D01*
X80485Y-63848D01*
X80526Y-63805D01*
X80573Y-63750D01*
X80617Y-63688D01*
X80657Y-63612D01*
X80693Y-63528D01*
Y-63525D01*
X80697Y-63517D01*
X80700Y-63506D01*
X80704Y-63488D01*
X80711Y-63466D01*
X80718Y-63441D01*
X80729Y-63379D01*
X80744Y-63306D01*
X80759Y-63226D01*
X80766Y-63139D01*
X80769Y-63044D01*
Y-63040D01*
Y-63029D01*
Y-63011D01*
Y-62989D01*
X80766Y-62964D01*
Y-62931D01*
X80762Y-62895D01*
X80759Y-62855D01*
X80748Y-62767D01*
X80729Y-62673D01*
X80708Y-62578D01*
X80678Y-62483D01*
Y-62480D01*
X80675Y-62472D01*
X80668Y-62462D01*
X80660Y-62443D01*
X80638Y-62400D01*
X80606Y-62349D01*
X80566Y-62291D01*
X80515Y-62229D01*
X80456Y-62174D01*
X80387Y-62123D01*
X80384D01*
X80376Y-62119D01*
X80365Y-62112D01*
X80351Y-62105D01*
X80333Y-62098D01*
X80311Y-62087D01*
X80260Y-62065D01*
X80194Y-62043D01*
X80121Y-62025D01*
X80041Y-62010D01*
X79958Y-62007D01*
X79932D01*
X79910Y-62010D01*
X79885D01*
X79859Y-62014D01*
X79794Y-62028D01*
X79717Y-62047D01*
X79641Y-62076D01*
X79561Y-62116D01*
X79521Y-62138D01*
X79484Y-62167D01*
X79481Y-62170D01*
X79477Y-62174D01*
X79466Y-62185D01*
X79452Y-62196D01*
X79437Y-62214D01*
X79419Y-62236D01*
X79397Y-62258D01*
X79379Y-62287D01*
X79357Y-62320D01*
X79332Y-62356D01*
X79310Y-62392D01*
X79288Y-62436D01*
X79270Y-62483D01*
X79252Y-62534D01*
X79233Y-62589D01*
X79219Y-62647D01*
X78884Y-62564D01*
Y-62560D01*
X78888Y-62545D01*
X78895Y-62524D01*
X78906Y-62494D01*
X78917Y-62462D01*
X78931Y-62422D01*
X78949Y-62378D01*
X78971Y-62331D01*
X79022Y-62229D01*
X79088Y-62127D01*
X79128Y-62076D01*
X79168Y-62025D01*
X79211Y-61981D01*
X79263Y-61937D01*
X79266Y-61934D01*
X79273Y-61927D01*
X79292Y-61919D01*
X79310Y-61905D01*
X79339Y-61887D01*
X79368Y-61868D01*
X79408Y-61850D01*
X79448Y-61832D01*
X79495Y-61810D01*
X79546Y-61792D01*
X79601Y-61774D01*
X79659Y-61755D01*
X79721Y-61741D01*
X79787Y-61734D01*
X79856Y-61726D01*
X79929Y-61723D01*
X79969D01*
X79998Y-61726D01*
D02*
G37*
G36*
X77745Y-63736D02*
X77748Y-63732D01*
X77766Y-63717D01*
X77788Y-63696D01*
X77825Y-63670D01*
X77865Y-63637D01*
X77916Y-63601D01*
X77974Y-63561D01*
X78039Y-63521D01*
X78043D01*
X78047Y-63517D01*
X78069Y-63503D01*
X78105Y-63484D01*
X78149Y-63463D01*
X78200Y-63437D01*
X78254Y-63412D01*
X78309Y-63386D01*
X78363Y-63364D01*
Y-63663D01*
X78360D01*
X78352Y-63670D01*
X78338Y-63674D01*
X78320Y-63685D01*
X78298Y-63696D01*
X78272Y-63710D01*
X78211Y-63747D01*
X78138Y-63787D01*
X78065Y-63837D01*
X77988Y-63896D01*
X77912Y-63958D01*
X77908Y-63961D01*
X77905Y-63965D01*
X77894Y-63976D01*
X77879Y-63987D01*
X77846Y-64023D01*
X77803Y-64067D01*
X77759Y-64118D01*
X77712Y-64176D01*
X77672Y-64234D01*
X77635Y-64296D01*
X77435D01*
Y-61766D01*
X77745D01*
Y-63736D01*
D02*
G37*
G36*
X457836Y-74549D02*
X457865Y-74553D01*
X457902Y-74556D01*
X457942Y-74564D01*
X457982Y-74571D01*
X458077Y-74597D01*
X458171Y-74633D01*
X458218Y-74655D01*
X458266Y-74680D01*
X458310Y-74713D01*
X458350Y-74749D01*
X458353Y-74753D01*
X458360Y-74757D01*
X458368Y-74771D01*
X458382Y-74786D01*
X458400Y-74804D01*
X458419Y-74830D01*
X458437Y-74855D01*
X458459Y-74888D01*
X458495Y-74957D01*
X458532Y-75044D01*
X458546Y-75088D01*
X458553Y-75139D01*
X458561Y-75190D01*
X458564Y-75244D01*
Y-75252D01*
Y-75270D01*
X458561Y-75299D01*
X458557Y-75339D01*
X458550Y-75383D01*
X458535Y-75434D01*
X458521Y-75488D01*
X458499Y-75543D01*
X458495Y-75550D01*
X458488Y-75568D01*
X458473Y-75598D01*
X458452Y-75638D01*
X458422Y-75681D01*
X458386Y-75736D01*
X458342Y-75791D01*
X458291Y-75852D01*
X458284Y-75860D01*
X458266Y-75881D01*
X458248Y-75900D01*
X458229Y-75918D01*
X458208Y-75940D01*
X458179Y-75969D01*
X458149Y-75998D01*
X458113Y-76031D01*
X458077Y-76067D01*
X458033Y-76107D01*
X457986Y-76147D01*
X457935Y-76195D01*
X457876Y-76242D01*
X457818Y-76293D01*
X457815Y-76296D01*
X457807Y-76304D01*
X457793Y-76315D01*
X457774Y-76329D01*
X457753Y-76351D01*
X457727Y-76373D01*
X457669Y-76420D01*
X457607Y-76475D01*
X457549Y-76529D01*
X457498Y-76577D01*
X457476Y-76595D01*
X457458Y-76613D01*
X457454Y-76617D01*
X457443Y-76628D01*
X457429Y-76642D01*
X457410Y-76664D01*
X457392Y-76690D01*
X457370Y-76715D01*
X457327Y-76777D01*
X458568D01*
Y-77075D01*
X456897D01*
Y-77072D01*
Y-77057D01*
Y-77035D01*
X456901Y-77006D01*
X456905Y-76973D01*
X456912Y-76937D01*
X456919Y-76901D01*
X456934Y-76861D01*
Y-76857D01*
X456937Y-76853D01*
X456945Y-76832D01*
X456959Y-76799D01*
X456981Y-76755D01*
X457010Y-76704D01*
X457046Y-76646D01*
X457087Y-76588D01*
X457137Y-76526D01*
Y-76522D01*
X457145Y-76518D01*
X457163Y-76497D01*
X457196Y-76464D01*
X457243Y-76417D01*
X457298Y-76362D01*
X457367Y-76296D01*
X457450Y-76224D01*
X457542Y-76147D01*
X457545Y-76144D01*
X457560Y-76133D01*
X457582Y-76114D01*
X457607Y-76093D01*
X457640Y-76064D01*
X457680Y-76031D01*
X457720Y-75994D01*
X457767Y-75954D01*
X457858Y-75867D01*
X457949Y-75780D01*
X457993Y-75736D01*
X458033Y-75692D01*
X458069Y-75652D01*
X458098Y-75612D01*
Y-75608D01*
X458106Y-75605D01*
X458113Y-75594D01*
X458120Y-75579D01*
X458146Y-75539D01*
X458175Y-75492D01*
X458200Y-75434D01*
X458226Y-75372D01*
X458240Y-75303D01*
X458248Y-75237D01*
Y-75234D01*
Y-75230D01*
X458244Y-75208D01*
X458240Y-75172D01*
X458229Y-75132D01*
X458215Y-75081D01*
X458189Y-75030D01*
X458157Y-74979D01*
X458113Y-74928D01*
X458106Y-74920D01*
X458087Y-74906D01*
X458062Y-74888D01*
X458022Y-74862D01*
X457971Y-74840D01*
X457913Y-74819D01*
X457844Y-74804D01*
X457767Y-74800D01*
X457745D01*
X457731Y-74804D01*
X457687Y-74808D01*
X457636Y-74819D01*
X457582Y-74833D01*
X457520Y-74859D01*
X457461Y-74891D01*
X457407Y-74935D01*
X457400Y-74942D01*
X457385Y-74961D01*
X457363Y-74990D01*
X457341Y-75033D01*
X457316Y-75084D01*
X457294Y-75150D01*
X457279Y-75223D01*
X457272Y-75306D01*
X456955Y-75274D01*
Y-75270D01*
X456959Y-75259D01*
Y-75241D01*
X456963Y-75215D01*
X456970Y-75186D01*
X456977Y-75153D01*
X456988Y-75113D01*
X456999Y-75073D01*
X457028Y-74986D01*
X457072Y-74899D01*
X457097Y-74855D01*
X457130Y-74811D01*
X457163Y-74771D01*
X457199Y-74735D01*
X457203Y-74731D01*
X457210Y-74728D01*
X457221Y-74717D01*
X457239Y-74706D01*
X457261Y-74691D01*
X457287Y-74677D01*
X457316Y-74658D01*
X457352Y-74640D01*
X457392Y-74622D01*
X457436Y-74604D01*
X457483Y-74589D01*
X457534Y-74575D01*
X457589Y-74564D01*
X457647Y-74553D01*
X457709Y-74549D01*
X457774Y-74546D01*
X457811D01*
X457836Y-74549D01*
D02*
G37*
G36*
X455561Y-74560D02*
X455634Y-74564D01*
X455707Y-74571D01*
X455780Y-74582D01*
X455842Y-74593D01*
X455845D01*
X455853Y-74597D01*
X455863D01*
X455878Y-74604D01*
X455918Y-74615D01*
X455969Y-74633D01*
X456027Y-74658D01*
X456089Y-74691D01*
X456151Y-74728D01*
X456209Y-74775D01*
X456213Y-74779D01*
X456216Y-74782D01*
X456227Y-74793D01*
X456242Y-74804D01*
X456278Y-74840D01*
X456322Y-74891D01*
X456369Y-74953D01*
X456420Y-75026D01*
X456468Y-75110D01*
X456508Y-75204D01*
Y-75208D01*
X456511Y-75215D01*
X456519Y-75230D01*
X456522Y-75252D01*
X456533Y-75277D01*
X456540Y-75306D01*
X456548Y-75339D01*
X456559Y-75379D01*
X456570Y-75419D01*
X456577Y-75467D01*
X456595Y-75568D01*
X456606Y-75681D01*
X456610Y-75805D01*
Y-75809D01*
Y-75816D01*
Y-75834D01*
Y-75852D01*
X456606Y-75878D01*
Y-75907D01*
X456602Y-75976D01*
X456591Y-76056D01*
X456580Y-76140D01*
X456562Y-76227D01*
X456540Y-76315D01*
Y-76318D01*
X456537Y-76326D01*
X456533Y-76336D01*
X456530Y-76351D01*
X456515Y-76391D01*
X456493Y-76442D01*
X456471Y-76500D01*
X456442Y-76559D01*
X456406Y-76620D01*
X456369Y-76679D01*
X456366Y-76686D01*
X456351Y-76704D01*
X456329Y-76730D01*
X456300Y-76762D01*
X456267Y-76799D01*
X456227Y-76835D01*
X456187Y-76875D01*
X456140Y-76908D01*
X456133Y-76912D01*
X456118Y-76923D01*
X456093Y-76937D01*
X456056Y-76955D01*
X456013Y-76977D01*
X455962Y-76995D01*
X455903Y-77017D01*
X455838Y-77035D01*
X455831D01*
X455820Y-77039D01*
X455809Y-77043D01*
X455772Y-77046D01*
X455722Y-77054D01*
X455663Y-77061D01*
X455594Y-77068D01*
X455518Y-77072D01*
X455434Y-77075D01*
X454528D01*
Y-74556D01*
X455496D01*
X455561Y-74560D01*
D02*
G37*
G36*
X459795Y-74549D02*
X459842Y-74556D01*
X459897Y-74567D01*
X459955Y-74582D01*
X460017Y-74600D01*
X460075Y-74629D01*
X460079D01*
X460082Y-74633D01*
X460100Y-74644D01*
X460129Y-74662D01*
X460166Y-74688D01*
X460206Y-74724D01*
X460250Y-74764D01*
X460290Y-74811D01*
X460330Y-74866D01*
X460333Y-74873D01*
X460348Y-74891D01*
X460362Y-74924D01*
X460388Y-74971D01*
X460410Y-75026D01*
X460439Y-75088D01*
X460464Y-75161D01*
X460486Y-75241D01*
Y-75244D01*
X460490Y-75252D01*
X460494Y-75263D01*
X460497Y-75281D01*
X460501Y-75303D01*
X460504Y-75328D01*
X460512Y-75361D01*
X460515Y-75397D01*
X460523Y-75437D01*
X460526Y-75481D01*
X460530Y-75532D01*
X460537Y-75583D01*
X460541Y-75641D01*
Y-75700D01*
X460544Y-75765D01*
Y-75834D01*
Y-75838D01*
Y-75852D01*
Y-75878D01*
Y-75907D01*
X460541Y-75947D01*
Y-75991D01*
X460537Y-76038D01*
X460534Y-76089D01*
X460523Y-76205D01*
X460504Y-76326D01*
X460483Y-76442D01*
X460468Y-76497D01*
X460450Y-76551D01*
Y-76555D01*
X460446Y-76562D01*
X460439Y-76577D01*
X460432Y-76595D01*
X460424Y-76620D01*
X460410Y-76646D01*
X460381Y-76708D01*
X460344Y-76773D01*
X460297Y-76846D01*
X460242Y-76912D01*
X460177Y-76973D01*
X460173D01*
X460170Y-76981D01*
X460159Y-76988D01*
X460144Y-76995D01*
X460126Y-77006D01*
X460108Y-77021D01*
X460053Y-77046D01*
X459988Y-77072D01*
X459911Y-77097D01*
X459820Y-77112D01*
X459722Y-77119D01*
X459685D01*
X459660Y-77115D01*
X459631Y-77112D01*
X459594Y-77105D01*
X459554Y-77097D01*
X459511Y-77086D01*
X459467Y-77072D01*
X459420Y-77057D01*
X459372Y-77035D01*
X459325Y-77010D01*
X459278Y-76981D01*
X459230Y-76944D01*
X459187Y-76904D01*
X459147Y-76861D01*
X459143Y-76857D01*
X459136Y-76846D01*
X459125Y-76828D01*
X459107Y-76799D01*
X459089Y-76766D01*
X459070Y-76722D01*
X459045Y-76671D01*
X459023Y-76613D01*
X459001Y-76548D01*
X458979Y-76471D01*
X458957Y-76387D01*
X458939Y-76293D01*
X458921Y-76191D01*
X458910Y-76082D01*
X458903Y-75962D01*
X458899Y-75834D01*
Y-75831D01*
Y-75816D01*
Y-75791D01*
Y-75761D01*
X458903Y-75721D01*
Y-75678D01*
X458907Y-75630D01*
X458910Y-75576D01*
X458921Y-75463D01*
X458939Y-75343D01*
X458961Y-75223D01*
X458976Y-75168D01*
X458990Y-75113D01*
Y-75110D01*
X458994Y-75103D01*
X459001Y-75088D01*
X459008Y-75070D01*
X459016Y-75044D01*
X459030Y-75019D01*
X459059Y-74957D01*
X459096Y-74891D01*
X459143Y-74822D01*
X459198Y-74753D01*
X459263Y-74695D01*
X459267D01*
X459270Y-74688D01*
X459281Y-74680D01*
X459296Y-74673D01*
X459314Y-74658D01*
X459336Y-74647D01*
X459391Y-74618D01*
X459456Y-74593D01*
X459533Y-74567D01*
X459624Y-74553D01*
X459722Y-74546D01*
X459755D01*
X459795Y-74549D01*
D02*
G37*
G36*
X95276Y-93904D02*
X94307D01*
X94242Y-93900D01*
X94169Y-93897D01*
X94096Y-93889D01*
X94023Y-93878D01*
X93962Y-93867D01*
X93958D01*
X93951Y-93864D01*
X93940D01*
X93925Y-93856D01*
X93885Y-93845D01*
X93834Y-93827D01*
X93776Y-93802D01*
X93714Y-93769D01*
X93652Y-93733D01*
X93594Y-93685D01*
X93590Y-93682D01*
X93587Y-93678D01*
X93576Y-93667D01*
X93561Y-93656D01*
X93525Y-93620D01*
X93481Y-93569D01*
X93434Y-93507D01*
X93383Y-93434D01*
X93335Y-93350D01*
X93295Y-93256D01*
Y-93252D01*
X93292Y-93245D01*
X93284Y-93230D01*
X93281Y-93208D01*
X93270Y-93183D01*
X93263Y-93154D01*
X93255Y-93121D01*
X93244Y-93081D01*
X93234Y-93041D01*
X93226Y-92994D01*
X93208Y-92892D01*
X93197Y-92779D01*
X93194Y-92655D01*
Y-92652D01*
Y-92644D01*
Y-92626D01*
Y-92608D01*
X93197Y-92582D01*
Y-92553D01*
X93201Y-92484D01*
X93212Y-92404D01*
X93223Y-92320D01*
X93241Y-92233D01*
X93263Y-92146D01*
Y-92142D01*
X93266Y-92135D01*
X93270Y-92124D01*
X93274Y-92109D01*
X93288Y-92069D01*
X93310Y-92018D01*
X93332Y-91960D01*
X93361Y-91902D01*
X93397Y-91840D01*
X93434Y-91782D01*
X93437Y-91774D01*
X93452Y-91756D01*
X93474Y-91731D01*
X93503Y-91698D01*
X93536Y-91662D01*
X93576Y-91625D01*
X93616Y-91585D01*
X93663Y-91552D01*
X93670Y-91549D01*
X93685Y-91538D01*
X93710Y-91523D01*
X93747Y-91505D01*
X93791Y-91483D01*
X93841Y-91465D01*
X93900Y-91443D01*
X93965Y-91425D01*
X93972D01*
X93983Y-91421D01*
X93994Y-91418D01*
X94031Y-91414D01*
X94082Y-91407D01*
X94140Y-91399D01*
X94209Y-91392D01*
X94286Y-91388D01*
X94369Y-91385D01*
X95276D01*
Y-93904D01*
D02*
G37*
G36*
X91872Y-91989D02*
X92968D01*
Y-92273D01*
X91814Y-93904D01*
X91563D01*
Y-92273D01*
X91221D01*
Y-91989D01*
X91563D01*
Y-91385D01*
X91872D01*
Y-91989D01*
D02*
G37*
G36*
X98850Y-99606D02*
X98541D01*
Y-97637D01*
X98537Y-97641D01*
X98519Y-97655D01*
X98497Y-97677D01*
X98461Y-97703D01*
X98421Y-97735D01*
X98369Y-97772D01*
X98311Y-97812D01*
X98246Y-97852D01*
X98242D01*
X98238Y-97856D01*
X98217Y-97870D01*
X98180Y-97888D01*
X98137Y-97910D01*
X98086Y-97936D01*
X98031Y-97961D01*
X97976Y-97987D01*
X97922Y-98008D01*
Y-97710D01*
X97925D01*
X97933Y-97703D01*
X97947Y-97699D01*
X97966Y-97688D01*
X97987Y-97677D01*
X98013Y-97663D01*
X98075Y-97626D01*
X98147Y-97586D01*
X98220Y-97535D01*
X98297Y-97477D01*
X98373Y-97415D01*
X98377Y-97411D01*
X98380Y-97408D01*
X98391Y-97397D01*
X98406Y-97386D01*
X98439Y-97350D01*
X98482Y-97306D01*
X98526Y-97255D01*
X98573Y-97197D01*
X98613Y-97138D01*
X98650Y-97076D01*
X98850D01*
Y-99606D01*
D02*
G37*
G36*
X96473Y-97091D02*
X96506D01*
X96582Y-97095D01*
X96662Y-97106D01*
X96750Y-97117D01*
X96830Y-97135D01*
X96870Y-97146D01*
X96903Y-97157D01*
X96906D01*
X96910Y-97160D01*
X96932Y-97171D01*
X96965Y-97186D01*
X97004Y-97211D01*
X97048Y-97244D01*
X97096Y-97288D01*
X97139Y-97339D01*
X97183Y-97397D01*
Y-97400D01*
X97186Y-97404D01*
X97201Y-97426D01*
X97216Y-97462D01*
X97237Y-97510D01*
X97256Y-97564D01*
X97274Y-97630D01*
X97285Y-97699D01*
X97288Y-97775D01*
Y-97779D01*
Y-97786D01*
Y-97801D01*
X97285Y-97819D01*
Y-97845D01*
X97281Y-97870D01*
X97267Y-97932D01*
X97245Y-98005D01*
X97216Y-98081D01*
X97172Y-98158D01*
X97143Y-98194D01*
X97114Y-98230D01*
X97110Y-98234D01*
X97106Y-98238D01*
X97096Y-98249D01*
X97081Y-98260D01*
X97063Y-98274D01*
X97041Y-98289D01*
X97012Y-98307D01*
X96983Y-98329D01*
X96946Y-98347D01*
X96906Y-98365D01*
X96863Y-98387D01*
X96815Y-98405D01*
X96761Y-98420D01*
X96706Y-98438D01*
X96644Y-98449D01*
X96579Y-98460D01*
X96586Y-98463D01*
X96601Y-98471D01*
X96622Y-98485D01*
X96651Y-98500D01*
X96717Y-98540D01*
X96750Y-98565D01*
X96779Y-98587D01*
X96786Y-98594D01*
X96804Y-98613D01*
X96833Y-98642D01*
X96870Y-98678D01*
X96910Y-98729D01*
X96957Y-98784D01*
X97004Y-98849D01*
X97056Y-98922D01*
X97489Y-99606D01*
X97074D01*
X96742Y-99082D01*
Y-99079D01*
X96735Y-99071D01*
X96728Y-99060D01*
X96717Y-99046D01*
X96692Y-99006D01*
X96659Y-98955D01*
X96619Y-98900D01*
X96579Y-98842D01*
X96539Y-98787D01*
X96502Y-98736D01*
X96499Y-98733D01*
X96488Y-98718D01*
X96469Y-98696D01*
X96444Y-98671D01*
X96389Y-98616D01*
X96360Y-98591D01*
X96331Y-98569D01*
X96328Y-98565D01*
X96320Y-98562D01*
X96306Y-98554D01*
X96284Y-98544D01*
X96262Y-98533D01*
X96236Y-98522D01*
X96178Y-98503D01*
X96175D01*
X96167Y-98500D01*
X96153D01*
X96135Y-98496D01*
X96109Y-98492D01*
X96080D01*
X96040Y-98489D01*
X95610D01*
Y-99606D01*
X95275D01*
Y-97088D01*
X96444D01*
X96473Y-97091D01*
D02*
G37*
G36*
X469685Y-78897D02*
X468517D01*
X468488Y-78893D01*
X468455D01*
X468378Y-78890D01*
X468298Y-78879D01*
X468211Y-78868D01*
X468131Y-78850D01*
X468091Y-78838D01*
X468058Y-78828D01*
X468054D01*
X468051Y-78824D01*
X468029Y-78813D01*
X467996Y-78799D01*
X467956Y-78773D01*
X467912Y-78740D01*
X467865Y-78697D01*
X467821Y-78646D01*
X467778Y-78587D01*
Y-78584D01*
X467774Y-78580D01*
X467760Y-78558D01*
X467745Y-78522D01*
X467723Y-78474D01*
X467705Y-78420D01*
X467687Y-78354D01*
X467676Y-78285D01*
X467672Y-78209D01*
Y-78205D01*
Y-78198D01*
Y-78183D01*
X467676Y-78165D01*
Y-78140D01*
X467679Y-78114D01*
X467694Y-78052D01*
X467716Y-77979D01*
X467745Y-77903D01*
X467789Y-77827D01*
X467818Y-77790D01*
X467847Y-77754D01*
X467850Y-77750D01*
X467854Y-77746D01*
X467865Y-77736D01*
X467880Y-77725D01*
X467898Y-77710D01*
X467920Y-77696D01*
X467949Y-77677D01*
X467978Y-77656D01*
X468014Y-77637D01*
X468054Y-77619D01*
X468098Y-77597D01*
X468145Y-77579D01*
X468200Y-77565D01*
X468255Y-77546D01*
X468316Y-77535D01*
X468382Y-77525D01*
X468375Y-77521D01*
X468360Y-77514D01*
X468338Y-77499D01*
X468309Y-77485D01*
X468244Y-77444D01*
X468211Y-77419D01*
X468182Y-77397D01*
X468175Y-77390D01*
X468156Y-77372D01*
X468127Y-77342D01*
X468091Y-77306D01*
X468051Y-77255D01*
X468003Y-77201D01*
X467956Y-77135D01*
X467905Y-77062D01*
X467472Y-76378D01*
X467887D01*
X468218Y-76902D01*
Y-76906D01*
X468225Y-76913D01*
X468233Y-76924D01*
X468244Y-76938D01*
X468269Y-76978D01*
X468302Y-77030D01*
X468342Y-77084D01*
X468382Y-77142D01*
X468422Y-77197D01*
X468458Y-77248D01*
X468462Y-77251D01*
X468473Y-77266D01*
X468491Y-77288D01*
X468517Y-77313D01*
X468571Y-77368D01*
X468600Y-77394D01*
X468630Y-77415D01*
X468633Y-77419D01*
X468640Y-77423D01*
X468655Y-77430D01*
X468677Y-77441D01*
X468699Y-77452D01*
X468724Y-77463D01*
X468782Y-77481D01*
X468786D01*
X468793Y-77485D01*
X468808D01*
X468826Y-77488D01*
X468852Y-77492D01*
X468881D01*
X468921Y-77495D01*
X469350D01*
Y-76378D01*
X469685D01*
Y-78897D01*
D02*
G37*
G36*
X466900Y-76381D02*
Y-76393D01*
Y-76407D01*
X466897Y-76429D01*
Y-76458D01*
X466893Y-76494D01*
X466890Y-76534D01*
X466886Y-76578D01*
X466879Y-76629D01*
X466871Y-76680D01*
X466860Y-76742D01*
X466850Y-76804D01*
X466839Y-76869D01*
X466824Y-76942D01*
X466788Y-77091D01*
Y-77095D01*
X466784Y-77109D01*
X466777Y-77131D01*
X466766Y-77164D01*
X466755Y-77201D01*
X466740Y-77244D01*
X466726Y-77295D01*
X466704Y-77350D01*
X466682Y-77412D01*
X466660Y-77473D01*
X466606Y-77612D01*
X466540Y-77758D01*
X466467Y-77903D01*
X466464Y-77907D01*
X466456Y-77921D01*
X466445Y-77939D01*
X466431Y-77969D01*
X466413Y-78001D01*
X466387Y-78041D01*
X466362Y-78085D01*
X466333Y-78132D01*
X466263Y-78238D01*
X466191Y-78347D01*
X466107Y-78460D01*
X466020Y-78566D01*
X467254D01*
Y-78864D01*
X465623D01*
Y-78620D01*
X465626Y-78616D01*
X465634Y-78609D01*
X465648Y-78595D01*
X465663Y-78573D01*
X465685Y-78547D01*
X465714Y-78518D01*
X465743Y-78482D01*
X465776Y-78438D01*
X465808Y-78395D01*
X465848Y-78343D01*
X465889Y-78285D01*
X465929Y-78227D01*
X465972Y-78162D01*
X466016Y-78092D01*
X466060Y-78016D01*
X466103Y-77939D01*
X466107Y-77936D01*
X466114Y-77921D01*
X466125Y-77899D01*
X466143Y-77867D01*
X466162Y-77827D01*
X466183Y-77783D01*
X466209Y-77732D01*
X466234Y-77674D01*
X466263Y-77608D01*
X466296Y-77543D01*
X466325Y-77470D01*
X466355Y-77394D01*
X466413Y-77237D01*
X466467Y-77069D01*
Y-77066D01*
X466471Y-77055D01*
X466475Y-77037D01*
X466482Y-77015D01*
X466489Y-76986D01*
X466497Y-76949D01*
X466507Y-76909D01*
X466515Y-76866D01*
X466526Y-76815D01*
X466537Y-76760D01*
X466555Y-76644D01*
X466573Y-76516D01*
X466584Y-76378D01*
X466900D01*
Y-76381D01*
D02*
G37*
G36*
X464942D02*
Y-76393D01*
Y-76407D01*
X464938Y-76429D01*
Y-76458D01*
X464935Y-76494D01*
X464931Y-76534D01*
X464928Y-76578D01*
X464920Y-76629D01*
X464913Y-76680D01*
X464902Y-76742D01*
X464891Y-76804D01*
X464880Y-76869D01*
X464866Y-76942D01*
X464829Y-77091D01*
Y-77095D01*
X464826Y-77109D01*
X464818Y-77131D01*
X464808Y-77164D01*
X464797Y-77201D01*
X464782Y-77244D01*
X464768Y-77295D01*
X464746Y-77350D01*
X464724Y-77412D01*
X464702Y-77473D01*
X464647Y-77612D01*
X464582Y-77758D01*
X464509Y-77903D01*
X464505Y-77907D01*
X464498Y-77921D01*
X464487Y-77939D01*
X464473Y-77969D01*
X464454Y-78001D01*
X464429Y-78041D01*
X464403Y-78085D01*
X464374Y-78132D01*
X464305Y-78238D01*
X464232Y-78347D01*
X464149Y-78460D01*
X464061Y-78566D01*
X465295D01*
Y-78864D01*
X463664D01*
Y-78620D01*
X463668Y-78616D01*
X463675Y-78609D01*
X463690Y-78595D01*
X463705Y-78573D01*
X463726Y-78547D01*
X463756Y-78518D01*
X463785Y-78482D01*
X463817Y-78438D01*
X463850Y-78395D01*
X463890Y-78343D01*
X463930Y-78285D01*
X463970Y-78227D01*
X464014Y-78162D01*
X464058Y-78092D01*
X464101Y-78016D01*
X464145Y-77939D01*
X464149Y-77936D01*
X464156Y-77921D01*
X464167Y-77899D01*
X464185Y-77867D01*
X464203Y-77827D01*
X464225Y-77783D01*
X464251Y-77732D01*
X464276Y-77674D01*
X464305Y-77608D01*
X464338Y-77543D01*
X464367Y-77470D01*
X464396Y-77394D01*
X464454Y-77237D01*
X464509Y-77069D01*
Y-77066D01*
X464513Y-77055D01*
X464516Y-77037D01*
X464524Y-77015D01*
X464531Y-76986D01*
X464538Y-76949D01*
X464549Y-76909D01*
X464556Y-76866D01*
X464567Y-76815D01*
X464578Y-76760D01*
X464596Y-76644D01*
X464615Y-76516D01*
X464626Y-76378D01*
X464942D01*
Y-76381D01*
D02*
G37*
G36*
X29595Y-9846D02*
X29628D01*
X29668Y-9850D01*
X29711Y-9857D01*
X29762Y-9864D01*
X29868Y-9883D01*
X29977Y-9912D01*
X30086Y-9952D01*
X30137Y-9977D01*
X30188Y-10006D01*
X30192Y-10010D01*
X30199Y-10014D01*
X30214Y-10024D01*
X30228Y-10039D01*
X30250Y-10054D01*
X30275Y-10075D01*
X30305Y-10101D01*
X30334Y-10130D01*
X30363Y-10163D01*
X30396Y-10196D01*
X30461Y-10279D01*
X30523Y-10378D01*
X30578Y-10487D01*
Y-10490D01*
X30585Y-10501D01*
X30589Y-10520D01*
X30599Y-10541D01*
X30607Y-10571D01*
X30618Y-10607D01*
X30632Y-10647D01*
X30643Y-10691D01*
X30654Y-10738D01*
X30669Y-10792D01*
X30687Y-10905D01*
X30701Y-11033D01*
X30709Y-11164D01*
Y-11167D01*
Y-11182D01*
Y-11204D01*
X30705Y-11229D01*
Y-11266D01*
X30701Y-11302D01*
X30698Y-11349D01*
X30691Y-11397D01*
X30672Y-11502D01*
X30647Y-11619D01*
X30610Y-11735D01*
X30560Y-11848D01*
X30556Y-11852D01*
X30552Y-11863D01*
X30545Y-11877D01*
X30530Y-11895D01*
X30516Y-11921D01*
X30498Y-11950D01*
X30450Y-12016D01*
X30388Y-12088D01*
X30316Y-12161D01*
X30232Y-12234D01*
X30134Y-12296D01*
X30130Y-12299D01*
X30119Y-12303D01*
X30105Y-12310D01*
X30086Y-12321D01*
X30057Y-12332D01*
X30028Y-12343D01*
X29992Y-12358D01*
X29952Y-12372D01*
X29908Y-12387D01*
X29861Y-12401D01*
X29759Y-12423D01*
X29642Y-12442D01*
X29522Y-12449D01*
X29486D01*
X29460Y-12445D01*
X29427Y-12442D01*
X29387Y-12438D01*
X29347Y-12434D01*
X29300Y-12423D01*
X29202Y-12401D01*
X29092Y-12369D01*
X29038Y-12347D01*
X28987Y-12321D01*
X28936Y-12289D01*
X28885Y-12256D01*
X28881Y-12252D01*
X28874Y-12248D01*
X28860Y-12238D01*
X28841Y-12219D01*
X28823Y-12201D01*
X28798Y-12176D01*
X28772Y-12147D01*
X28743Y-12117D01*
X28714Y-12081D01*
X28685Y-12037D01*
X28652Y-11994D01*
X28623Y-11946D01*
X28598Y-11892D01*
X28568Y-11837D01*
X28547Y-11779D01*
X28525Y-11714D01*
X28852Y-11637D01*
Y-11641D01*
X28856Y-11648D01*
X28863Y-11663D01*
X28870Y-11681D01*
X28878Y-11703D01*
X28889Y-11732D01*
X28918Y-11790D01*
X28954Y-11855D01*
X28998Y-11921D01*
X29052Y-11983D01*
X29111Y-12037D01*
X29118Y-12045D01*
X29140Y-12059D01*
X29176Y-12077D01*
X29224Y-12103D01*
X29285Y-12125D01*
X29355Y-12147D01*
X29438Y-12161D01*
X29529Y-12165D01*
X29559D01*
X29577Y-12161D01*
X29602D01*
X29631Y-12157D01*
X29700Y-12147D01*
X29777Y-12132D01*
X29857Y-12107D01*
X29941Y-12070D01*
X30017Y-12023D01*
X30021D01*
X30024Y-12016D01*
X30050Y-11997D01*
X30083Y-11968D01*
X30123Y-11925D01*
X30170Y-11870D01*
X30214Y-11808D01*
X30254Y-11732D01*
X30290Y-11648D01*
Y-11644D01*
X30294Y-11637D01*
X30297Y-11626D01*
X30301Y-11608D01*
X30308Y-11586D01*
X30316Y-11561D01*
X30327Y-11499D01*
X30341Y-11426D01*
X30356Y-11346D01*
X30363Y-11259D01*
X30367Y-11164D01*
Y-11160D01*
Y-11149D01*
Y-11131D01*
Y-11109D01*
X30363Y-11084D01*
Y-11051D01*
X30359Y-11015D01*
X30356Y-10975D01*
X30345Y-10887D01*
X30327Y-10792D01*
X30305Y-10698D01*
X30275Y-10603D01*
Y-10600D01*
X30272Y-10592D01*
X30265Y-10581D01*
X30257Y-10563D01*
X30235Y-10520D01*
X30203Y-10469D01*
X30163Y-10410D01*
X30112Y-10348D01*
X30053Y-10294D01*
X29984Y-10243D01*
X29981D01*
X29973Y-10239D01*
X29963Y-10232D01*
X29948Y-10225D01*
X29930Y-10217D01*
X29908Y-10206D01*
X29857Y-10185D01*
X29791Y-10163D01*
X29719Y-10145D01*
X29638Y-10130D01*
X29555Y-10126D01*
X29529D01*
X29507Y-10130D01*
X29482D01*
X29456Y-10134D01*
X29391Y-10148D01*
X29315Y-10166D01*
X29238Y-10196D01*
X29158Y-10236D01*
X29118Y-10257D01*
X29082Y-10287D01*
X29078Y-10290D01*
X29074Y-10294D01*
X29063Y-10305D01*
X29049Y-10316D01*
X29034Y-10334D01*
X29016Y-10356D01*
X28994Y-10378D01*
X28976Y-10407D01*
X28954Y-10439D01*
X28929Y-10476D01*
X28907Y-10512D01*
X28885Y-10556D01*
X28867Y-10603D01*
X28849Y-10654D01*
X28831Y-10709D01*
X28816Y-10767D01*
X28481Y-10683D01*
Y-10680D01*
X28485Y-10665D01*
X28492Y-10643D01*
X28503Y-10614D01*
X28514Y-10581D01*
X28528Y-10541D01*
X28547Y-10498D01*
X28568Y-10450D01*
X28619Y-10348D01*
X28685Y-10246D01*
X28725Y-10196D01*
X28765Y-10145D01*
X28809Y-10101D01*
X28860Y-10057D01*
X28863Y-10054D01*
X28870Y-10046D01*
X28889Y-10039D01*
X28907Y-10024D01*
X28936Y-10006D01*
X28965Y-9988D01*
X29005Y-9970D01*
X29045Y-9952D01*
X29092Y-9930D01*
X29144Y-9912D01*
X29198Y-9893D01*
X29256Y-9875D01*
X29318Y-9861D01*
X29384Y-9853D01*
X29453Y-9846D01*
X29526Y-9843D01*
X29566D01*
X29595Y-9846D01*
D02*
G37*
G36*
X27342Y-11855D02*
X27345Y-11852D01*
X27363Y-11837D01*
X27385Y-11815D01*
X27422Y-11790D01*
X27462Y-11757D01*
X27513Y-11721D01*
X27571Y-11681D01*
X27637Y-11641D01*
X27640D01*
X27644Y-11637D01*
X27666Y-11622D01*
X27702Y-11604D01*
X27746Y-11582D01*
X27797Y-11557D01*
X27851Y-11531D01*
X27906Y-11506D01*
X27961Y-11484D01*
Y-11783D01*
X27957D01*
X27950Y-11790D01*
X27935Y-11794D01*
X27917Y-11804D01*
X27895Y-11815D01*
X27869Y-11830D01*
X27808Y-11866D01*
X27735Y-11906D01*
X27662Y-11957D01*
X27586Y-12016D01*
X27509Y-12077D01*
X27505Y-12081D01*
X27502Y-12085D01*
X27491Y-12096D01*
X27476Y-12107D01*
X27444Y-12143D01*
X27400Y-12187D01*
X27356Y-12238D01*
X27309Y-12296D01*
X27269Y-12354D01*
X27233Y-12416D01*
X27032D01*
Y-9886D01*
X27342D01*
Y-11855D01*
D02*
G37*
G36*
X26283Y-9890D02*
Y-9904D01*
Y-9926D01*
X26279Y-9955D01*
X26275Y-9988D01*
X26268Y-10024D01*
X26261Y-10061D01*
X26246Y-10101D01*
Y-10105D01*
X26242Y-10108D01*
X26235Y-10130D01*
X26221Y-10163D01*
X26199Y-10206D01*
X26170Y-10257D01*
X26133Y-10316D01*
X26093Y-10374D01*
X26042Y-10436D01*
Y-10439D01*
X26035Y-10443D01*
X26017Y-10465D01*
X25984Y-10498D01*
X25937Y-10545D01*
X25882Y-10600D01*
X25813Y-10665D01*
X25729Y-10738D01*
X25638Y-10814D01*
X25635Y-10818D01*
X25620Y-10829D01*
X25598Y-10847D01*
X25573Y-10869D01*
X25540Y-10898D01*
X25500Y-10931D01*
X25460Y-10967D01*
X25412Y-11007D01*
X25321Y-11095D01*
X25231Y-11182D01*
X25187Y-11226D01*
X25147Y-11269D01*
X25110Y-11309D01*
X25081Y-11349D01*
Y-11353D01*
X25074Y-11357D01*
X25067Y-11368D01*
X25059Y-11382D01*
X25034Y-11422D01*
X25005Y-11470D01*
X24979Y-11528D01*
X24954Y-11590D01*
X24939Y-11659D01*
X24932Y-11724D01*
Y-11728D01*
Y-11732D01*
X24936Y-11754D01*
X24939Y-11790D01*
X24950Y-11830D01*
X24965Y-11881D01*
X24990Y-11932D01*
X25023Y-11983D01*
X25067Y-12034D01*
X25074Y-12041D01*
X25092Y-12056D01*
X25118Y-12074D01*
X25158Y-12099D01*
X25209Y-12121D01*
X25267Y-12143D01*
X25336Y-12157D01*
X25412Y-12161D01*
X25434D01*
X25449Y-12157D01*
X25493Y-12154D01*
X25543Y-12143D01*
X25598Y-12128D01*
X25660Y-12103D01*
X25718Y-12070D01*
X25773Y-12026D01*
X25780Y-12019D01*
X25795Y-12001D01*
X25817Y-11972D01*
X25838Y-11928D01*
X25864Y-11877D01*
X25886Y-11812D01*
X25900Y-11739D01*
X25907Y-11655D01*
X26224Y-11688D01*
Y-11692D01*
X26221Y-11703D01*
Y-11721D01*
X26217Y-11746D01*
X26210Y-11775D01*
X26202Y-11808D01*
X26191Y-11848D01*
X26180Y-11888D01*
X26151Y-11975D01*
X26108Y-12063D01*
X26082Y-12107D01*
X26050Y-12150D01*
X26017Y-12190D01*
X25980Y-12227D01*
X25977Y-12230D01*
X25969Y-12234D01*
X25958Y-12245D01*
X25940Y-12256D01*
X25918Y-12270D01*
X25893Y-12285D01*
X25864Y-12303D01*
X25828Y-12321D01*
X25787Y-12340D01*
X25744Y-12358D01*
X25696Y-12372D01*
X25646Y-12387D01*
X25591Y-12398D01*
X25533Y-12409D01*
X25471Y-12412D01*
X25405Y-12416D01*
X25369D01*
X25343Y-12412D01*
X25314Y-12409D01*
X25278Y-12405D01*
X25238Y-12398D01*
X25198Y-12391D01*
X25103Y-12365D01*
X25008Y-12329D01*
X24961Y-12307D01*
X24914Y-12281D01*
X24870Y-12248D01*
X24830Y-12212D01*
X24826Y-12208D01*
X24819Y-12205D01*
X24812Y-12190D01*
X24797Y-12176D01*
X24779Y-12157D01*
X24761Y-12132D01*
X24743Y-12107D01*
X24721Y-12074D01*
X24685Y-12005D01*
X24648Y-11917D01*
X24633Y-11874D01*
X24626Y-11823D01*
X24619Y-11772D01*
X24615Y-11717D01*
Y-11710D01*
Y-11692D01*
X24619Y-11663D01*
X24623Y-11622D01*
X24630Y-11579D01*
X24645Y-11528D01*
X24659Y-11473D01*
X24681Y-11419D01*
X24685Y-11411D01*
X24692Y-11393D01*
X24706Y-11364D01*
X24728Y-11324D01*
X24757Y-11280D01*
X24794Y-11226D01*
X24837Y-11171D01*
X24888Y-11109D01*
X24896Y-11102D01*
X24914Y-11080D01*
X24932Y-11062D01*
X24950Y-11044D01*
X24972Y-11022D01*
X25001Y-10993D01*
X25030Y-10964D01*
X25067Y-10931D01*
X25103Y-10894D01*
X25147Y-10854D01*
X25194Y-10814D01*
X25245Y-10767D01*
X25303Y-10720D01*
X25361Y-10669D01*
X25365Y-10665D01*
X25372Y-10658D01*
X25387Y-10647D01*
X25405Y-10632D01*
X25427Y-10610D01*
X25453Y-10589D01*
X25511Y-10541D01*
X25573Y-10487D01*
X25631Y-10432D01*
X25682Y-10385D01*
X25704Y-10367D01*
X25722Y-10348D01*
X25725Y-10345D01*
X25736Y-10334D01*
X25751Y-10319D01*
X25769Y-10298D01*
X25787Y-10272D01*
X25809Y-10246D01*
X25853Y-10185D01*
X24612D01*
Y-9886D01*
X26283D01*
Y-9890D01*
D02*
G37*
G36*
X606459Y-220325D02*
X606801D01*
Y-220609D01*
X606459D01*
Y-221214D01*
X606149D01*
Y-220609D01*
X605054D01*
Y-220325D01*
X606207Y-218695D01*
X606459D01*
Y-220325D01*
D02*
G37*
G36*
X604096Y-218687D02*
X604125Y-218691D01*
X604162Y-218695D01*
X604202Y-218702D01*
X604242Y-218709D01*
X604336Y-218735D01*
X604431Y-218771D01*
X604478Y-218793D01*
X604526Y-218818D01*
X604569Y-218851D01*
X604609Y-218888D01*
X604613Y-218891D01*
X604620Y-218895D01*
X604628Y-218909D01*
X604642Y-218924D01*
X604660Y-218942D01*
X604679Y-218968D01*
X604697Y-218993D01*
X604719Y-219026D01*
X604755Y-219095D01*
X604791Y-219182D01*
X604806Y-219226D01*
X604813Y-219277D01*
X604820Y-219328D01*
X604824Y-219383D01*
Y-219390D01*
Y-219408D01*
X604820Y-219437D01*
X604817Y-219477D01*
X604810Y-219521D01*
X604795Y-219572D01*
X604780Y-219626D01*
X604759Y-219681D01*
X604755Y-219688D01*
X604748Y-219707D01*
X604733Y-219736D01*
X604711Y-219776D01*
X604682Y-219819D01*
X604646Y-219874D01*
X604602Y-219929D01*
X604551Y-219990D01*
X604544Y-219998D01*
X604526Y-220020D01*
X604507Y-220038D01*
X604489Y-220056D01*
X604467Y-220078D01*
X604438Y-220107D01*
X604409Y-220136D01*
X604373Y-220169D01*
X604336Y-220205D01*
X604293Y-220245D01*
X604245Y-220285D01*
X604194Y-220333D01*
X604136Y-220380D01*
X604078Y-220431D01*
X604074Y-220435D01*
X604067Y-220442D01*
X604052Y-220453D01*
X604034Y-220467D01*
X604012Y-220489D01*
X603987Y-220511D01*
X603929Y-220558D01*
X603867Y-220613D01*
X603809Y-220668D01*
X603758Y-220715D01*
X603736Y-220733D01*
X603718Y-220751D01*
X603714Y-220755D01*
X603703Y-220766D01*
X603688Y-220780D01*
X603670Y-220802D01*
X603652Y-220828D01*
X603630Y-220853D01*
X603587Y-220915D01*
X604828D01*
Y-221214D01*
X603157D01*
Y-221210D01*
Y-221195D01*
Y-221174D01*
X603161Y-221144D01*
X603164Y-221112D01*
X603172Y-221075D01*
X603179Y-221039D01*
X603193Y-220999D01*
Y-220995D01*
X603197Y-220991D01*
X603204Y-220970D01*
X603219Y-220937D01*
X603241Y-220893D01*
X603270Y-220842D01*
X603306Y-220784D01*
X603346Y-220726D01*
X603397Y-220664D01*
Y-220660D01*
X603405Y-220657D01*
X603423Y-220635D01*
X603455Y-220602D01*
X603503Y-220555D01*
X603557Y-220500D01*
X603627Y-220435D01*
X603710Y-220362D01*
X603801Y-220285D01*
X603805Y-220282D01*
X603820Y-220271D01*
X603841Y-220253D01*
X603867Y-220231D01*
X603900Y-220202D01*
X603940Y-220169D01*
X603980Y-220132D01*
X604027Y-220092D01*
X604118Y-220005D01*
X604209Y-219918D01*
X604253Y-219874D01*
X604293Y-219830D01*
X604329Y-219790D01*
X604358Y-219750D01*
Y-219747D01*
X604365Y-219743D01*
X604373Y-219732D01*
X604380Y-219718D01*
X604406Y-219677D01*
X604435Y-219630D01*
X604460Y-219572D01*
X604486Y-219510D01*
X604500Y-219441D01*
X604507Y-219375D01*
Y-219372D01*
Y-219368D01*
X604504Y-219346D01*
X604500Y-219310D01*
X604489Y-219270D01*
X604475Y-219219D01*
X604449Y-219168D01*
X604417Y-219117D01*
X604373Y-219066D01*
X604365Y-219059D01*
X604347Y-219044D01*
X604322Y-219026D01*
X604282Y-219000D01*
X604231Y-218979D01*
X604173Y-218957D01*
X604103Y-218942D01*
X604027Y-218939D01*
X604005D01*
X603991Y-218942D01*
X603947Y-218946D01*
X603896Y-218957D01*
X603841Y-218971D01*
X603780Y-218997D01*
X603721Y-219030D01*
X603667Y-219073D01*
X603659Y-219080D01*
X603645Y-219099D01*
X603623Y-219128D01*
X603601Y-219172D01*
X603576Y-219222D01*
X603554Y-219288D01*
X603539Y-219361D01*
X603532Y-219444D01*
X603215Y-219412D01*
Y-219408D01*
X603219Y-219397D01*
Y-219379D01*
X603223Y-219354D01*
X603230Y-219324D01*
X603237Y-219292D01*
X603248Y-219252D01*
X603259Y-219212D01*
X603288Y-219124D01*
X603332Y-219037D01*
X603357Y-218993D01*
X603390Y-218950D01*
X603423Y-218909D01*
X603459Y-218873D01*
X603463Y-218869D01*
X603470Y-218866D01*
X603481Y-218855D01*
X603499Y-218844D01*
X603521Y-218829D01*
X603546Y-218815D01*
X603576Y-218797D01*
X603612Y-218778D01*
X603652Y-218760D01*
X603696Y-218742D01*
X603743Y-218727D01*
X603794Y-218713D01*
X603849Y-218702D01*
X603907Y-218691D01*
X603969Y-218687D01*
X604034Y-218684D01*
X604071D01*
X604096Y-218687D01*
D02*
G37*
G36*
X601821Y-218698D02*
X601894Y-218702D01*
X601967Y-218709D01*
X602040Y-218720D01*
X602101Y-218731D01*
X602105D01*
X602112Y-218735D01*
X602123D01*
X602138Y-218742D01*
X602178Y-218753D01*
X602229Y-218771D01*
X602287Y-218797D01*
X602349Y-218829D01*
X602411Y-218866D01*
X602469Y-218913D01*
X602473Y-218917D01*
X602476Y-218920D01*
X602487Y-218931D01*
X602502Y-218942D01*
X602538Y-218979D01*
X602582Y-219030D01*
X602629Y-219091D01*
X602680Y-219164D01*
X602728Y-219248D01*
X602768Y-219343D01*
Y-219346D01*
X602771Y-219354D01*
X602778Y-219368D01*
X602782Y-219390D01*
X602793Y-219415D01*
X602800Y-219444D01*
X602808Y-219477D01*
X602818Y-219517D01*
X602829Y-219557D01*
X602837Y-219605D01*
X602855Y-219707D01*
X602866Y-219819D01*
X602870Y-219943D01*
Y-219947D01*
Y-219954D01*
Y-219972D01*
Y-219990D01*
X602866Y-220016D01*
Y-220045D01*
X602862Y-220114D01*
X602851Y-220194D01*
X602840Y-220278D01*
X602822Y-220365D01*
X602800Y-220453D01*
Y-220456D01*
X602797Y-220464D01*
X602793Y-220475D01*
X602789Y-220489D01*
X602775Y-220529D01*
X602753Y-220580D01*
X602731Y-220638D01*
X602702Y-220697D01*
X602666Y-220759D01*
X602629Y-220817D01*
X602626Y-220824D01*
X602611Y-220842D01*
X602589Y-220868D01*
X602560Y-220901D01*
X602527Y-220937D01*
X602487Y-220973D01*
X602447Y-221013D01*
X602400Y-221046D01*
X602393Y-221050D01*
X602378Y-221061D01*
X602353Y-221075D01*
X602316Y-221093D01*
X602273Y-221115D01*
X602222Y-221133D01*
X602163Y-221155D01*
X602098Y-221174D01*
X602091D01*
X602080Y-221177D01*
X602069Y-221181D01*
X602032Y-221184D01*
X601981Y-221192D01*
X601923Y-221199D01*
X601854Y-221206D01*
X601778Y-221210D01*
X601694Y-221214D01*
X600787D01*
Y-218695D01*
X601756D01*
X601821Y-218698D01*
D02*
G37*
G36*
X281158Y-189259D02*
X281187Y-189262D01*
X281220Y-189270D01*
X281256Y-189277D01*
X281296Y-189284D01*
X281384Y-189313D01*
X281431Y-189335D01*
X281475Y-189357D01*
X281522Y-189386D01*
X281570Y-189419D01*
X281617Y-189455D01*
X281661Y-189499D01*
X281664Y-189503D01*
X281671Y-189510D01*
X281682Y-189524D01*
X281697Y-189543D01*
X281715Y-189565D01*
X281733Y-189594D01*
X281755Y-189626D01*
X281773Y-189666D01*
X281795Y-189706D01*
X281817Y-189754D01*
X281835Y-189801D01*
X281853Y-189856D01*
X281868Y-189914D01*
X281879Y-189976D01*
X281886Y-190038D01*
X281890Y-190107D01*
Y-190140D01*
X281886Y-190161D01*
X281883Y-190191D01*
X281879Y-190223D01*
X281872Y-190260D01*
X281864Y-190300D01*
X281842Y-190387D01*
X281806Y-190478D01*
X281784Y-190525D01*
X281759Y-190569D01*
X281726Y-190613D01*
X281693Y-190656D01*
X281690Y-190660D01*
X281682Y-190667D01*
X281671Y-190678D01*
X281657Y-190689D01*
X281639Y-190707D01*
X281613Y-190726D01*
X281588Y-190747D01*
X281555Y-190769D01*
X281519Y-190791D01*
X281482Y-190813D01*
X281395Y-190853D01*
X281293Y-190886D01*
X281238Y-190897D01*
X281180Y-190904D01*
X281140Y-190595D01*
X281144D01*
X281151Y-190591D01*
X281166Y-190587D01*
X281184Y-190584D01*
X281206Y-190580D01*
X281231Y-190573D01*
X281286Y-190555D01*
X281351Y-190529D01*
X281413Y-190496D01*
X281471Y-190460D01*
X281522Y-190416D01*
X281526Y-190409D01*
X281540Y-190394D01*
X281559Y-190365D01*
X281577Y-190329D01*
X281599Y-190285D01*
X281617Y-190231D01*
X281631Y-190169D01*
X281635Y-190103D01*
Y-190081D01*
X281631Y-190067D01*
X281628Y-190027D01*
X281617Y-189976D01*
X281599Y-189918D01*
X281573Y-189856D01*
X281537Y-189794D01*
X281486Y-189736D01*
X281479Y-189728D01*
X281457Y-189710D01*
X281424Y-189688D01*
X281380Y-189659D01*
X281326Y-189630D01*
X281264Y-189608D01*
X281191Y-189590D01*
X281111Y-189583D01*
X281107D01*
X281100D01*
X281089D01*
X281074Y-189586D01*
X281034Y-189590D01*
X280987Y-189601D01*
X280929Y-189615D01*
X280871Y-189641D01*
X280812Y-189677D01*
X280758Y-189725D01*
X280750Y-189732D01*
X280736Y-189750D01*
X280714Y-189779D01*
X280689Y-189819D01*
X280663Y-189870D01*
X280641Y-189932D01*
X280627Y-190001D01*
X280620Y-190078D01*
Y-190111D01*
X280623Y-190136D01*
X280627Y-190169D01*
X280634Y-190205D01*
X280641Y-190249D01*
X280652Y-190296D01*
X280379Y-190260D01*
Y-190242D01*
X280383Y-190227D01*
Y-190180D01*
X280376Y-190140D01*
X280368Y-190092D01*
X280357Y-190038D01*
X280339Y-189976D01*
X280314Y-189918D01*
X280281Y-189856D01*
Y-189852D01*
X280277Y-189848D01*
X280263Y-189830D01*
X280237Y-189805D01*
X280205Y-189776D01*
X280157Y-189746D01*
X280103Y-189721D01*
X280041Y-189703D01*
X280004Y-189696D01*
X279964D01*
X279961D01*
X279957D01*
X279935D01*
X279906Y-189703D01*
X279866Y-189710D01*
X279822Y-189725D01*
X279775Y-189743D01*
X279728Y-189772D01*
X279684Y-189812D01*
X279680Y-189816D01*
X279666Y-189834D01*
X279648Y-189859D01*
X279626Y-189892D01*
X279608Y-189936D01*
X279589Y-189987D01*
X279575Y-190045D01*
X279571Y-190111D01*
Y-190140D01*
X279578Y-190172D01*
X279586Y-190216D01*
X279600Y-190263D01*
X279618Y-190311D01*
X279648Y-190362D01*
X279684Y-190409D01*
X279688Y-190413D01*
X279706Y-190427D01*
X279731Y-190449D01*
X279768Y-190474D01*
X279815Y-190500D01*
X279873Y-190525D01*
X279942Y-190547D01*
X280023Y-190562D01*
X279968Y-190871D01*
X279964D01*
X279953Y-190868D01*
X279939Y-190864D01*
X279917Y-190860D01*
X279891Y-190853D01*
X279862Y-190842D01*
X279793Y-190820D01*
X279713Y-190784D01*
X279633Y-190740D01*
X279557Y-190686D01*
X279487Y-190616D01*
X279484Y-190613D01*
X279480Y-190605D01*
X279473Y-190595D01*
X279462Y-190580D01*
X279447Y-190562D01*
X279433Y-190536D01*
X279418Y-190511D01*
X279400Y-190478D01*
X279371Y-190405D01*
X279342Y-190322D01*
X279324Y-190223D01*
X279316Y-190172D01*
Y-190081D01*
X279320Y-190041D01*
X279327Y-189994D01*
X279338Y-189936D01*
X279356Y-189870D01*
X279378Y-189805D01*
X279407Y-189739D01*
Y-189736D01*
X279411Y-189732D01*
X279422Y-189710D01*
X279444Y-189677D01*
X279469Y-189641D01*
X279506Y-189597D01*
X279546Y-189554D01*
X279593Y-189510D01*
X279648Y-189473D01*
X279655Y-189470D01*
X279673Y-189459D01*
X279706Y-189444D01*
X279746Y-189426D01*
X279793Y-189408D01*
X279848Y-189393D01*
X279910Y-189383D01*
X279972Y-189379D01*
X279979D01*
X280001D01*
X280030Y-189383D01*
X280070Y-189390D01*
X280117Y-189401D01*
X280168Y-189419D01*
X280219Y-189441D01*
X280270Y-189470D01*
X280277Y-189473D01*
X280292Y-189484D01*
X280317Y-189506D01*
X280346Y-189535D01*
X280379Y-189572D01*
X280416Y-189615D01*
X280448Y-189666D01*
X280481Y-189728D01*
Y-189725D01*
X280485Y-189717D01*
X280488Y-189706D01*
X280492Y-189692D01*
X280507Y-189652D01*
X280528Y-189601D01*
X280558Y-189543D01*
X280594Y-189484D01*
X280641Y-189430D01*
X280696Y-189379D01*
X280703Y-189375D01*
X280725Y-189361D01*
X280761Y-189339D01*
X280809Y-189317D01*
X280867Y-189295D01*
X280936Y-189273D01*
X281016Y-189259D01*
X281104Y-189255D01*
X281107D01*
X281118D01*
X281136D01*
X281158Y-189259D01*
D02*
G37*
G36*
X281846Y-192910D02*
X281842D01*
X281828D01*
X281806D01*
X281777Y-192906D01*
X281744Y-192902D01*
X281708Y-192895D01*
X281671Y-192888D01*
X281631Y-192873D01*
X281628D01*
X281624Y-192870D01*
X281602Y-192862D01*
X281570Y-192848D01*
X281526Y-192826D01*
X281475Y-192797D01*
X281417Y-192760D01*
X281358Y-192720D01*
X281296Y-192669D01*
X281293D01*
X281289Y-192662D01*
X281267Y-192644D01*
X281235Y-192611D01*
X281187Y-192564D01*
X281133Y-192509D01*
X281067Y-192440D01*
X280994Y-192356D01*
X280918Y-192265D01*
X280914Y-192262D01*
X280903Y-192247D01*
X280885Y-192225D01*
X280863Y-192200D01*
X280834Y-192167D01*
X280802Y-192127D01*
X280765Y-192087D01*
X280725Y-192040D01*
X280638Y-191949D01*
X280550Y-191858D01*
X280507Y-191814D01*
X280463Y-191774D01*
X280423Y-191738D01*
X280383Y-191708D01*
X280379D01*
X280376Y-191701D01*
X280365Y-191694D01*
X280350Y-191687D01*
X280310Y-191661D01*
X280263Y-191632D01*
X280205Y-191606D01*
X280143Y-191581D01*
X280073Y-191567D01*
X280008Y-191559D01*
X280004D01*
X280001D01*
X279979Y-191563D01*
X279942Y-191567D01*
X279902Y-191577D01*
X279851Y-191592D01*
X279801Y-191617D01*
X279749Y-191650D01*
X279698Y-191694D01*
X279691Y-191701D01*
X279677Y-191719D01*
X279659Y-191745D01*
X279633Y-191785D01*
X279611Y-191836D01*
X279589Y-191894D01*
X279575Y-191963D01*
X279571Y-192040D01*
Y-192061D01*
X279575Y-192076D01*
X279578Y-192120D01*
X279589Y-192171D01*
X279604Y-192225D01*
X279629Y-192287D01*
X279662Y-192345D01*
X279706Y-192400D01*
X279713Y-192407D01*
X279731Y-192422D01*
X279760Y-192444D01*
X279804Y-192466D01*
X279855Y-192491D01*
X279921Y-192513D01*
X279993Y-192527D01*
X280077Y-192535D01*
X280044Y-192851D01*
X280041D01*
X280030Y-192848D01*
X280012D01*
X279986Y-192844D01*
X279957Y-192837D01*
X279924Y-192830D01*
X279884Y-192819D01*
X279844Y-192808D01*
X279757Y-192779D01*
X279669Y-192735D01*
X279626Y-192709D01*
X279582Y-192677D01*
X279542Y-192644D01*
X279506Y-192607D01*
X279502Y-192604D01*
X279498Y-192597D01*
X279487Y-192586D01*
X279476Y-192568D01*
X279462Y-192546D01*
X279447Y-192520D01*
X279429Y-192491D01*
X279411Y-192455D01*
X279393Y-192415D01*
X279375Y-192371D01*
X279360Y-192324D01*
X279345Y-192273D01*
X279334Y-192218D01*
X279324Y-192160D01*
X279320Y-192098D01*
X279316Y-192032D01*
Y-191996D01*
X279320Y-191971D01*
X279324Y-191941D01*
X279327Y-191905D01*
X279334Y-191865D01*
X279342Y-191825D01*
X279367Y-191730D01*
X279404Y-191636D01*
X279426Y-191588D01*
X279451Y-191541D01*
X279484Y-191497D01*
X279520Y-191457D01*
X279524Y-191454D01*
X279527Y-191446D01*
X279542Y-191439D01*
X279557Y-191425D01*
X279575Y-191406D01*
X279600Y-191388D01*
X279626Y-191370D01*
X279659Y-191348D01*
X279728Y-191312D01*
X279815Y-191275D01*
X279859Y-191261D01*
X279910Y-191253D01*
X279961Y-191246D01*
X280015Y-191243D01*
X280023D01*
X280041D01*
X280070Y-191246D01*
X280110Y-191250D01*
X280153Y-191257D01*
X280205Y-191272D01*
X280259Y-191286D01*
X280314Y-191308D01*
X280321Y-191312D01*
X280339Y-191319D01*
X280368Y-191333D01*
X280408Y-191355D01*
X280452Y-191384D01*
X280507Y-191421D01*
X280561Y-191465D01*
X280623Y-191516D01*
X280630Y-191523D01*
X280652Y-191541D01*
X280670Y-191559D01*
X280689Y-191577D01*
X280710Y-191599D01*
X280740Y-191628D01*
X280769Y-191657D01*
X280802Y-191694D01*
X280838Y-191730D01*
X280878Y-191774D01*
X280918Y-191821D01*
X280965Y-191872D01*
X281013Y-191930D01*
X281064Y-191989D01*
X281067Y-191992D01*
X281074Y-192000D01*
X281085Y-192014D01*
X281100Y-192032D01*
X281122Y-192054D01*
X281144Y-192080D01*
X281191Y-192138D01*
X281245Y-192200D01*
X281300Y-192258D01*
X281347Y-192309D01*
X281366Y-192331D01*
X281384Y-192349D01*
X281387Y-192353D01*
X281398Y-192364D01*
X281413Y-192378D01*
X281435Y-192396D01*
X281460Y-192415D01*
X281486Y-192436D01*
X281548Y-192480D01*
Y-191239D01*
X281846D01*
Y-192910D01*
D02*
G37*
G36*
X280878Y-193299D02*
X280914D01*
X280958Y-193303D01*
X281002Y-193306D01*
X281100Y-193317D01*
X281202Y-193332D01*
X281300Y-193354D01*
X281347Y-193368D01*
X281391Y-193383D01*
X281395D01*
X281402Y-193386D01*
X281413Y-193394D01*
X281428Y-193401D01*
X281468Y-193423D01*
X281519Y-193456D01*
X281577Y-193499D01*
X281635Y-193550D01*
X281697Y-193616D01*
X281751Y-193696D01*
Y-193700D01*
X281759Y-193707D01*
X281762Y-193718D01*
X281773Y-193736D01*
X281784Y-193758D01*
X281795Y-193787D01*
X281806Y-193816D01*
X281821Y-193852D01*
X281835Y-193892D01*
X281846Y-193936D01*
X281857Y-193983D01*
X281868Y-194038D01*
X281875Y-194093D01*
X281883Y-194151D01*
X281890Y-194282D01*
Y-194315D01*
X281886Y-194340D01*
Y-194369D01*
X281883Y-194406D01*
X281879Y-194446D01*
X281875Y-194486D01*
X281861Y-194577D01*
X281839Y-194675D01*
X281810Y-194770D01*
X281770Y-194861D01*
Y-194864D01*
X281762Y-194872D01*
X281755Y-194883D01*
X281748Y-194897D01*
X281719Y-194937D01*
X281679Y-194984D01*
X281628Y-195039D01*
X281570Y-195090D01*
X281497Y-195141D01*
X281417Y-195181D01*
X281413D01*
X281406Y-195185D01*
X281391Y-195188D01*
X281373Y-195196D01*
X281351Y-195203D01*
X281322Y-195210D01*
X281289Y-195221D01*
X281249Y-195228D01*
X281206Y-195236D01*
X281158Y-195247D01*
X281107Y-195254D01*
X281053Y-195261D01*
X280991Y-195268D01*
X280925Y-195272D01*
X280856Y-195276D01*
X280783D01*
X279327D01*
Y-194941D01*
X280783D01*
X280787D01*
X280798D01*
X280816D01*
X280838D01*
X280863Y-194937D01*
X280896D01*
X280965Y-194933D01*
X281045Y-194926D01*
X281125Y-194915D01*
X281202Y-194901D01*
X281235Y-194893D01*
X281267Y-194883D01*
X281275Y-194879D01*
X281293Y-194872D01*
X281318Y-194853D01*
X281355Y-194832D01*
X281391Y-194806D01*
X281431Y-194770D01*
X281471Y-194726D01*
X281504Y-194675D01*
X281508Y-194668D01*
X281519Y-194650D01*
X281529Y-194617D01*
X281544Y-194573D01*
X281562Y-194522D01*
X281573Y-194457D01*
X281584Y-194387D01*
X281588Y-194311D01*
Y-194275D01*
X281584Y-194253D01*
Y-194220D01*
X281580Y-194187D01*
X281566Y-194107D01*
X281548Y-194020D01*
X281519Y-193936D01*
X281479Y-193856D01*
X281453Y-193820D01*
X281424Y-193787D01*
X281420Y-193783D01*
X281417Y-193780D01*
X281406Y-193772D01*
X281391Y-193761D01*
X281369Y-193751D01*
X281347Y-193736D01*
X281315Y-193721D01*
X281282Y-193707D01*
X281242Y-193692D01*
X281195Y-193681D01*
X281140Y-193667D01*
X281082Y-193656D01*
X281016Y-193645D01*
X280947Y-193638D01*
X280867Y-193630D01*
X280783D01*
X279327D01*
Y-193296D01*
X280783D01*
X280787D01*
X280802D01*
X280820D01*
X280845D01*
X280878Y-193299D01*
D02*
G37*
G36*
X182516Y-120084D02*
X180547D01*
X180551Y-120087D01*
X180565Y-120106D01*
X180587Y-120127D01*
X180613Y-120164D01*
X180645Y-120204D01*
X180682Y-120255D01*
X180722Y-120313D01*
X180762Y-120379D01*
Y-120382D01*
X180765Y-120386D01*
X180780Y-120408D01*
X180798Y-120444D01*
X180820Y-120488D01*
X180845Y-120539D01*
X180871Y-120593D01*
X180896Y-120648D01*
X180918Y-120703D01*
X180620D01*
Y-120699D01*
X180613Y-120692D01*
X180609Y-120677D01*
X180598Y-120659D01*
X180587Y-120637D01*
X180572Y-120612D01*
X180536Y-120550D01*
X180496Y-120477D01*
X180445Y-120404D01*
X180387Y-120328D01*
X180325Y-120251D01*
X180321Y-120247D01*
X180318Y-120244D01*
X180307Y-120233D01*
X180296Y-120218D01*
X180260Y-120186D01*
X180216Y-120142D01*
X180165Y-120098D01*
X180107Y-120051D01*
X180048Y-120011D01*
X179987Y-119975D01*
Y-119774D01*
X182516D01*
Y-120084D01*
D02*
G37*
G36*
X181450Y-122118D02*
X182516D01*
Y-122453D01*
X181450D01*
X179997Y-123425D01*
Y-123021D01*
X180762Y-122526D01*
X180765D01*
X180773Y-122519D01*
X180784Y-122512D01*
X180798Y-122504D01*
X180816Y-122490D01*
X180838Y-122475D01*
X180893Y-122442D01*
X180958Y-122402D01*
X181031Y-122359D01*
X181108Y-122311D01*
X181188Y-122268D01*
X181184D01*
X181177Y-122264D01*
X181166Y-122257D01*
X181151Y-122246D01*
X181133Y-122235D01*
X181111Y-122220D01*
X181057Y-122188D01*
X180991Y-122148D01*
X180915Y-122100D01*
X180831Y-122046D01*
X180740Y-121987D01*
X179997Y-121503D01*
Y-121114D01*
X181450Y-122118D01*
D02*
G37*
G36*
X169497Y-101972D02*
X169533D01*
X169570Y-101976D01*
X169617Y-101979D01*
X169665Y-101987D01*
X169770Y-102005D01*
X169887Y-102030D01*
X170003Y-102067D01*
X170116Y-102118D01*
X170120Y-102121D01*
X170130Y-102125D01*
X170145Y-102132D01*
X170163Y-102147D01*
X170189Y-102161D01*
X170218Y-102180D01*
X170283Y-102227D01*
X170356Y-102289D01*
X170429Y-102362D01*
X170502Y-102445D01*
X170563Y-102544D01*
X170567Y-102547D01*
X170571Y-102558D01*
X170578Y-102573D01*
X170589Y-102591D01*
X170600Y-102620D01*
X170611Y-102649D01*
X170625Y-102685D01*
X170640Y-102726D01*
X170654Y-102769D01*
X170669Y-102817D01*
X170691Y-102919D01*
X170709Y-103035D01*
X170716Y-103155D01*
Y-103191D01*
X170713Y-103217D01*
X170709Y-103250D01*
X170705Y-103290D01*
X170702Y-103330D01*
X170691Y-103377D01*
X170669Y-103475D01*
X170636Y-103585D01*
X170615Y-103639D01*
X170589Y-103690D01*
X170556Y-103741D01*
X170524Y-103792D01*
X170520Y-103796D01*
X170516Y-103803D01*
X170505Y-103818D01*
X170487Y-103836D01*
X170469Y-103854D01*
X170443Y-103879D01*
X170414Y-103905D01*
X170385Y-103934D01*
X170349Y-103963D01*
X170305Y-103992D01*
X170261Y-104025D01*
X170214Y-104054D01*
X170159Y-104080D01*
X170105Y-104109D01*
X170047Y-104131D01*
X169981Y-104153D01*
X169905Y-103825D01*
X169908D01*
X169916Y-103821D01*
X169930Y-103814D01*
X169948Y-103807D01*
X169970Y-103799D01*
X169999Y-103788D01*
X170058Y-103759D01*
X170123Y-103723D01*
X170189Y-103679D01*
X170250Y-103625D01*
X170305Y-103566D01*
X170312Y-103559D01*
X170327Y-103537D01*
X170345Y-103501D01*
X170371Y-103454D01*
X170393Y-103392D01*
X170414Y-103323D01*
X170429Y-103239D01*
X170432Y-103148D01*
Y-103119D01*
X170429Y-103101D01*
Y-103075D01*
X170425Y-103046D01*
X170414Y-102977D01*
X170400Y-102900D01*
X170374Y-102820D01*
X170338Y-102736D01*
X170291Y-102660D01*
Y-102656D01*
X170283Y-102653D01*
X170265Y-102627D01*
X170236Y-102594D01*
X170192Y-102555D01*
X170138Y-102507D01*
X170076Y-102463D01*
X169999Y-102424D01*
X169916Y-102387D01*
X169912D01*
X169905Y-102383D01*
X169894Y-102380D01*
X169876Y-102376D01*
X169854Y-102369D01*
X169828Y-102362D01*
X169766Y-102351D01*
X169694Y-102336D01*
X169614Y-102322D01*
X169526Y-102314D01*
X169431Y-102311D01*
X169428D01*
X169417D01*
X169399D01*
X169377D01*
X169351Y-102314D01*
X169319D01*
X169282Y-102318D01*
X169242Y-102322D01*
X169155Y-102332D01*
X169060Y-102351D01*
X168966Y-102373D01*
X168871Y-102402D01*
X168867D01*
X168860Y-102405D01*
X168849Y-102412D01*
X168831Y-102420D01*
X168787Y-102442D01*
X168736Y-102474D01*
X168678Y-102515D01*
X168616Y-102565D01*
X168561Y-102624D01*
X168511Y-102693D01*
Y-102697D01*
X168507Y-102704D01*
X168500Y-102715D01*
X168492Y-102729D01*
X168485Y-102747D01*
X168474Y-102769D01*
X168452Y-102820D01*
X168430Y-102886D01*
X168412Y-102959D01*
X168398Y-103039D01*
X168394Y-103122D01*
Y-103148D01*
X168398Y-103170D01*
Y-103195D01*
X168401Y-103221D01*
X168416Y-103286D01*
X168434Y-103363D01*
X168463Y-103439D01*
X168503Y-103519D01*
X168525Y-103559D01*
X168554Y-103595D01*
X168558Y-103599D01*
X168561Y-103603D01*
X168572Y-103614D01*
X168583Y-103628D01*
X168602Y-103643D01*
X168623Y-103661D01*
X168645Y-103683D01*
X168674Y-103701D01*
X168707Y-103723D01*
X168744Y-103748D01*
X168780Y-103770D01*
X168824Y-103792D01*
X168871Y-103810D01*
X168922Y-103829D01*
X168976Y-103847D01*
X169035Y-103861D01*
X168951Y-104196D01*
X168947D01*
X168933Y-104192D01*
X168911Y-104185D01*
X168882Y-104174D01*
X168849Y-104163D01*
X168809Y-104149D01*
X168765Y-104131D01*
X168718Y-104109D01*
X168616Y-104058D01*
X168514Y-103992D01*
X168463Y-103952D01*
X168412Y-103912D01*
X168369Y-103868D01*
X168325Y-103818D01*
X168321Y-103814D01*
X168314Y-103807D01*
X168307Y-103788D01*
X168292Y-103770D01*
X168274Y-103741D01*
X168256Y-103712D01*
X168238Y-103672D01*
X168219Y-103632D01*
X168198Y-103585D01*
X168179Y-103534D01*
X168161Y-103479D01*
X168143Y-103421D01*
X168128Y-103359D01*
X168121Y-103293D01*
X168114Y-103224D01*
X168110Y-103152D01*
Y-103111D01*
X168114Y-103082D01*
Y-103050D01*
X168117Y-103009D01*
X168125Y-102966D01*
X168132Y-102915D01*
X168150Y-102809D01*
X168179Y-102700D01*
X168219Y-102591D01*
X168245Y-102540D01*
X168274Y-102489D01*
X168278Y-102485D01*
X168281Y-102478D01*
X168292Y-102463D01*
X168307Y-102449D01*
X168321Y-102427D01*
X168343Y-102402D01*
X168369Y-102373D01*
X168398Y-102343D01*
X168430Y-102314D01*
X168463Y-102281D01*
X168547Y-102216D01*
X168645Y-102154D01*
X168754Y-102100D01*
X168758D01*
X168769Y-102092D01*
X168787Y-102089D01*
X168809Y-102078D01*
X168838Y-102070D01*
X168875Y-102059D01*
X168915Y-102045D01*
X168958Y-102034D01*
X169006Y-102023D01*
X169060Y-102008D01*
X169173Y-101990D01*
X169300Y-101976D01*
X169431Y-101969D01*
X169435D01*
X169450D01*
X169472D01*
X169497Y-101972D01*
D02*
G37*
G36*
X170640Y-106133D02*
X170396D01*
X170393Y-106129D01*
X170385Y-106122D01*
X170371Y-106107D01*
X170349Y-106093D01*
X170323Y-106071D01*
X170294Y-106042D01*
X170258Y-106012D01*
X170214Y-105980D01*
X170170Y-105947D01*
X170120Y-105907D01*
X170061Y-105867D01*
X170003Y-105827D01*
X169938Y-105783D01*
X169868Y-105739D01*
X169792Y-105696D01*
X169715Y-105652D01*
X169712Y-105649D01*
X169697Y-105641D01*
X169675Y-105630D01*
X169643Y-105612D01*
X169603Y-105594D01*
X169559Y-105572D01*
X169508Y-105547D01*
X169450Y-105521D01*
X169384Y-105492D01*
X169319Y-105459D01*
X169246Y-105430D01*
X169169Y-105401D01*
X169013Y-105343D01*
X168845Y-105288D01*
X168842D01*
X168831Y-105285D01*
X168813Y-105281D01*
X168791Y-105274D01*
X168762Y-105266D01*
X168725Y-105259D01*
X168685Y-105248D01*
X168642Y-105241D01*
X168591Y-105230D01*
X168536Y-105219D01*
X168420Y-105201D01*
X168292Y-105183D01*
X168154Y-105172D01*
Y-104855D01*
X168157D01*
X168168D01*
X168183D01*
X168205Y-104859D01*
X168234D01*
X168270Y-104862D01*
X168310Y-104866D01*
X168354Y-104869D01*
X168405Y-104877D01*
X168456Y-104884D01*
X168518Y-104895D01*
X168580Y-104906D01*
X168645Y-104917D01*
X168718Y-104931D01*
X168867Y-104968D01*
X168871D01*
X168886Y-104972D01*
X168907Y-104979D01*
X168940Y-104990D01*
X168976Y-105001D01*
X169020Y-105015D01*
X169071Y-105030D01*
X169126Y-105052D01*
X169188Y-105073D01*
X169249Y-105095D01*
X169388Y-105150D01*
X169533Y-105215D01*
X169679Y-105288D01*
X169683Y-105292D01*
X169697Y-105299D01*
X169715Y-105310D01*
X169745Y-105324D01*
X169777Y-105343D01*
X169817Y-105368D01*
X169861Y-105394D01*
X169908Y-105423D01*
X170014Y-105492D01*
X170123Y-105565D01*
X170236Y-105649D01*
X170342Y-105736D01*
Y-104502D01*
X170640D01*
Y-106133D01*
D02*
G37*
G36*
X606054Y-224987D02*
X606084Y-224990D01*
X606120Y-224994D01*
X606160Y-225001D01*
X606200Y-225008D01*
X606295Y-225034D01*
X606389Y-225070D01*
X606437Y-225092D01*
X606484Y-225118D01*
X606528Y-225150D01*
X606568Y-225187D01*
X606571Y-225190D01*
X606579Y-225194D01*
X606586Y-225209D01*
X606601Y-225223D01*
X606619Y-225241D01*
X606637Y-225267D01*
X606655Y-225292D01*
X606677Y-225325D01*
X606713Y-225394D01*
X606750Y-225482D01*
X606764Y-225525D01*
X606772Y-225576D01*
X606779Y-225627D01*
X606782Y-225682D01*
Y-225689D01*
Y-225707D01*
X606779Y-225736D01*
X606775Y-225777D01*
X606768Y-225820D01*
X606753Y-225871D01*
X606739Y-225926D01*
X606717Y-225980D01*
X606713Y-225988D01*
X606706Y-226006D01*
X606692Y-226035D01*
X606670Y-226075D01*
X606640Y-226119D01*
X606604Y-226173D01*
X606560Y-226228D01*
X606509Y-226290D01*
X606502Y-226297D01*
X606484Y-226319D01*
X606466Y-226337D01*
X606448Y-226355D01*
X606426Y-226377D01*
X606397Y-226406D01*
X606367Y-226435D01*
X606331Y-226468D01*
X606295Y-226504D01*
X606251Y-226544D01*
X606204Y-226585D01*
X606153Y-226632D01*
X606095Y-226679D01*
X606036Y-226730D01*
X606033Y-226734D01*
X606025Y-226741D01*
X606011Y-226752D01*
X605993Y-226767D01*
X605971Y-226788D01*
X605945Y-226810D01*
X605887Y-226858D01*
X605825Y-226912D01*
X605767Y-226967D01*
X605716Y-227014D01*
X605694Y-227032D01*
X605676Y-227050D01*
X605672Y-227054D01*
X605661Y-227065D01*
X605647Y-227080D01*
X605629Y-227101D01*
X605610Y-227127D01*
X605589Y-227152D01*
X605545Y-227214D01*
X606786D01*
Y-227513D01*
X605115D01*
Y-227509D01*
Y-227495D01*
Y-227473D01*
X605119Y-227444D01*
X605123Y-227411D01*
X605130Y-227374D01*
X605137Y-227338D01*
X605152Y-227298D01*
Y-227294D01*
X605155Y-227291D01*
X605163Y-227269D01*
X605177Y-227236D01*
X605199Y-227192D01*
X605228Y-227141D01*
X605265Y-227083D01*
X605305Y-227025D01*
X605356Y-226963D01*
Y-226959D01*
X605363Y-226956D01*
X605381Y-226934D01*
X605414Y-226901D01*
X605461Y-226854D01*
X605516Y-226799D01*
X605585Y-226734D01*
X605669Y-226661D01*
X605760Y-226585D01*
X605763Y-226581D01*
X605778Y-226570D01*
X605800Y-226552D01*
X605825Y-226530D01*
X605858Y-226501D01*
X605898Y-226468D01*
X605938Y-226432D01*
X605985Y-226392D01*
X606076Y-226304D01*
X606167Y-226217D01*
X606211Y-226173D01*
X606251Y-226130D01*
X606287Y-226090D01*
X606317Y-226049D01*
Y-226046D01*
X606324Y-226042D01*
X606331Y-226031D01*
X606338Y-226017D01*
X606364Y-225977D01*
X606393Y-225929D01*
X606419Y-225871D01*
X606444Y-225809D01*
X606459Y-225740D01*
X606466Y-225675D01*
Y-225671D01*
Y-225667D01*
X606462Y-225645D01*
X606459Y-225609D01*
X606448Y-225569D01*
X606433Y-225518D01*
X606408Y-225467D01*
X606375Y-225416D01*
X606331Y-225365D01*
X606324Y-225358D01*
X606306Y-225343D01*
X606280Y-225325D01*
X606240Y-225300D01*
X606189Y-225278D01*
X606131Y-225256D01*
X606062Y-225241D01*
X605985Y-225238D01*
X605964D01*
X605949Y-225241D01*
X605905Y-225245D01*
X605854Y-225256D01*
X605800Y-225271D01*
X605738Y-225296D01*
X605680Y-225329D01*
X605625Y-225372D01*
X605618Y-225380D01*
X605603Y-225398D01*
X605581Y-225427D01*
X605559Y-225471D01*
X605534Y-225522D01*
X605512Y-225587D01*
X605498Y-225660D01*
X605490Y-225744D01*
X605174Y-225711D01*
Y-225707D01*
X605177Y-225696D01*
Y-225678D01*
X605181Y-225653D01*
X605188Y-225624D01*
X605195Y-225591D01*
X605206Y-225551D01*
X605217Y-225511D01*
X605246Y-225423D01*
X605290Y-225336D01*
X605316Y-225292D01*
X605348Y-225249D01*
X605381Y-225209D01*
X605417Y-225172D01*
X605421Y-225169D01*
X605428Y-225165D01*
X605439Y-225154D01*
X605457Y-225143D01*
X605479Y-225129D01*
X605505Y-225114D01*
X605534Y-225096D01*
X605570Y-225078D01*
X605610Y-225059D01*
X605654Y-225041D01*
X605701Y-225027D01*
X605752Y-225012D01*
X605807Y-225001D01*
X605865Y-224990D01*
X605927Y-224987D01*
X605993Y-224983D01*
X606029D01*
X606054Y-224987D01*
D02*
G37*
G36*
X604096D02*
X604125Y-224990D01*
X604162Y-224994D01*
X604202Y-225001D01*
X604242Y-225008D01*
X604336Y-225034D01*
X604431Y-225070D01*
X604478Y-225092D01*
X604526Y-225118D01*
X604569Y-225150D01*
X604609Y-225187D01*
X604613Y-225190D01*
X604620Y-225194D01*
X604628Y-225209D01*
X604642Y-225223D01*
X604660Y-225241D01*
X604679Y-225267D01*
X604697Y-225292D01*
X604719Y-225325D01*
X604755Y-225394D01*
X604791Y-225482D01*
X604806Y-225525D01*
X604813Y-225576D01*
X604820Y-225627D01*
X604824Y-225682D01*
Y-225689D01*
Y-225707D01*
X604820Y-225736D01*
X604817Y-225777D01*
X604810Y-225820D01*
X604795Y-225871D01*
X604780Y-225926D01*
X604759Y-225980D01*
X604755Y-225988D01*
X604748Y-226006D01*
X604733Y-226035D01*
X604711Y-226075D01*
X604682Y-226119D01*
X604646Y-226173D01*
X604602Y-226228D01*
X604551Y-226290D01*
X604544Y-226297D01*
X604526Y-226319D01*
X604507Y-226337D01*
X604489Y-226355D01*
X604467Y-226377D01*
X604438Y-226406D01*
X604409Y-226435D01*
X604373Y-226468D01*
X604336Y-226504D01*
X604293Y-226544D01*
X604245Y-226585D01*
X604194Y-226632D01*
X604136Y-226679D01*
X604078Y-226730D01*
X604074Y-226734D01*
X604067Y-226741D01*
X604052Y-226752D01*
X604034Y-226767D01*
X604012Y-226788D01*
X603987Y-226810D01*
X603929Y-226858D01*
X603867Y-226912D01*
X603809Y-226967D01*
X603758Y-227014D01*
X603736Y-227032D01*
X603718Y-227050D01*
X603714Y-227054D01*
X603703Y-227065D01*
X603688Y-227080D01*
X603670Y-227101D01*
X603652Y-227127D01*
X603630Y-227152D01*
X603587Y-227214D01*
X604828D01*
Y-227513D01*
X603157D01*
Y-227509D01*
Y-227495D01*
Y-227473D01*
X603161Y-227444D01*
X603164Y-227411D01*
X603172Y-227374D01*
X603179Y-227338D01*
X603193Y-227298D01*
Y-227294D01*
X603197Y-227291D01*
X603204Y-227269D01*
X603219Y-227236D01*
X603241Y-227192D01*
X603270Y-227141D01*
X603306Y-227083D01*
X603346Y-227025D01*
X603397Y-226963D01*
Y-226959D01*
X603405Y-226956D01*
X603423Y-226934D01*
X603455Y-226901D01*
X603503Y-226854D01*
X603557Y-226799D01*
X603627Y-226734D01*
X603710Y-226661D01*
X603801Y-226585D01*
X603805Y-226581D01*
X603820Y-226570D01*
X603841Y-226552D01*
X603867Y-226530D01*
X603900Y-226501D01*
X603940Y-226468D01*
X603980Y-226432D01*
X604027Y-226392D01*
X604118Y-226304D01*
X604209Y-226217D01*
X604253Y-226173D01*
X604293Y-226130D01*
X604329Y-226090D01*
X604358Y-226049D01*
Y-226046D01*
X604365Y-226042D01*
X604373Y-226031D01*
X604380Y-226017D01*
X604406Y-225977D01*
X604435Y-225929D01*
X604460Y-225871D01*
X604486Y-225809D01*
X604500Y-225740D01*
X604507Y-225675D01*
Y-225671D01*
Y-225667D01*
X604504Y-225645D01*
X604500Y-225609D01*
X604489Y-225569D01*
X604475Y-225518D01*
X604449Y-225467D01*
X604417Y-225416D01*
X604373Y-225365D01*
X604365Y-225358D01*
X604347Y-225343D01*
X604322Y-225325D01*
X604282Y-225300D01*
X604231Y-225278D01*
X604173Y-225256D01*
X604103Y-225241D01*
X604027Y-225238D01*
X604005D01*
X603991Y-225241D01*
X603947Y-225245D01*
X603896Y-225256D01*
X603841Y-225271D01*
X603780Y-225296D01*
X603721Y-225329D01*
X603667Y-225372D01*
X603659Y-225380D01*
X603645Y-225398D01*
X603623Y-225427D01*
X603601Y-225471D01*
X603576Y-225522D01*
X603554Y-225587D01*
X603539Y-225660D01*
X603532Y-225744D01*
X603215Y-225711D01*
Y-225707D01*
X603219Y-225696D01*
Y-225678D01*
X603223Y-225653D01*
X603230Y-225624D01*
X603237Y-225591D01*
X603248Y-225551D01*
X603259Y-225511D01*
X603288Y-225423D01*
X603332Y-225336D01*
X603357Y-225292D01*
X603390Y-225249D01*
X603423Y-225209D01*
X603459Y-225172D01*
X603463Y-225169D01*
X603470Y-225165D01*
X603481Y-225154D01*
X603499Y-225143D01*
X603521Y-225129D01*
X603546Y-225114D01*
X603576Y-225096D01*
X603612Y-225078D01*
X603652Y-225059D01*
X603696Y-225041D01*
X603743Y-225027D01*
X603794Y-225012D01*
X603849Y-225001D01*
X603907Y-224990D01*
X603969Y-224987D01*
X604034Y-224983D01*
X604071D01*
X604096Y-224987D01*
D02*
G37*
G36*
X601821Y-224997D02*
X601894Y-225001D01*
X601967Y-225008D01*
X602040Y-225019D01*
X602101Y-225030D01*
X602105D01*
X602112Y-225034D01*
X602123D01*
X602138Y-225041D01*
X602178Y-225052D01*
X602229Y-225070D01*
X602287Y-225096D01*
X602349Y-225129D01*
X602411Y-225165D01*
X602469Y-225212D01*
X602473Y-225216D01*
X602476Y-225220D01*
X602487Y-225231D01*
X602502Y-225241D01*
X602538Y-225278D01*
X602582Y-225329D01*
X602629Y-225391D01*
X602680Y-225464D01*
X602728Y-225547D01*
X602768Y-225642D01*
Y-225645D01*
X602771Y-225653D01*
X602778Y-225667D01*
X602782Y-225689D01*
X602793Y-225715D01*
X602800Y-225744D01*
X602808Y-225777D01*
X602818Y-225816D01*
X602829Y-225857D01*
X602837Y-225904D01*
X602855Y-226006D01*
X602866Y-226119D01*
X602870Y-226242D01*
Y-226246D01*
Y-226253D01*
Y-226272D01*
Y-226290D01*
X602866Y-226315D01*
Y-226344D01*
X602862Y-226413D01*
X602851Y-226494D01*
X602840Y-226577D01*
X602822Y-226665D01*
X602800Y-226752D01*
Y-226756D01*
X602797Y-226763D01*
X602793Y-226774D01*
X602789Y-226788D01*
X602775Y-226829D01*
X602753Y-226879D01*
X602731Y-226938D01*
X602702Y-226996D01*
X602666Y-227058D01*
X602629Y-227116D01*
X602626Y-227123D01*
X602611Y-227141D01*
X602589Y-227167D01*
X602560Y-227200D01*
X602527Y-227236D01*
X602487Y-227273D01*
X602447Y-227313D01*
X602400Y-227345D01*
X602393Y-227349D01*
X602378Y-227360D01*
X602353Y-227374D01*
X602316Y-227393D01*
X602273Y-227414D01*
X602222Y-227433D01*
X602163Y-227454D01*
X602098Y-227473D01*
X602091D01*
X602080Y-227476D01*
X602069Y-227480D01*
X602032Y-227484D01*
X601981Y-227491D01*
X601923Y-227498D01*
X601854Y-227505D01*
X601778Y-227509D01*
X601694Y-227513D01*
X600787D01*
Y-224994D01*
X601756D01*
X601821Y-224997D01*
D02*
G37*
G36*
X4667Y-237799D02*
X4692D01*
X4721Y-237803D01*
X4790Y-237817D01*
X4867Y-237835D01*
X4947Y-237864D01*
X5027Y-237904D01*
X5067Y-237930D01*
X5103Y-237959D01*
X5107Y-237963D01*
X5111Y-237966D01*
X5122Y-237977D01*
X5132Y-237988D01*
X5147Y-238006D01*
X5165Y-238028D01*
X5202Y-238079D01*
X5238Y-238145D01*
X5274Y-238225D01*
X5303Y-238316D01*
X5325Y-238421D01*
X5027Y-238447D01*
Y-238443D01*
X5023Y-238436D01*
Y-238429D01*
X5020Y-238414D01*
X5009Y-238374D01*
X4994Y-238330D01*
X4976Y-238279D01*
X4950Y-238228D01*
X4921Y-238181D01*
X4885Y-238141D01*
X4881Y-238137D01*
X4867Y-238126D01*
X4841Y-238112D01*
X4812Y-238097D01*
X4772Y-238079D01*
X4725Y-238065D01*
X4670Y-238054D01*
X4612Y-238050D01*
X4586D01*
X4561Y-238054D01*
X4528Y-238057D01*
X4488Y-238065D01*
X4448Y-238075D01*
X4404Y-238090D01*
X4364Y-238112D01*
X4361Y-238116D01*
X4346Y-238123D01*
X4324Y-238137D01*
X4302Y-238159D01*
X4273Y-238185D01*
X4244Y-238214D01*
X4215Y-238247D01*
X4186Y-238287D01*
X4182Y-238290D01*
X4175Y-238309D01*
X4160Y-238334D01*
X4146Y-238367D01*
X4128Y-238410D01*
X4110Y-238461D01*
X4091Y-238520D01*
X4073Y-238585D01*
Y-238589D01*
X4070Y-238592D01*
Y-238603D01*
X4066Y-238618D01*
X4059Y-238654D01*
X4048Y-238702D01*
X4040Y-238760D01*
X4033Y-238822D01*
X4030Y-238891D01*
X4026Y-238964D01*
Y-238967D01*
Y-238978D01*
Y-238997D01*
Y-239026D01*
X4030Y-239018D01*
X4044Y-239000D01*
X4066Y-238975D01*
X4091Y-238938D01*
X4128Y-238902D01*
X4171Y-238862D01*
X4222Y-238822D01*
X4281Y-238785D01*
X4288Y-238782D01*
X4310Y-238771D01*
X4343Y-238756D01*
X4383Y-238742D01*
X4437Y-238723D01*
X4495Y-238709D01*
X4561Y-238698D01*
X4630Y-238694D01*
X4659D01*
X4681Y-238698D01*
X4710Y-238702D01*
X4739Y-238705D01*
X4776Y-238713D01*
X4812Y-238723D01*
X4896Y-238749D01*
X4939Y-238767D01*
X4983Y-238789D01*
X5031Y-238814D01*
X5074Y-238847D01*
X5118Y-238880D01*
X5158Y-238920D01*
X5161Y-238924D01*
X5169Y-238931D01*
X5176Y-238942D01*
X5191Y-238960D01*
X5209Y-238985D01*
X5227Y-239011D01*
X5245Y-239044D01*
X5263Y-239080D01*
X5285Y-239120D01*
X5303Y-239164D01*
X5322Y-239215D01*
X5340Y-239266D01*
X5354Y-239324D01*
X5362Y-239386D01*
X5369Y-239448D01*
X5373Y-239517D01*
Y-239521D01*
Y-239535D01*
Y-239553D01*
X5369Y-239579D01*
X5365Y-239612D01*
X5362Y-239652D01*
X5354Y-239692D01*
X5344Y-239739D01*
X5318Y-239834D01*
X5300Y-239885D01*
X5278Y-239939D01*
X5252Y-239990D01*
X5220Y-240037D01*
X5187Y-240089D01*
X5147Y-240132D01*
X5143Y-240136D01*
X5136Y-240143D01*
X5125Y-240154D01*
X5107Y-240168D01*
X5085Y-240187D01*
X5056Y-240209D01*
X5027Y-240227D01*
X4990Y-240252D01*
X4954Y-240274D01*
X4910Y-240292D01*
X4812Y-240332D01*
X4761Y-240347D01*
X4703Y-240358D01*
X4645Y-240365D01*
X4583Y-240369D01*
X4557D01*
X4539Y-240365D01*
X4521D01*
X4495Y-240361D01*
X4434Y-240351D01*
X4364Y-240336D01*
X4288Y-240311D01*
X4211Y-240278D01*
X4135Y-240234D01*
X4131D01*
X4128Y-240227D01*
X4117Y-240219D01*
X4102Y-240209D01*
X4066Y-240179D01*
X4019Y-240139D01*
X3971Y-240085D01*
X3917Y-240019D01*
X3869Y-239943D01*
X3826Y-239856D01*
Y-239852D01*
X3822Y-239845D01*
X3815Y-239830D01*
X3808Y-239812D01*
X3800Y-239786D01*
X3789Y-239754D01*
X3782Y-239717D01*
X3771Y-239677D01*
X3760Y-239630D01*
X3749Y-239575D01*
X3742Y-239517D01*
X3735Y-239455D01*
X3727Y-239386D01*
X3720Y-239313D01*
X3716Y-239233D01*
Y-239149D01*
Y-239146D01*
Y-239127D01*
Y-239102D01*
Y-239069D01*
X3720Y-239029D01*
Y-238982D01*
X3724Y-238927D01*
X3731Y-238873D01*
X3742Y-238749D01*
X3760Y-238618D01*
X3786Y-238494D01*
X3804Y-238432D01*
X3822Y-238378D01*
Y-238374D01*
X3826Y-238367D01*
X3833Y-238352D01*
X3840Y-238330D01*
X3851Y-238309D01*
X3866Y-238279D01*
X3902Y-238217D01*
X3946Y-238148D01*
X3997Y-238075D01*
X4062Y-238006D01*
X4135Y-237945D01*
X4139D01*
X4146Y-237937D01*
X4157Y-237930D01*
X4171Y-237923D01*
X4193Y-237912D01*
X4215Y-237897D01*
X4244Y-237883D01*
X4273Y-237872D01*
X4343Y-237843D01*
X4426Y-237817D01*
X4517Y-237803D01*
X4619Y-237795D01*
X4648D01*
X4667Y-237799D01*
D02*
G37*
G36*
X8729D02*
X8761D01*
X8801Y-237803D01*
X8845Y-237810D01*
X8896Y-237817D01*
X9002Y-237835D01*
X9111Y-237864D01*
X9220Y-237904D01*
X9271Y-237930D01*
X9322Y-237959D01*
X9326Y-237963D01*
X9333Y-237966D01*
X9347Y-237977D01*
X9362Y-237992D01*
X9384Y-238006D01*
X9409Y-238028D01*
X9438Y-238054D01*
X9468Y-238083D01*
X9497Y-238116D01*
X9529Y-238148D01*
X9595Y-238232D01*
X9657Y-238330D01*
X9712Y-238439D01*
Y-238443D01*
X9719Y-238454D01*
X9723Y-238472D01*
X9733Y-238494D01*
X9741Y-238523D01*
X9752Y-238560D01*
X9766Y-238600D01*
X9777Y-238643D01*
X9788Y-238691D01*
X9803Y-238745D01*
X9821Y-238858D01*
X9835Y-238985D01*
X9843Y-239117D01*
Y-239120D01*
Y-239135D01*
Y-239157D01*
X9839Y-239182D01*
Y-239218D01*
X9835Y-239255D01*
X9832Y-239302D01*
X9824Y-239350D01*
X9806Y-239455D01*
X9781Y-239572D01*
X9744Y-239688D01*
X9693Y-239801D01*
X9690Y-239805D01*
X9686Y-239815D01*
X9679Y-239830D01*
X9664Y-239848D01*
X9650Y-239874D01*
X9631Y-239903D01*
X9584Y-239968D01*
X9522Y-240041D01*
X9449Y-240114D01*
X9366Y-240187D01*
X9267Y-240249D01*
X9264Y-240252D01*
X9253Y-240256D01*
X9238Y-240263D01*
X9220Y-240274D01*
X9191Y-240285D01*
X9162Y-240296D01*
X9126Y-240311D01*
X9086Y-240325D01*
X9042Y-240340D01*
X8995Y-240354D01*
X8892Y-240376D01*
X8776Y-240394D01*
X8656Y-240402D01*
X8619D01*
X8594Y-240398D01*
X8561Y-240394D01*
X8521Y-240391D01*
X8481Y-240387D01*
X8434Y-240376D01*
X8336Y-240354D01*
X8226Y-240321D01*
X8172Y-240300D01*
X8121Y-240274D01*
X8070Y-240241D01*
X8019Y-240209D01*
X8015Y-240205D01*
X8008Y-240201D01*
X7993Y-240190D01*
X7975Y-240172D01*
X7957Y-240154D01*
X7932Y-240128D01*
X7906Y-240099D01*
X7877Y-240070D01*
X7848Y-240034D01*
X7819Y-239990D01*
X7786Y-239947D01*
X7757Y-239899D01*
X7731Y-239845D01*
X7702Y-239790D01*
X7680Y-239732D01*
X7659Y-239666D01*
X7986Y-239590D01*
Y-239593D01*
X7990Y-239601D01*
X7997Y-239615D01*
X8004Y-239633D01*
X8012Y-239655D01*
X8023Y-239684D01*
X8052Y-239743D01*
X8088Y-239808D01*
X8132Y-239874D01*
X8186Y-239936D01*
X8245Y-239990D01*
X8252Y-239997D01*
X8274Y-240012D01*
X8310Y-240030D01*
X8358Y-240056D01*
X8419Y-240077D01*
X8489Y-240099D01*
X8572Y-240114D01*
X8663Y-240118D01*
X8692D01*
X8710Y-240114D01*
X8736D01*
X8765Y-240110D01*
X8834Y-240099D01*
X8911Y-240085D01*
X8991Y-240059D01*
X9075Y-240023D01*
X9151Y-239976D01*
X9155D01*
X9158Y-239968D01*
X9184Y-239950D01*
X9217Y-239921D01*
X9257Y-239877D01*
X9304Y-239823D01*
X9347Y-239761D01*
X9388Y-239684D01*
X9424Y-239601D01*
Y-239597D01*
X9428Y-239590D01*
X9431Y-239579D01*
X9435Y-239561D01*
X9442Y-239539D01*
X9449Y-239513D01*
X9460Y-239452D01*
X9475Y-239379D01*
X9489Y-239299D01*
X9497Y-239211D01*
X9500Y-239117D01*
Y-239113D01*
Y-239102D01*
Y-239084D01*
Y-239062D01*
X9497Y-239036D01*
Y-239004D01*
X9493Y-238967D01*
X9489Y-238927D01*
X9479Y-238840D01*
X9460Y-238745D01*
X9438Y-238651D01*
X9409Y-238556D01*
Y-238552D01*
X9406Y-238545D01*
X9398Y-238534D01*
X9391Y-238516D01*
X9369Y-238472D01*
X9337Y-238421D01*
X9297Y-238363D01*
X9246Y-238301D01*
X9187Y-238247D01*
X9118Y-238196D01*
X9115D01*
X9107Y-238192D01*
X9096Y-238185D01*
X9082Y-238177D01*
X9064Y-238170D01*
X9042Y-238159D01*
X8991Y-238137D01*
X8925Y-238116D01*
X8852Y-238097D01*
X8772Y-238083D01*
X8689Y-238079D01*
X8663D01*
X8641Y-238083D01*
X8616D01*
X8590Y-238087D01*
X8525Y-238101D01*
X8448Y-238119D01*
X8372Y-238148D01*
X8292Y-238188D01*
X8252Y-238210D01*
X8215Y-238239D01*
X8212Y-238243D01*
X8208Y-238247D01*
X8197Y-238258D01*
X8183Y-238268D01*
X8168Y-238287D01*
X8150Y-238309D01*
X8128Y-238330D01*
X8110Y-238359D01*
X8088Y-238392D01*
X8063Y-238429D01*
X8041Y-238465D01*
X8019Y-238509D01*
X8001Y-238556D01*
X7982Y-238607D01*
X7964Y-238662D01*
X7950Y-238720D01*
X7615Y-238636D01*
Y-238632D01*
X7619Y-238618D01*
X7626Y-238596D01*
X7637Y-238567D01*
X7648Y-238534D01*
X7662Y-238494D01*
X7680Y-238451D01*
X7702Y-238403D01*
X7753Y-238301D01*
X7819Y-238199D01*
X7859Y-238148D01*
X7899Y-238097D01*
X7942Y-238054D01*
X7993Y-238010D01*
X7997Y-238006D01*
X8004Y-237999D01*
X8023Y-237992D01*
X8041Y-237977D01*
X8070Y-237959D01*
X8099Y-237941D01*
X8139Y-237923D01*
X8179Y-237904D01*
X8226Y-237883D01*
X8277Y-237864D01*
X8332Y-237846D01*
X8390Y-237828D01*
X8452Y-237813D01*
X8518Y-237806D01*
X8587Y-237799D01*
X8660Y-237795D01*
X8700D01*
X8729Y-237799D01*
D02*
G37*
G36*
X7375Y-237843D02*
Y-237857D01*
Y-237879D01*
X7371Y-237908D01*
X7367Y-237941D01*
X7360Y-237977D01*
X7353Y-238014D01*
X7338Y-238054D01*
Y-238057D01*
X7335Y-238061D01*
X7327Y-238083D01*
X7313Y-238116D01*
X7291Y-238159D01*
X7262Y-238210D01*
X7225Y-238268D01*
X7185Y-238327D01*
X7134Y-238389D01*
Y-238392D01*
X7127Y-238396D01*
X7109Y-238418D01*
X7076Y-238451D01*
X7029Y-238498D01*
X6974Y-238552D01*
X6905Y-238618D01*
X6821Y-238691D01*
X6730Y-238767D01*
X6727Y-238771D01*
X6712Y-238782D01*
X6690Y-238800D01*
X6665Y-238822D01*
X6632Y-238851D01*
X6592Y-238884D01*
X6552Y-238920D01*
X6505Y-238960D01*
X6414Y-239047D01*
X6323Y-239135D01*
X6279Y-239178D01*
X6239Y-239222D01*
X6203Y-239262D01*
X6173Y-239302D01*
Y-239306D01*
X6166Y-239310D01*
X6159Y-239320D01*
X6152Y-239335D01*
X6126Y-239375D01*
X6097Y-239422D01*
X6072Y-239481D01*
X6046Y-239543D01*
X6032Y-239612D01*
X6024Y-239677D01*
Y-239681D01*
Y-239684D01*
X6028Y-239706D01*
X6032Y-239743D01*
X6042Y-239783D01*
X6057Y-239834D01*
X6083Y-239885D01*
X6115Y-239936D01*
X6159Y-239986D01*
X6166Y-239994D01*
X6184Y-240008D01*
X6210Y-240027D01*
X6250Y-240052D01*
X6301Y-240074D01*
X6359Y-240096D01*
X6428Y-240110D01*
X6505Y-240114D01*
X6526D01*
X6541Y-240110D01*
X6585Y-240107D01*
X6636Y-240096D01*
X6690Y-240081D01*
X6752Y-240056D01*
X6810Y-240023D01*
X6865Y-239979D01*
X6872Y-239972D01*
X6887Y-239954D01*
X6909Y-239925D01*
X6931Y-239881D01*
X6956Y-239830D01*
X6978Y-239764D01*
X6992Y-239692D01*
X7000Y-239608D01*
X7316Y-239641D01*
Y-239644D01*
X7313Y-239655D01*
Y-239673D01*
X7309Y-239699D01*
X7302Y-239728D01*
X7295Y-239761D01*
X7284Y-239801D01*
X7273Y-239841D01*
X7244Y-239928D01*
X7200Y-240016D01*
X7175Y-240059D01*
X7142Y-240103D01*
X7109Y-240143D01*
X7073Y-240179D01*
X7069Y-240183D01*
X7062Y-240187D01*
X7051Y-240198D01*
X7033Y-240209D01*
X7011Y-240223D01*
X6985Y-240238D01*
X6956Y-240256D01*
X6920Y-240274D01*
X6880Y-240292D01*
X6836Y-240311D01*
X6789Y-240325D01*
X6738Y-240340D01*
X6683Y-240351D01*
X6625Y-240361D01*
X6563Y-240365D01*
X6497Y-240369D01*
X6461D01*
X6436Y-240365D01*
X6406Y-240361D01*
X6370Y-240358D01*
X6330Y-240351D01*
X6290Y-240343D01*
X6195Y-240318D01*
X6101Y-240281D01*
X6053Y-240260D01*
X6006Y-240234D01*
X5962Y-240201D01*
X5922Y-240165D01*
X5919Y-240161D01*
X5911Y-240158D01*
X5904Y-240143D01*
X5889Y-240128D01*
X5871Y-240110D01*
X5853Y-240085D01*
X5835Y-240059D01*
X5813Y-240027D01*
X5777Y-239957D01*
X5740Y-239870D01*
X5726Y-239826D01*
X5718Y-239775D01*
X5711Y-239724D01*
X5708Y-239670D01*
Y-239663D01*
Y-239644D01*
X5711Y-239615D01*
X5715Y-239575D01*
X5722Y-239531D01*
X5737Y-239481D01*
X5751Y-239426D01*
X5773Y-239371D01*
X5777Y-239364D01*
X5784Y-239346D01*
X5799Y-239317D01*
X5820Y-239277D01*
X5850Y-239233D01*
X5886Y-239178D01*
X5930Y-239124D01*
X5980Y-239062D01*
X5988Y-239055D01*
X6006Y-239033D01*
X6024Y-239015D01*
X6042Y-238997D01*
X6064Y-238975D01*
X6093Y-238946D01*
X6123Y-238916D01*
X6159Y-238884D01*
X6195Y-238847D01*
X6239Y-238807D01*
X6286Y-238767D01*
X6337Y-238720D01*
X6396Y-238672D01*
X6454Y-238621D01*
X6457Y-238618D01*
X6465Y-238611D01*
X6479Y-238600D01*
X6497Y-238585D01*
X6519Y-238563D01*
X6545Y-238541D01*
X6603Y-238494D01*
X6665Y-238439D01*
X6723Y-238385D01*
X6774Y-238338D01*
X6796Y-238319D01*
X6814Y-238301D01*
X6818Y-238298D01*
X6829Y-238287D01*
X6843Y-238272D01*
X6861Y-238250D01*
X6880Y-238225D01*
X6901Y-238199D01*
X6945Y-238137D01*
X5704D01*
Y-237839D01*
X7375D01*
Y-237843D01*
D02*
G37*
G36*
X5973Y-349216D02*
X6006D01*
X6046Y-349220D01*
X6089Y-349227D01*
X6140Y-349234D01*
X6246Y-349253D01*
X6355Y-349282D01*
X6464Y-349322D01*
X6515Y-349347D01*
X6566Y-349376D01*
X6570Y-349380D01*
X6577Y-349384D01*
X6592Y-349395D01*
X6606Y-349409D01*
X6628Y-349424D01*
X6654Y-349446D01*
X6683Y-349471D01*
X6712Y-349500D01*
X6741Y-349533D01*
X6774Y-349566D01*
X6839Y-349649D01*
X6901Y-349748D01*
X6956Y-349857D01*
Y-349861D01*
X6963Y-349871D01*
X6966Y-349890D01*
X6977Y-349911D01*
X6985Y-349941D01*
X6996Y-349977D01*
X7010Y-350017D01*
X7021Y-350061D01*
X7032Y-350108D01*
X7047Y-350163D01*
X7065Y-350275D01*
X7079Y-350403D01*
X7087Y-350534D01*
Y-350537D01*
Y-350552D01*
Y-350574D01*
X7083Y-350599D01*
Y-350636D01*
X7079Y-350672D01*
X7076Y-350719D01*
X7068Y-350767D01*
X7050Y-350872D01*
X7025Y-350989D01*
X6988Y-351105D01*
X6937Y-351218D01*
X6934Y-351222D01*
X6930Y-351233D01*
X6923Y-351247D01*
X6908Y-351266D01*
X6894Y-351291D01*
X6876Y-351320D01*
X6828Y-351386D01*
X6766Y-351458D01*
X6694Y-351531D01*
X6610Y-351604D01*
X6511Y-351666D01*
X6508Y-351670D01*
X6497Y-351673D01*
X6482Y-351680D01*
X6464Y-351691D01*
X6435Y-351702D01*
X6406Y-351713D01*
X6370Y-351728D01*
X6329Y-351742D01*
X6286Y-351757D01*
X6239Y-351771D01*
X6137Y-351793D01*
X6020Y-351812D01*
X5900Y-351819D01*
X5864D01*
X5838Y-351815D01*
X5805Y-351812D01*
X5765Y-351808D01*
X5725Y-351804D01*
X5678Y-351793D01*
X5580Y-351771D01*
X5471Y-351739D01*
X5416Y-351717D01*
X5365Y-351691D01*
X5314Y-351659D01*
X5263Y-351626D01*
X5259Y-351622D01*
X5252Y-351619D01*
X5237Y-351608D01*
X5219Y-351589D01*
X5201Y-351571D01*
X5176Y-351546D01*
X5150Y-351517D01*
X5121Y-351488D01*
X5092Y-351451D01*
X5063Y-351408D01*
X5030Y-351364D01*
X5001Y-351316D01*
X4975Y-351262D01*
X4946Y-351207D01*
X4924Y-351149D01*
X4903Y-351083D01*
X5230Y-351007D01*
Y-351011D01*
X5234Y-351018D01*
X5241Y-351033D01*
X5248Y-351051D01*
X5256Y-351073D01*
X5267Y-351102D01*
X5296Y-351160D01*
X5332Y-351225D01*
X5376Y-351291D01*
X5430Y-351353D01*
X5489Y-351408D01*
X5496Y-351415D01*
X5518Y-351429D01*
X5554Y-351448D01*
X5601Y-351473D01*
X5663Y-351495D01*
X5733Y-351517D01*
X5816Y-351531D01*
X5907Y-351535D01*
X5936D01*
X5955Y-351531D01*
X5980D01*
X6009Y-351528D01*
X6078Y-351517D01*
X6155Y-351502D01*
X6235Y-351477D01*
X6319Y-351440D01*
X6395Y-351393D01*
X6399D01*
X6402Y-351386D01*
X6428Y-351367D01*
X6461Y-351338D01*
X6501Y-351295D01*
X6548Y-351240D01*
X6592Y-351178D01*
X6632Y-351102D01*
X6668Y-351018D01*
Y-351014D01*
X6672Y-351007D01*
X6675Y-350996D01*
X6679Y-350978D01*
X6686Y-350956D01*
X6694Y-350931D01*
X6704Y-350869D01*
X6719Y-350796D01*
X6734Y-350716D01*
X6741Y-350628D01*
X6745Y-350534D01*
Y-350530D01*
Y-350519D01*
Y-350501D01*
Y-350479D01*
X6741Y-350454D01*
Y-350421D01*
X6737Y-350385D01*
X6734Y-350345D01*
X6723Y-350257D01*
X6704Y-350163D01*
X6683Y-350068D01*
X6654Y-349973D01*
Y-349970D01*
X6650Y-349962D01*
X6643Y-349952D01*
X6635Y-349933D01*
X6613Y-349890D01*
X6581Y-349839D01*
X6541Y-349780D01*
X6490Y-349718D01*
X6431Y-349664D01*
X6362Y-349613D01*
X6359D01*
X6351Y-349609D01*
X6340Y-349602D01*
X6326Y-349595D01*
X6308Y-349587D01*
X6286Y-349577D01*
X6235Y-349555D01*
X6169Y-349533D01*
X6097Y-349515D01*
X6016Y-349500D01*
X5933Y-349497D01*
X5907D01*
X5885Y-349500D01*
X5860D01*
X5835Y-349504D01*
X5769Y-349518D01*
X5692Y-349536D01*
X5616Y-349566D01*
X5536Y-349606D01*
X5496Y-349627D01*
X5460Y-349657D01*
X5456Y-349660D01*
X5452Y-349664D01*
X5441Y-349675D01*
X5427Y-349686D01*
X5412Y-349704D01*
X5394Y-349726D01*
X5372Y-349748D01*
X5354Y-349777D01*
X5332Y-349810D01*
X5307Y-349846D01*
X5285Y-349882D01*
X5263Y-349926D01*
X5245Y-349973D01*
X5227Y-350024D01*
X5208Y-350079D01*
X5194Y-350137D01*
X4859Y-350053D01*
Y-350050D01*
X4863Y-350035D01*
X4870Y-350013D01*
X4881Y-349984D01*
X4892Y-349952D01*
X4906Y-349911D01*
X4924Y-349868D01*
X4946Y-349820D01*
X4997Y-349718D01*
X5063Y-349617D01*
X5103Y-349566D01*
X5143Y-349515D01*
X5187Y-349471D01*
X5237Y-349427D01*
X5241Y-349424D01*
X5248Y-349416D01*
X5267Y-349409D01*
X5285Y-349395D01*
X5314Y-349376D01*
X5343Y-349358D01*
X5383Y-349340D01*
X5423Y-349322D01*
X5471Y-349300D01*
X5521Y-349282D01*
X5576Y-349264D01*
X5634Y-349245D01*
X5696Y-349231D01*
X5762Y-349223D01*
X5831Y-349216D01*
X5904Y-349213D01*
X5944D01*
X5973Y-349216D01*
D02*
G37*
G36*
X4619Y-349260D02*
Y-349274D01*
Y-349296D01*
X4615Y-349325D01*
X4611Y-349358D01*
X4604Y-349395D01*
X4597Y-349431D01*
X4582Y-349471D01*
Y-349475D01*
X4579Y-349478D01*
X4571Y-349500D01*
X4557Y-349533D01*
X4535Y-349577D01*
X4506Y-349627D01*
X4470Y-349686D01*
X4429Y-349744D01*
X4378Y-349806D01*
Y-349810D01*
X4371Y-349813D01*
X4353Y-349835D01*
X4320Y-349868D01*
X4273Y-349915D01*
X4218Y-349970D01*
X4149Y-350035D01*
X4065Y-350108D01*
X3974Y-350184D01*
X3971Y-350188D01*
X3956Y-350199D01*
X3934Y-350217D01*
X3909Y-350239D01*
X3876Y-350268D01*
X3836Y-350301D01*
X3796Y-350337D01*
X3749Y-350377D01*
X3658Y-350465D01*
X3567Y-350552D01*
X3523Y-350596D01*
X3483Y-350639D01*
X3447Y-350679D01*
X3418Y-350719D01*
Y-350723D01*
X3410Y-350727D01*
X3403Y-350738D01*
X3396Y-350752D01*
X3370Y-350792D01*
X3341Y-350840D01*
X3316Y-350898D01*
X3290Y-350960D01*
X3276Y-351029D01*
X3268Y-351095D01*
Y-351098D01*
Y-351102D01*
X3272Y-351124D01*
X3276Y-351160D01*
X3286Y-351200D01*
X3301Y-351251D01*
X3326Y-351302D01*
X3359Y-351353D01*
X3403Y-351404D01*
X3410Y-351411D01*
X3428Y-351426D01*
X3454Y-351444D01*
X3494Y-351469D01*
X3545Y-351491D01*
X3603Y-351513D01*
X3672Y-351528D01*
X3749Y-351531D01*
X3771D01*
X3785Y-351528D01*
X3829Y-351524D01*
X3880Y-351513D01*
X3934Y-351499D01*
X3996Y-351473D01*
X4055Y-351440D01*
X4109Y-351397D01*
X4116Y-351389D01*
X4131Y-351371D01*
X4153Y-351342D01*
X4175Y-351298D01*
X4200Y-351247D01*
X4222Y-351182D01*
X4236Y-351109D01*
X4244Y-351025D01*
X4561Y-351058D01*
Y-351062D01*
X4557Y-351073D01*
Y-351091D01*
X4553Y-351116D01*
X4546Y-351145D01*
X4539Y-351178D01*
X4528Y-351218D01*
X4517Y-351258D01*
X4488Y-351346D01*
X4444Y-351433D01*
X4419Y-351477D01*
X4386Y-351520D01*
X4353Y-351560D01*
X4317Y-351597D01*
X4313Y-351600D01*
X4306Y-351604D01*
X4295Y-351615D01*
X4277Y-351626D01*
X4255Y-351641D01*
X4229Y-351655D01*
X4200Y-351673D01*
X4164Y-351691D01*
X4124Y-351710D01*
X4080Y-351728D01*
X4033Y-351742D01*
X3982Y-351757D01*
X3927Y-351768D01*
X3869Y-351779D01*
X3807Y-351782D01*
X3742Y-351786D01*
X3705D01*
X3680Y-351782D01*
X3650Y-351779D01*
X3614Y-351775D01*
X3574Y-351768D01*
X3534Y-351761D01*
X3439Y-351735D01*
X3345Y-351699D01*
X3297Y-351677D01*
X3250Y-351651D01*
X3206Y-351619D01*
X3166Y-351582D01*
X3163Y-351579D01*
X3155Y-351575D01*
X3148Y-351560D01*
X3134Y-351546D01*
X3115Y-351528D01*
X3097Y-351502D01*
X3079Y-351477D01*
X3057Y-351444D01*
X3021Y-351375D01*
X2984Y-351287D01*
X2970Y-351244D01*
X2963Y-351193D01*
X2955Y-351142D01*
X2952Y-351087D01*
Y-351080D01*
Y-351062D01*
X2955Y-351033D01*
X2959Y-350992D01*
X2966Y-350949D01*
X2981Y-350898D01*
X2995Y-350843D01*
X3017Y-350789D01*
X3021Y-350781D01*
X3028Y-350763D01*
X3043Y-350734D01*
X3064Y-350694D01*
X3094Y-350650D01*
X3130Y-350596D01*
X3174Y-350541D01*
X3225Y-350479D01*
X3232Y-350472D01*
X3250Y-350450D01*
X3268Y-350432D01*
X3286Y-350414D01*
X3308Y-350392D01*
X3337Y-350363D01*
X3367Y-350334D01*
X3403Y-350301D01*
X3439Y-350265D01*
X3483Y-350224D01*
X3530Y-350184D01*
X3581Y-350137D01*
X3640Y-350090D01*
X3698Y-350039D01*
X3701Y-350035D01*
X3709Y-350028D01*
X3723Y-350017D01*
X3742Y-350002D01*
X3763Y-349981D01*
X3789Y-349959D01*
X3847Y-349911D01*
X3909Y-349857D01*
X3967Y-349802D01*
X4018Y-349755D01*
X4040Y-349737D01*
X4058Y-349718D01*
X4062Y-349715D01*
X4073Y-349704D01*
X4087Y-349689D01*
X4106Y-349668D01*
X4124Y-349642D01*
X4146Y-349617D01*
X4189Y-349555D01*
X2948D01*
Y-349256D01*
X4619D01*
Y-349260D01*
D02*
G37*
G36*
X1852Y-349216D02*
X1885Y-349220D01*
X1922Y-349223D01*
X1962Y-349231D01*
X2005Y-349242D01*
X2104Y-349267D01*
X2154Y-349285D01*
X2202Y-349304D01*
X2253Y-349329D01*
X2304Y-349358D01*
X2351Y-349391D01*
X2395Y-349431D01*
X2398Y-349435D01*
X2406Y-349442D01*
X2417Y-349453D01*
X2431Y-349471D01*
X2446Y-349493D01*
X2468Y-349518D01*
X2486Y-349547D01*
X2507Y-349584D01*
X2529Y-349620D01*
X2548Y-349664D01*
X2584Y-349755D01*
X2599Y-349810D01*
X2609Y-349864D01*
X2617Y-349922D01*
X2620Y-349981D01*
Y-349984D01*
Y-349991D01*
Y-350006D01*
X2617Y-350021D01*
Y-350043D01*
X2613Y-350068D01*
X2606Y-350126D01*
X2591Y-350192D01*
X2569Y-350257D01*
X2537Y-350326D01*
X2497Y-350392D01*
Y-350396D01*
X2489Y-350399D01*
X2475Y-350417D01*
X2446Y-350447D01*
X2406Y-350483D01*
X2355Y-350519D01*
X2293Y-350559D01*
X2224Y-350592D01*
X2140Y-350618D01*
X2144D01*
X2147Y-350621D01*
X2158Y-350625D01*
X2173Y-350632D01*
X2205Y-350647D01*
X2249Y-350669D01*
X2296Y-350698D01*
X2344Y-350734D01*
X2387Y-350774D01*
X2427Y-350818D01*
X2431Y-350825D01*
X2442Y-350840D01*
X2457Y-350869D01*
X2471Y-350905D01*
X2489Y-350953D01*
X2504Y-351007D01*
X2515Y-351069D01*
X2518Y-351134D01*
Y-351138D01*
Y-351145D01*
Y-351160D01*
X2515Y-351182D01*
X2511Y-351204D01*
X2507Y-351233D01*
X2493Y-351295D01*
X2471Y-351367D01*
X2435Y-351444D01*
X2413Y-351484D01*
X2387Y-351524D01*
X2355Y-351560D01*
X2322Y-351597D01*
X2318Y-351600D01*
X2311Y-351604D01*
X2300Y-351615D01*
X2286Y-351626D01*
X2267Y-351641D01*
X2242Y-351655D01*
X2213Y-351673D01*
X2184Y-351691D01*
X2147Y-351710D01*
X2107Y-351728D01*
X2063Y-351742D01*
X2016Y-351757D01*
X1914Y-351779D01*
X1856Y-351782D01*
X1798Y-351786D01*
X1765D01*
X1743Y-351782D01*
X1714Y-351779D01*
X1681Y-351775D01*
X1645Y-351771D01*
X1608Y-351761D01*
X1521Y-351739D01*
X1434Y-351706D01*
X1390Y-351684D01*
X1346Y-351659D01*
X1306Y-351626D01*
X1266Y-351593D01*
X1263Y-351589D01*
X1259Y-351586D01*
X1248Y-351575D01*
X1233Y-351560D01*
X1219Y-351538D01*
X1201Y-351517D01*
X1164Y-351462D01*
X1128Y-351393D01*
X1095Y-351313D01*
X1070Y-351222D01*
X1066Y-351174D01*
X1062Y-351124D01*
Y-351120D01*
Y-351116D01*
Y-351095D01*
X1066Y-351062D01*
X1073Y-351022D01*
X1084Y-350971D01*
X1103Y-350920D01*
X1124Y-350869D01*
X1157Y-350818D01*
X1161Y-350811D01*
X1175Y-350796D01*
X1197Y-350774D01*
X1226Y-350745D01*
X1266Y-350712D01*
X1314Y-350679D01*
X1368Y-350647D01*
X1434Y-350618D01*
X1430D01*
X1423Y-350614D01*
X1412Y-350610D01*
X1397Y-350603D01*
X1354Y-350585D01*
X1303Y-350559D01*
X1248Y-350523D01*
X1190Y-350483D01*
X1135Y-350432D01*
X1084Y-350374D01*
Y-350370D01*
X1081Y-350366D01*
X1066Y-350345D01*
X1044Y-350308D01*
X1022Y-350261D01*
X1001Y-350203D01*
X979Y-350133D01*
X964Y-350057D01*
X960Y-349973D01*
Y-349970D01*
Y-349959D01*
Y-349941D01*
X964Y-349919D01*
X968Y-349893D01*
X971Y-349861D01*
X979Y-349824D01*
X990Y-349784D01*
X1015Y-349700D01*
X1033Y-349653D01*
X1059Y-349609D01*
X1084Y-349562D01*
X1113Y-349518D01*
X1150Y-349475D01*
X1190Y-349431D01*
X1194Y-349427D01*
X1201Y-349420D01*
X1212Y-349409D01*
X1230Y-349398D01*
X1255Y-349380D01*
X1281Y-349362D01*
X1314Y-349344D01*
X1350Y-349322D01*
X1390Y-349300D01*
X1437Y-349282D01*
X1488Y-349264D01*
X1539Y-349245D01*
X1598Y-349234D01*
X1659Y-349223D01*
X1721Y-349216D01*
X1790Y-349213D01*
X1827D01*
X1852Y-349216D01*
D02*
G37*
G36*
X15560Y-298429D02*
X15596D01*
X15633Y-298432D01*
X15680Y-298436D01*
X15728Y-298443D01*
X15833Y-298462D01*
X15949Y-298487D01*
X16066Y-298523D01*
X16179Y-298574D01*
X16183Y-298578D01*
X16193Y-298582D01*
X16208Y-298589D01*
X16226Y-298604D01*
X16252Y-298618D01*
X16281Y-298636D01*
X16346Y-298684D01*
X16419Y-298745D01*
X16492Y-298818D01*
X16565Y-298902D01*
X16626Y-299000D01*
X16630Y-299004D01*
X16634Y-299015D01*
X16641Y-299029D01*
X16652Y-299048D01*
X16663Y-299077D01*
X16674Y-299106D01*
X16688Y-299142D01*
X16703Y-299182D01*
X16717Y-299226D01*
X16732Y-299273D01*
X16754Y-299375D01*
X16772Y-299492D01*
X16779Y-299612D01*
Y-299648D01*
X16776Y-299674D01*
X16772Y-299706D01*
X16769Y-299746D01*
X16765Y-299786D01*
X16754Y-299834D01*
X16732Y-299932D01*
X16699Y-300041D01*
X16678Y-300096D01*
X16652Y-300147D01*
X16619Y-300198D01*
X16587Y-300249D01*
X16583Y-300252D01*
X16579Y-300260D01*
X16568Y-300274D01*
X16550Y-300292D01*
X16532Y-300311D01*
X16506Y-300336D01*
X16477Y-300362D01*
X16448Y-300391D01*
X16412Y-300420D01*
X16368Y-300449D01*
X16324Y-300482D01*
X16277Y-300511D01*
X16222Y-300536D01*
X16168Y-300566D01*
X16110Y-300587D01*
X16044Y-300609D01*
X15968Y-300282D01*
X15971D01*
X15979Y-300278D01*
X15993Y-300271D01*
X16011Y-300263D01*
X16033Y-300256D01*
X16062Y-300245D01*
X16121Y-300216D01*
X16186Y-300180D01*
X16252Y-300136D01*
X16314Y-300081D01*
X16368Y-300023D01*
X16375Y-300016D01*
X16390Y-299994D01*
X16408Y-299958D01*
X16434Y-299910D01*
X16455Y-299848D01*
X16477Y-299779D01*
X16492Y-299695D01*
X16496Y-299605D01*
Y-299575D01*
X16492Y-299557D01*
Y-299532D01*
X16488Y-299503D01*
X16477Y-299433D01*
X16463Y-299357D01*
X16437Y-299277D01*
X16401Y-299193D01*
X16353Y-299117D01*
Y-299113D01*
X16346Y-299110D01*
X16328Y-299084D01*
X16299Y-299051D01*
X16255Y-299011D01*
X16201Y-298964D01*
X16139Y-298920D01*
X16062Y-298880D01*
X15979Y-298844D01*
X15975D01*
X15968Y-298840D01*
X15957Y-298836D01*
X15939Y-298833D01*
X15917Y-298826D01*
X15891Y-298818D01*
X15829Y-298807D01*
X15757Y-298793D01*
X15676Y-298778D01*
X15589Y-298771D01*
X15495Y-298767D01*
X15491D01*
X15480D01*
X15462D01*
X15440D01*
X15414Y-298771D01*
X15382D01*
X15345Y-298775D01*
X15305Y-298778D01*
X15218Y-298789D01*
X15123Y-298807D01*
X15029Y-298829D01*
X14934Y-298858D01*
X14930D01*
X14923Y-298862D01*
X14912Y-298869D01*
X14894Y-298877D01*
X14850Y-298898D01*
X14799Y-298931D01*
X14741Y-298971D01*
X14679Y-299022D01*
X14625Y-299080D01*
X14574Y-299149D01*
Y-299153D01*
X14570Y-299160D01*
X14563Y-299171D01*
X14555Y-299186D01*
X14548Y-299204D01*
X14537Y-299226D01*
X14515Y-299277D01*
X14493Y-299342D01*
X14475Y-299415D01*
X14461Y-299495D01*
X14457Y-299579D01*
Y-299605D01*
X14461Y-299626D01*
Y-299652D01*
X14464Y-299677D01*
X14479Y-299743D01*
X14497Y-299819D01*
X14526Y-299896D01*
X14566Y-299976D01*
X14588Y-300016D01*
X14617Y-300052D01*
X14621Y-300056D01*
X14625Y-300060D01*
X14636Y-300070D01*
X14646Y-300085D01*
X14665Y-300100D01*
X14686Y-300118D01*
X14708Y-300140D01*
X14737Y-300158D01*
X14770Y-300180D01*
X14807Y-300205D01*
X14843Y-300227D01*
X14887Y-300249D01*
X14934Y-300267D01*
X14985Y-300285D01*
X15040Y-300303D01*
X15098Y-300318D01*
X15014Y-300653D01*
X15010D01*
X14996Y-300649D01*
X14974Y-300642D01*
X14945Y-300631D01*
X14912Y-300620D01*
X14872Y-300606D01*
X14828Y-300587D01*
X14781Y-300566D01*
X14679Y-300515D01*
X14577Y-300449D01*
X14526Y-300409D01*
X14475Y-300369D01*
X14432Y-300325D01*
X14388Y-300274D01*
X14384Y-300271D01*
X14377Y-300263D01*
X14370Y-300245D01*
X14355Y-300227D01*
X14337Y-300198D01*
X14319Y-300169D01*
X14301Y-300129D01*
X14282Y-300089D01*
X14261Y-300041D01*
X14242Y-299990D01*
X14224Y-299936D01*
X14206Y-299878D01*
X14191Y-299816D01*
X14184Y-299750D01*
X14177Y-299681D01*
X14173Y-299608D01*
Y-299568D01*
X14177Y-299539D01*
Y-299506D01*
X14180Y-299466D01*
X14188Y-299423D01*
X14195Y-299372D01*
X14213Y-299266D01*
X14242Y-299157D01*
X14282Y-299048D01*
X14308Y-298997D01*
X14337Y-298946D01*
X14341Y-298942D01*
X14344Y-298935D01*
X14355Y-298920D01*
X14370Y-298906D01*
X14384Y-298884D01*
X14406Y-298858D01*
X14432Y-298829D01*
X14461Y-298800D01*
X14493Y-298771D01*
X14526Y-298738D01*
X14610Y-298673D01*
X14708Y-298611D01*
X14818Y-298556D01*
X14821D01*
X14832Y-298549D01*
X14850Y-298545D01*
X14872Y-298534D01*
X14901Y-298527D01*
X14938Y-298516D01*
X14978Y-298502D01*
X15021Y-298491D01*
X15069Y-298480D01*
X15123Y-298465D01*
X15236Y-298447D01*
X15363Y-298432D01*
X15495Y-298425D01*
X15498D01*
X15513D01*
X15534D01*
X15560Y-298429D01*
D02*
G37*
G36*
X14286Y-300897D02*
X14319Y-300900D01*
X14355Y-300908D01*
X14392Y-300915D01*
X14432Y-300929D01*
X14435D01*
X14439Y-300933D01*
X14461Y-300940D01*
X14493Y-300955D01*
X14537Y-300977D01*
X14588Y-301006D01*
X14646Y-301042D01*
X14705Y-301082D01*
X14766Y-301133D01*
X14770D01*
X14774Y-301141D01*
X14796Y-301159D01*
X14828Y-301192D01*
X14876Y-301239D01*
X14930Y-301293D01*
X14996Y-301363D01*
X15069Y-301446D01*
X15145Y-301537D01*
X15149Y-301541D01*
X15160Y-301556D01*
X15178Y-301577D01*
X15200Y-301603D01*
X15229Y-301636D01*
X15261Y-301676D01*
X15298Y-301716D01*
X15338Y-301763D01*
X15425Y-301854D01*
X15513Y-301945D01*
X15556Y-301989D01*
X15600Y-302029D01*
X15640Y-302065D01*
X15680Y-302094D01*
X15684D01*
X15687Y-302102D01*
X15698Y-302109D01*
X15713Y-302116D01*
X15753Y-302142D01*
X15800Y-302171D01*
X15858Y-302196D01*
X15920Y-302222D01*
X15990Y-302236D01*
X16055Y-302243D01*
X16059D01*
X16062D01*
X16084Y-302240D01*
X16121Y-302236D01*
X16161Y-302225D01*
X16212Y-302211D01*
X16262Y-302185D01*
X16314Y-302152D01*
X16364Y-302109D01*
X16372Y-302102D01*
X16386Y-302083D01*
X16405Y-302058D01*
X16430Y-302018D01*
X16452Y-301967D01*
X16474Y-301909D01*
X16488Y-301839D01*
X16492Y-301763D01*
Y-301741D01*
X16488Y-301727D01*
X16485Y-301683D01*
X16474Y-301632D01*
X16459Y-301577D01*
X16434Y-301516D01*
X16401Y-301457D01*
X16357Y-301403D01*
X16350Y-301395D01*
X16332Y-301381D01*
X16303Y-301359D01*
X16259Y-301337D01*
X16208Y-301312D01*
X16142Y-301290D01*
X16070Y-301275D01*
X15986Y-301268D01*
X16019Y-300951D01*
X16022D01*
X16033Y-300955D01*
X16051D01*
X16077Y-300959D01*
X16106Y-300966D01*
X16139Y-300973D01*
X16179Y-300984D01*
X16219Y-300995D01*
X16306Y-301024D01*
X16394Y-301068D01*
X16437Y-301093D01*
X16481Y-301126D01*
X16521Y-301159D01*
X16557Y-301195D01*
X16561Y-301199D01*
X16565Y-301206D01*
X16576Y-301217D01*
X16587Y-301235D01*
X16601Y-301257D01*
X16616Y-301283D01*
X16634Y-301312D01*
X16652Y-301348D01*
X16670Y-301388D01*
X16688Y-301432D01*
X16703Y-301479D01*
X16717Y-301530D01*
X16728Y-301585D01*
X16739Y-301643D01*
X16743Y-301705D01*
X16747Y-301770D01*
Y-301807D01*
X16743Y-301832D01*
X16739Y-301861D01*
X16736Y-301898D01*
X16728Y-301938D01*
X16721Y-301978D01*
X16696Y-302072D01*
X16659Y-302167D01*
X16637Y-302214D01*
X16612Y-302262D01*
X16579Y-302305D01*
X16543Y-302345D01*
X16539Y-302349D01*
X16535Y-302356D01*
X16521Y-302364D01*
X16506Y-302378D01*
X16488Y-302396D01*
X16463Y-302415D01*
X16437Y-302433D01*
X16405Y-302455D01*
X16335Y-302491D01*
X16248Y-302527D01*
X16204Y-302542D01*
X16153Y-302549D01*
X16102Y-302557D01*
X16048Y-302560D01*
X16040D01*
X16022D01*
X15993Y-302557D01*
X15953Y-302553D01*
X15910Y-302546D01*
X15858Y-302531D01*
X15804Y-302517D01*
X15749Y-302495D01*
X15742Y-302491D01*
X15724Y-302484D01*
X15695Y-302469D01*
X15655Y-302447D01*
X15611Y-302418D01*
X15556Y-302382D01*
X15502Y-302338D01*
X15440Y-302287D01*
X15433Y-302280D01*
X15411Y-302262D01*
X15393Y-302243D01*
X15374Y-302225D01*
X15352Y-302203D01*
X15323Y-302174D01*
X15294Y-302145D01*
X15261Y-302109D01*
X15225Y-302072D01*
X15185Y-302029D01*
X15145Y-301981D01*
X15098Y-301930D01*
X15050Y-301872D01*
X14999Y-301814D01*
X14996Y-301810D01*
X14988Y-301803D01*
X14978Y-301788D01*
X14963Y-301770D01*
X14941Y-301748D01*
X14919Y-301723D01*
X14872Y-301665D01*
X14818Y-301603D01*
X14763Y-301545D01*
X14716Y-301494D01*
X14697Y-301472D01*
X14679Y-301454D01*
X14675Y-301450D01*
X14665Y-301439D01*
X14650Y-301425D01*
X14628Y-301406D01*
X14603Y-301388D01*
X14577Y-301366D01*
X14515Y-301323D01*
Y-302564D01*
X14217D01*
Y-300893D01*
X14220D01*
X14235D01*
X14257D01*
X14286Y-300897D01*
D02*
G37*
G36*
X16703Y-304548D02*
X16459D01*
X16455Y-304544D01*
X16448Y-304537D01*
X16434Y-304522D01*
X16412Y-304508D01*
X16386Y-304486D01*
X16357Y-304457D01*
X16321Y-304428D01*
X16277Y-304395D01*
X16233Y-304362D01*
X16183Y-304322D01*
X16124Y-304282D01*
X16066Y-304242D01*
X16001Y-304198D01*
X15931Y-304154D01*
X15855Y-304111D01*
X15778Y-304067D01*
X15775Y-304064D01*
X15760Y-304056D01*
X15738Y-304045D01*
X15706Y-304027D01*
X15666Y-304009D01*
X15622Y-303987D01*
X15571Y-303962D01*
X15513Y-303936D01*
X15447Y-303907D01*
X15382Y-303874D01*
X15309Y-303845D01*
X15232Y-303816D01*
X15076Y-303758D01*
X14909Y-303703D01*
X14905D01*
X14894Y-303699D01*
X14876Y-303696D01*
X14854Y-303689D01*
X14825Y-303681D01*
X14788Y-303674D01*
X14748Y-303663D01*
X14705Y-303656D01*
X14654Y-303645D01*
X14599Y-303634D01*
X14483Y-303616D01*
X14355Y-303598D01*
X14217Y-303587D01*
Y-303270D01*
X14220D01*
X14231D01*
X14246D01*
X14268Y-303274D01*
X14297D01*
X14333Y-303277D01*
X14373Y-303281D01*
X14417Y-303285D01*
X14468Y-303292D01*
X14519Y-303299D01*
X14581Y-303310D01*
X14643Y-303321D01*
X14708Y-303332D01*
X14781Y-303346D01*
X14930Y-303383D01*
X14934D01*
X14949Y-303386D01*
X14970Y-303394D01*
X15003Y-303405D01*
X15040Y-303416D01*
X15083Y-303430D01*
X15134Y-303445D01*
X15189Y-303467D01*
X15251Y-303488D01*
X15313Y-303510D01*
X15451Y-303565D01*
X15596Y-303630D01*
X15742Y-303703D01*
X15746Y-303707D01*
X15760Y-303714D01*
X15778Y-303725D01*
X15808Y-303740D01*
X15840Y-303758D01*
X15880Y-303783D01*
X15924Y-303809D01*
X15971Y-303838D01*
X16077Y-303907D01*
X16186Y-303980D01*
X16299Y-304064D01*
X16405Y-304151D01*
Y-302917D01*
X16703D01*
Y-304548D01*
D02*
G37*
G36*
X6519Y-193311D02*
X6548D01*
X6580Y-193314D01*
X6617Y-193322D01*
X6661Y-193333D01*
X6704Y-193343D01*
X6755Y-193358D01*
X6806Y-193376D01*
X6857Y-193398D01*
X6912Y-193427D01*
X6963Y-193460D01*
X7013Y-193496D01*
X7064Y-193540D01*
X7112Y-193591D01*
X7115Y-193595D01*
X7123Y-193605D01*
X7134Y-193620D01*
X7148Y-193646D01*
X7170Y-193678D01*
X7188Y-193715D01*
X7210Y-193762D01*
X7232Y-193813D01*
X7257Y-193875D01*
X7279Y-193944D01*
X7298Y-194020D01*
X7316Y-194104D01*
X7334Y-194199D01*
X7345Y-194301D01*
X7352Y-194410D01*
X7356Y-194526D01*
Y-194530D01*
Y-194534D01*
Y-194545D01*
Y-194559D01*
X7352Y-194596D01*
Y-194647D01*
X7348Y-194705D01*
X7341Y-194774D01*
X7334Y-194850D01*
X7323Y-194934D01*
X7308Y-195018D01*
X7290Y-195109D01*
X7268Y-195196D01*
X7243Y-195284D01*
X7210Y-195367D01*
X7174Y-195447D01*
X7134Y-195524D01*
X7086Y-195589D01*
X7083Y-195593D01*
X7075Y-195600D01*
X7061Y-195615D01*
X7043Y-195637D01*
X7021Y-195659D01*
X6992Y-195680D01*
X6955Y-195709D01*
X6919Y-195735D01*
X6875Y-195760D01*
X6828Y-195790D01*
X6773Y-195811D01*
X6719Y-195837D01*
X6657Y-195855D01*
X6591Y-195870D01*
X6522Y-195877D01*
X6449Y-195880D01*
X6420D01*
X6398Y-195877D01*
X6373D01*
X6344Y-195873D01*
X6275Y-195859D01*
X6198Y-195841D01*
X6118Y-195811D01*
X6038Y-195768D01*
X5998Y-195742D01*
X5962Y-195713D01*
X5958Y-195709D01*
X5954Y-195706D01*
X5943Y-195695D01*
X5932Y-195684D01*
X5914Y-195666D01*
X5900Y-195644D01*
X5860Y-195593D01*
X5820Y-195527D01*
X5783Y-195447D01*
X5751Y-195356D01*
X5729Y-195254D01*
X6038Y-195229D01*
Y-195233D01*
X6042Y-195236D01*
X6045Y-195258D01*
X6056Y-195291D01*
X6071Y-195331D01*
X6085Y-195375D01*
X6107Y-195418D01*
X6133Y-195458D01*
X6158Y-195491D01*
X6165Y-195498D01*
X6180Y-195513D01*
X6205Y-195535D01*
X6242Y-195560D01*
X6289Y-195582D01*
X6340Y-195604D01*
X6402Y-195618D01*
X6468Y-195626D01*
X6493D01*
X6522Y-195622D01*
X6555Y-195615D01*
X6599Y-195604D01*
X6642Y-195589D01*
X6686Y-195571D01*
X6730Y-195542D01*
X6737Y-195538D01*
X6755Y-195524D01*
X6781Y-195498D01*
X6813Y-195462D01*
X6850Y-195418D01*
X6890Y-195367D01*
X6926Y-195302D01*
X6963Y-195229D01*
Y-195225D01*
X6966Y-195218D01*
X6970Y-195207D01*
X6977Y-195193D01*
X6981Y-195171D01*
X6988Y-195145D01*
X6995Y-195116D01*
X7003Y-195080D01*
X7013Y-195040D01*
X7021Y-194996D01*
X7028Y-194949D01*
X7032Y-194898D01*
X7039Y-194840D01*
X7043Y-194781D01*
X7046Y-194716D01*
Y-194650D01*
X7043Y-194654D01*
X7028Y-194676D01*
X7003Y-194705D01*
X6970Y-194741D01*
X6933Y-194785D01*
X6886Y-194825D01*
X6835Y-194865D01*
X6777Y-194901D01*
X6773D01*
X6770Y-194905D01*
X6748Y-194916D01*
X6715Y-194927D01*
X6671Y-194945D01*
X6620Y-194960D01*
X6562Y-194971D01*
X6500Y-194981D01*
X6435Y-194985D01*
X6406D01*
X6384Y-194981D01*
X6355Y-194978D01*
X6326Y-194974D01*
X6289Y-194967D01*
X6253Y-194956D01*
X6169Y-194931D01*
X6125Y-194912D01*
X6082Y-194887D01*
X6038Y-194861D01*
X5991Y-194832D01*
X5947Y-194796D01*
X5907Y-194756D01*
X5903Y-194752D01*
X5896Y-194745D01*
X5885Y-194734D01*
X5874Y-194716D01*
X5856Y-194690D01*
X5838Y-194665D01*
X5820Y-194632D01*
X5798Y-194596D01*
X5776Y-194556D01*
X5758Y-194512D01*
X5740Y-194461D01*
X5721Y-194410D01*
X5710Y-194355D01*
X5700Y-194293D01*
X5692Y-194232D01*
X5689Y-194166D01*
Y-194162D01*
Y-194155D01*
Y-194144D01*
Y-194126D01*
X5692Y-194104D01*
Y-194082D01*
X5703Y-194024D01*
X5714Y-193955D01*
X5732Y-193882D01*
X5758Y-193802D01*
X5794Y-193726D01*
Y-193722D01*
X5798Y-193718D01*
X5805Y-193707D01*
X5812Y-193693D01*
X5834Y-193657D01*
X5867Y-193609D01*
X5907Y-193558D01*
X5954Y-193507D01*
X6013Y-193456D01*
X6074Y-193413D01*
X6078D01*
X6082Y-193409D01*
X6093Y-193402D01*
X6107Y-193398D01*
X6144Y-193380D01*
X6191Y-193362D01*
X6253Y-193340D01*
X6322Y-193325D01*
X6398Y-193311D01*
X6482Y-193307D01*
X6500D01*
X6519Y-193311D01*
D02*
G37*
G36*
X10697D02*
X10730D01*
X10770Y-193314D01*
X10814Y-193322D01*
X10865Y-193329D01*
X10970Y-193347D01*
X11079Y-193376D01*
X11189Y-193416D01*
X11240Y-193442D01*
X11291Y-193471D01*
X11294Y-193474D01*
X11302Y-193478D01*
X11316Y-193489D01*
X11331Y-193504D01*
X11352Y-193518D01*
X11378Y-193540D01*
X11407Y-193565D01*
X11436Y-193595D01*
X11465Y-193627D01*
X11498Y-193660D01*
X11564Y-193744D01*
X11625Y-193842D01*
X11680Y-193951D01*
Y-193955D01*
X11687Y-193966D01*
X11691Y-193984D01*
X11702Y-194006D01*
X11709Y-194035D01*
X11720Y-194071D01*
X11735Y-194112D01*
X11746Y-194155D01*
X11756Y-194202D01*
X11771Y-194257D01*
X11789Y-194370D01*
X11804Y-194497D01*
X11811Y-194628D01*
Y-194632D01*
Y-194647D01*
Y-194668D01*
X11807Y-194694D01*
Y-194730D01*
X11804Y-194767D01*
X11800Y-194814D01*
X11793Y-194861D01*
X11775Y-194967D01*
X11749Y-195083D01*
X11713Y-195200D01*
X11662Y-195313D01*
X11658Y-195316D01*
X11655Y-195327D01*
X11647Y-195342D01*
X11633Y-195360D01*
X11618Y-195386D01*
X11600Y-195415D01*
X11553Y-195480D01*
X11491Y-195553D01*
X11418Y-195626D01*
X11334Y-195698D01*
X11236Y-195760D01*
X11232Y-195764D01*
X11221Y-195768D01*
X11207Y-195775D01*
X11189Y-195786D01*
X11159Y-195797D01*
X11130Y-195808D01*
X11094Y-195822D01*
X11054Y-195837D01*
X11010Y-195851D01*
X10963Y-195866D01*
X10861Y-195888D01*
X10745Y-195906D01*
X10624Y-195913D01*
X10588D01*
X10563Y-195910D01*
X10530Y-195906D01*
X10490Y-195902D01*
X10450Y-195899D01*
X10402Y-195888D01*
X10304Y-195866D01*
X10195Y-195833D01*
X10140Y-195811D01*
X10089Y-195786D01*
X10038Y-195753D01*
X9987Y-195720D01*
X9984Y-195717D01*
X9977Y-195713D01*
X9962Y-195702D01*
X9944Y-195684D01*
X9926Y-195666D01*
X9900Y-195640D01*
X9875Y-195611D01*
X9845Y-195582D01*
X9816Y-195546D01*
X9787Y-195502D01*
X9754Y-195458D01*
X9725Y-195411D01*
X9700Y-195356D01*
X9671Y-195302D01*
X9649Y-195244D01*
X9627Y-195178D01*
X9955Y-195102D01*
Y-195105D01*
X9958Y-195113D01*
X9966Y-195127D01*
X9973Y-195145D01*
X9980Y-195167D01*
X9991Y-195196D01*
X10020Y-195254D01*
X10057Y-195320D01*
X10100Y-195386D01*
X10155Y-195447D01*
X10213Y-195502D01*
X10220Y-195509D01*
X10242Y-195524D01*
X10279Y-195542D01*
X10326Y-195568D01*
X10388Y-195589D01*
X10457Y-195611D01*
X10541Y-195626D01*
X10632Y-195629D01*
X10661D01*
X10679Y-195626D01*
X10705D01*
X10734Y-195622D01*
X10803Y-195611D01*
X10879Y-195597D01*
X10959Y-195571D01*
X11043Y-195535D01*
X11119Y-195487D01*
X11123D01*
X11127Y-195480D01*
X11152Y-195462D01*
X11185Y-195433D01*
X11225Y-195389D01*
X11272Y-195334D01*
X11316Y-195273D01*
X11356Y-195196D01*
X11393Y-195113D01*
Y-195109D01*
X11396Y-195102D01*
X11400Y-195091D01*
X11403Y-195072D01*
X11411Y-195051D01*
X11418Y-195025D01*
X11429Y-194963D01*
X11443Y-194890D01*
X11458Y-194810D01*
X11465Y-194723D01*
X11469Y-194628D01*
Y-194625D01*
Y-194614D01*
Y-194596D01*
Y-194574D01*
X11465Y-194548D01*
Y-194516D01*
X11462Y-194479D01*
X11458Y-194439D01*
X11447Y-194352D01*
X11429Y-194257D01*
X11407Y-194162D01*
X11378Y-194068D01*
Y-194064D01*
X11374Y-194057D01*
X11367Y-194046D01*
X11360Y-194028D01*
X11338Y-193984D01*
X11305Y-193933D01*
X11265Y-193875D01*
X11214Y-193813D01*
X11156Y-193758D01*
X11087Y-193707D01*
X11083D01*
X11076Y-193704D01*
X11065Y-193696D01*
X11050Y-193689D01*
X11032Y-193682D01*
X11010Y-193671D01*
X10959Y-193649D01*
X10894Y-193627D01*
X10821Y-193609D01*
X10741Y-193595D01*
X10657Y-193591D01*
X10632D01*
X10610Y-193595D01*
X10584D01*
X10559Y-193598D01*
X10493Y-193613D01*
X10417Y-193631D01*
X10340Y-193660D01*
X10260Y-193700D01*
X10220Y-193722D01*
X10184Y-193751D01*
X10180Y-193755D01*
X10177Y-193758D01*
X10166Y-193769D01*
X10151Y-193780D01*
X10137Y-193798D01*
X10119Y-193820D01*
X10097Y-193842D01*
X10078Y-193871D01*
X10057Y-193904D01*
X10031Y-193940D01*
X10009Y-193977D01*
X9987Y-194020D01*
X9969Y-194068D01*
X9951Y-194119D01*
X9933Y-194173D01*
X9918Y-194232D01*
X9583Y-194148D01*
Y-194144D01*
X9587Y-194130D01*
X9594Y-194108D01*
X9605Y-194079D01*
X9616Y-194046D01*
X9631Y-194006D01*
X9649Y-193962D01*
X9671Y-193915D01*
X9722Y-193813D01*
X9787Y-193711D01*
X9827Y-193660D01*
X9867Y-193609D01*
X9911Y-193565D01*
X9962Y-193522D01*
X9966Y-193518D01*
X9973Y-193511D01*
X9991Y-193504D01*
X10009Y-193489D01*
X10038Y-193471D01*
X10068Y-193453D01*
X10108Y-193434D01*
X10148Y-193416D01*
X10195Y-193394D01*
X10246Y-193376D01*
X10300Y-193358D01*
X10359Y-193340D01*
X10421Y-193325D01*
X10486Y-193318D01*
X10555Y-193311D01*
X10628Y-193307D01*
X10668D01*
X10697Y-193311D01*
D02*
G37*
G36*
X9343Y-193354D02*
Y-193369D01*
Y-193391D01*
X9340Y-193420D01*
X9336Y-193453D01*
X9329Y-193489D01*
X9321Y-193525D01*
X9307Y-193565D01*
Y-193569D01*
X9303Y-193573D01*
X9296Y-193595D01*
X9281Y-193627D01*
X9259Y-193671D01*
X9230Y-193722D01*
X9194Y-193780D01*
X9154Y-193839D01*
X9103Y-193900D01*
Y-193904D01*
X9096Y-193908D01*
X9077Y-193930D01*
X9045Y-193962D01*
X8997Y-194010D01*
X8943Y-194064D01*
X8874Y-194130D01*
X8790Y-194202D01*
X8699Y-194279D01*
X8695Y-194283D01*
X8681Y-194293D01*
X8659Y-194312D01*
X8633Y-194334D01*
X8601Y-194363D01*
X8561Y-194395D01*
X8521Y-194432D01*
X8473Y-194472D01*
X8382Y-194559D01*
X8291Y-194647D01*
X8247Y-194690D01*
X8207Y-194734D01*
X8171Y-194774D01*
X8142Y-194814D01*
Y-194818D01*
X8135Y-194821D01*
X8127Y-194832D01*
X8120Y-194847D01*
X8095Y-194887D01*
X8066Y-194934D01*
X8040Y-194992D01*
X8015Y-195054D01*
X8000Y-195123D01*
X7993Y-195189D01*
Y-195193D01*
Y-195196D01*
X7996Y-195218D01*
X8000Y-195254D01*
X8011Y-195294D01*
X8026Y-195345D01*
X8051Y-195396D01*
X8084Y-195447D01*
X8127Y-195498D01*
X8135Y-195506D01*
X8153Y-195520D01*
X8178Y-195538D01*
X8218Y-195564D01*
X8269Y-195586D01*
X8328Y-195607D01*
X8397Y-195622D01*
X8473Y-195626D01*
X8495D01*
X8510Y-195622D01*
X8553Y-195618D01*
X8604Y-195607D01*
X8659Y-195593D01*
X8721Y-195568D01*
X8779Y-195535D01*
X8833Y-195491D01*
X8841Y-195484D01*
X8855Y-195466D01*
X8877Y-195436D01*
X8899Y-195393D01*
X8925Y-195342D01*
X8946Y-195276D01*
X8961Y-195203D01*
X8968Y-195120D01*
X9285Y-195152D01*
Y-195156D01*
X9281Y-195167D01*
Y-195185D01*
X9278Y-195211D01*
X9270Y-195240D01*
X9263Y-195273D01*
X9252Y-195313D01*
X9241Y-195353D01*
X9212Y-195440D01*
X9168Y-195527D01*
X9143Y-195571D01*
X9110Y-195615D01*
X9077Y-195655D01*
X9041Y-195691D01*
X9037Y-195695D01*
X9030Y-195698D01*
X9019Y-195709D01*
X9001Y-195720D01*
X8979Y-195735D01*
X8954Y-195749D01*
X8925Y-195768D01*
X8888Y-195786D01*
X8848Y-195804D01*
X8804Y-195822D01*
X8757Y-195837D01*
X8706Y-195851D01*
X8652Y-195862D01*
X8593Y-195873D01*
X8531Y-195877D01*
X8466Y-195880D01*
X8429D01*
X8404Y-195877D01*
X8375Y-195873D01*
X8338Y-195870D01*
X8298Y-195862D01*
X8258Y-195855D01*
X8164Y-195830D01*
X8069Y-195793D01*
X8022Y-195771D01*
X7975Y-195746D01*
X7931Y-195713D01*
X7891Y-195677D01*
X7887Y-195673D01*
X7880Y-195669D01*
X7873Y-195655D01*
X7858Y-195640D01*
X7840Y-195622D01*
X7822Y-195597D01*
X7803Y-195571D01*
X7782Y-195538D01*
X7745Y-195469D01*
X7709Y-195382D01*
X7694Y-195338D01*
X7687Y-195287D01*
X7680Y-195236D01*
X7676Y-195182D01*
Y-195174D01*
Y-195156D01*
X7680Y-195127D01*
X7683Y-195087D01*
X7691Y-195043D01*
X7705Y-194992D01*
X7720Y-194938D01*
X7741Y-194883D01*
X7745Y-194876D01*
X7752Y-194858D01*
X7767Y-194829D01*
X7789Y-194789D01*
X7818Y-194745D01*
X7854Y-194690D01*
X7898Y-194636D01*
X7949Y-194574D01*
X7956Y-194567D01*
X7975Y-194545D01*
X7993Y-194526D01*
X8011Y-194508D01*
X8033Y-194486D01*
X8062Y-194457D01*
X8091Y-194428D01*
X8127Y-194395D01*
X8164Y-194359D01*
X8207Y-194319D01*
X8255Y-194279D01*
X8306Y-194232D01*
X8364Y-194184D01*
X8422Y-194133D01*
X8426Y-194130D01*
X8433Y-194122D01*
X8448Y-194112D01*
X8466Y-194097D01*
X8488Y-194075D01*
X8513Y-194053D01*
X8572Y-194006D01*
X8633Y-193951D01*
X8692Y-193897D01*
X8743Y-193849D01*
X8764Y-193831D01*
X8783Y-193813D01*
X8786Y-193809D01*
X8797Y-193798D01*
X8812Y-193784D01*
X8830Y-193762D01*
X8848Y-193737D01*
X8870Y-193711D01*
X8914Y-193649D01*
X7672D01*
Y-193351D01*
X9343D01*
Y-193354D01*
D02*
G37*
G36*
X330901Y-237194D02*
X330927D01*
X330956Y-237198D01*
X331025Y-237212D01*
X331101Y-237230D01*
X331182Y-237260D01*
X331262Y-237303D01*
X331302Y-237329D01*
X331338Y-237358D01*
X331342Y-237361D01*
X331345Y-237365D01*
X331356Y-237376D01*
X331367Y-237387D01*
X331385Y-237405D01*
X331400Y-237427D01*
X331440Y-237478D01*
X331480Y-237543D01*
X331516Y-237624D01*
X331549Y-237715D01*
X331571Y-237816D01*
X331262Y-237842D01*
Y-237838D01*
X331258Y-237835D01*
X331254Y-237813D01*
X331243Y-237780D01*
X331229Y-237740D01*
X331214Y-237696D01*
X331192Y-237653D01*
X331167Y-237613D01*
X331141Y-237580D01*
X331134Y-237573D01*
X331120Y-237558D01*
X331094Y-237536D01*
X331058Y-237511D01*
X331011Y-237489D01*
X330960Y-237467D01*
X330898Y-237452D01*
X330832Y-237445D01*
X330807D01*
X330778Y-237449D01*
X330745Y-237456D01*
X330701Y-237467D01*
X330657Y-237482D01*
X330614Y-237500D01*
X330570Y-237529D01*
X330563Y-237532D01*
X330544Y-237547D01*
X330519Y-237573D01*
X330486Y-237609D01*
X330450Y-237653D01*
X330410Y-237704D01*
X330374Y-237769D01*
X330337Y-237842D01*
Y-237846D01*
X330333Y-237853D01*
X330330Y-237864D01*
X330323Y-237878D01*
X330319Y-237900D01*
X330312Y-237926D01*
X330304Y-237955D01*
X330297Y-237991D01*
X330286Y-238031D01*
X330279Y-238075D01*
X330272Y-238122D01*
X330268Y-238173D01*
X330261Y-238231D01*
X330257Y-238290D01*
X330253Y-238355D01*
Y-238421D01*
X330257Y-238417D01*
X330272Y-238395D01*
X330297Y-238366D01*
X330330Y-238330D01*
X330366Y-238286D01*
X330414Y-238246D01*
X330465Y-238206D01*
X330523Y-238170D01*
X330526D01*
X330530Y-238166D01*
X330552Y-238155D01*
X330585Y-238144D01*
X330628Y-238126D01*
X330679Y-238111D01*
X330737Y-238100D01*
X330799Y-238089D01*
X330865Y-238086D01*
X330894D01*
X330916Y-238089D01*
X330945Y-238093D01*
X330974Y-238097D01*
X331011Y-238104D01*
X331047Y-238115D01*
X331131Y-238140D01*
X331174Y-238159D01*
X331218Y-238184D01*
X331262Y-238210D01*
X331309Y-238239D01*
X331353Y-238275D01*
X331393Y-238315D01*
X331396Y-238319D01*
X331404Y-238326D01*
X331415Y-238337D01*
X331425Y-238355D01*
X331444Y-238381D01*
X331462Y-238406D01*
X331480Y-238439D01*
X331502Y-238475D01*
X331524Y-238515D01*
X331542Y-238559D01*
X331560Y-238610D01*
X331578Y-238661D01*
X331589Y-238716D01*
X331600Y-238777D01*
X331607Y-238839D01*
X331611Y-238905D01*
Y-238908D01*
Y-238916D01*
Y-238927D01*
Y-238945D01*
X331607Y-238967D01*
Y-238988D01*
X331596Y-239047D01*
X331586Y-239116D01*
X331567Y-239189D01*
X331542Y-239269D01*
X331505Y-239345D01*
Y-239349D01*
X331502Y-239352D01*
X331495Y-239363D01*
X331487Y-239378D01*
X331466Y-239414D01*
X331433Y-239462D01*
X331393Y-239513D01*
X331345Y-239564D01*
X331287Y-239615D01*
X331225Y-239658D01*
X331222D01*
X331218Y-239662D01*
X331207Y-239669D01*
X331192Y-239673D01*
X331156Y-239691D01*
X331109Y-239709D01*
X331047Y-239731D01*
X330978Y-239746D01*
X330901Y-239760D01*
X330818Y-239764D01*
X330799D01*
X330781Y-239760D01*
X330752D01*
X330719Y-239757D01*
X330683Y-239749D01*
X330639Y-239738D01*
X330595Y-239727D01*
X330544Y-239713D01*
X330494Y-239695D01*
X330443Y-239673D01*
X330388Y-239644D01*
X330337Y-239611D01*
X330286Y-239575D01*
X330235Y-239531D01*
X330188Y-239480D01*
X330184Y-239476D01*
X330177Y-239465D01*
X330166Y-239451D01*
X330151Y-239425D01*
X330130Y-239392D01*
X330111Y-239356D01*
X330089Y-239309D01*
X330068Y-239258D01*
X330042Y-239196D01*
X330020Y-239127D01*
X330002Y-239050D01*
X329984Y-238967D01*
X329966Y-238872D01*
X329955Y-238770D01*
X329948Y-238661D01*
X329944Y-238544D01*
Y-238541D01*
Y-238537D01*
Y-238526D01*
Y-238512D01*
X329948Y-238475D01*
Y-238424D01*
X329951Y-238366D01*
X329959Y-238297D01*
X329966Y-238221D01*
X329977Y-238137D01*
X329991Y-238053D01*
X330010Y-237962D01*
X330031Y-237875D01*
X330057Y-237787D01*
X330089Y-237704D01*
X330126Y-237624D01*
X330166Y-237547D01*
X330213Y-237482D01*
X330217Y-237478D01*
X330224Y-237471D01*
X330239Y-237456D01*
X330257Y-237434D01*
X330279Y-237412D01*
X330308Y-237390D01*
X330344Y-237361D01*
X330381Y-237336D01*
X330424Y-237311D01*
X330472Y-237281D01*
X330526Y-237260D01*
X330581Y-237234D01*
X330643Y-237216D01*
X330708Y-237201D01*
X330778Y-237194D01*
X330850Y-237190D01*
X330879D01*
X330901Y-237194D01*
D02*
G37*
G36*
X327571Y-238657D02*
Y-238661D01*
Y-238675D01*
Y-238694D01*
Y-238719D01*
X327567Y-238752D01*
Y-238788D01*
X327563Y-238832D01*
X327560Y-238876D01*
X327549Y-238974D01*
X327534Y-239076D01*
X327512Y-239174D01*
X327498Y-239222D01*
X327483Y-239265D01*
Y-239269D01*
X327480Y-239276D01*
X327472Y-239287D01*
X327465Y-239301D01*
X327443Y-239342D01*
X327411Y-239392D01*
X327367Y-239451D01*
X327316Y-239509D01*
X327250Y-239571D01*
X327170Y-239626D01*
X327167D01*
X327159Y-239633D01*
X327148Y-239636D01*
X327130Y-239647D01*
X327108Y-239658D01*
X327079Y-239669D01*
X327050Y-239680D01*
X327014Y-239695D01*
X326974Y-239709D01*
X326930Y-239720D01*
X326883Y-239731D01*
X326828Y-239742D01*
X326774Y-239749D01*
X326715Y-239757D01*
X326584Y-239764D01*
X326552D01*
X326526Y-239760D01*
X326497D01*
X326461Y-239757D01*
X326420Y-239753D01*
X326380Y-239749D01*
X326289Y-239735D01*
X326191Y-239713D01*
X326097Y-239684D01*
X326006Y-239644D01*
X326002D01*
X325994Y-239636D01*
X325984Y-239629D01*
X325969Y-239622D01*
X325929Y-239593D01*
X325882Y-239553D01*
X325827Y-239502D01*
X325776Y-239443D01*
X325725Y-239371D01*
X325685Y-239291D01*
Y-239287D01*
X325681Y-239280D01*
X325678Y-239265D01*
X325671Y-239247D01*
X325663Y-239225D01*
X325656Y-239196D01*
X325645Y-239163D01*
X325638Y-239123D01*
X325630Y-239079D01*
X325620Y-239032D01*
X325612Y-238981D01*
X325605Y-238927D01*
X325598Y-238865D01*
X325594Y-238799D01*
X325590Y-238730D01*
Y-238657D01*
Y-237201D01*
X325925D01*
Y-238657D01*
Y-238661D01*
Y-238672D01*
Y-238690D01*
Y-238712D01*
X325929Y-238737D01*
Y-238770D01*
X325933Y-238839D01*
X325940Y-238919D01*
X325951Y-238999D01*
X325965Y-239076D01*
X325973Y-239109D01*
X325984Y-239141D01*
X325987Y-239149D01*
X325994Y-239167D01*
X326013Y-239192D01*
X326035Y-239229D01*
X326060Y-239265D01*
X326097Y-239305D01*
X326140Y-239345D01*
X326191Y-239378D01*
X326198Y-239382D01*
X326217Y-239392D01*
X326249Y-239404D01*
X326293Y-239418D01*
X326344Y-239436D01*
X326410Y-239447D01*
X326479Y-239458D01*
X326555Y-239462D01*
X326591D01*
X326613Y-239458D01*
X326646D01*
X326679Y-239454D01*
X326759Y-239440D01*
X326846Y-239422D01*
X326930Y-239392D01*
X327010Y-239352D01*
X327046Y-239327D01*
X327079Y-239298D01*
X327083Y-239294D01*
X327086Y-239291D01*
X327094Y-239280D01*
X327105Y-239265D01*
X327116Y-239243D01*
X327130Y-239222D01*
X327145Y-239189D01*
X327159Y-239156D01*
X327174Y-239116D01*
X327185Y-239069D01*
X327199Y-239014D01*
X327210Y-238956D01*
X327221Y-238890D01*
X327228Y-238821D01*
X327236Y-238741D01*
Y-238657D01*
Y-237201D01*
X327571D01*
Y-238657D01*
D02*
G37*
G36*
X328896Y-237194D02*
X328925Y-237198D01*
X328961Y-237201D01*
X329001Y-237209D01*
X329041Y-237216D01*
X329136Y-237241D01*
X329230Y-237278D01*
X329278Y-237299D01*
X329325Y-237325D01*
X329369Y-237358D01*
X329409Y-237394D01*
X329413Y-237398D01*
X329420Y-237402D01*
X329427Y-237416D01*
X329442Y-237431D01*
X329460Y-237449D01*
X329478Y-237474D01*
X329496Y-237500D01*
X329518Y-237532D01*
X329555Y-237602D01*
X329591Y-237689D01*
X329605Y-237733D01*
X329613Y-237784D01*
X329620Y-237835D01*
X329624Y-237889D01*
Y-237896D01*
Y-237915D01*
X329620Y-237944D01*
X329616Y-237984D01*
X329609Y-238028D01*
X329594Y-238078D01*
X329580Y-238133D01*
X329558Y-238188D01*
X329555Y-238195D01*
X329547Y-238213D01*
X329533Y-238242D01*
X329511Y-238282D01*
X329482Y-238326D01*
X329445Y-238381D01*
X329402Y-238435D01*
X329351Y-238497D01*
X329343Y-238504D01*
X329325Y-238526D01*
X329307Y-238544D01*
X329289Y-238563D01*
X329267Y-238584D01*
X329238Y-238614D01*
X329209Y-238643D01*
X329172Y-238675D01*
X329136Y-238712D01*
X329092Y-238752D01*
X329045Y-238792D01*
X328994Y-238839D01*
X328936Y-238887D01*
X328877Y-238938D01*
X328874Y-238941D01*
X328867Y-238948D01*
X328852Y-238959D01*
X328834Y-238974D01*
X328812Y-238996D01*
X328786Y-239018D01*
X328728Y-239065D01*
X328666Y-239120D01*
X328608Y-239174D01*
X328557Y-239222D01*
X328535Y-239240D01*
X328517Y-239258D01*
X328513Y-239262D01*
X328502Y-239272D01*
X328488Y-239287D01*
X328470Y-239309D01*
X328451Y-239334D01*
X328430Y-239360D01*
X328386Y-239422D01*
X329627D01*
Y-239720D01*
X327957D01*
Y-239717D01*
Y-239702D01*
Y-239680D01*
X327960Y-239651D01*
X327964Y-239618D01*
X327971Y-239582D01*
X327978Y-239545D01*
X327993Y-239505D01*
Y-239502D01*
X327996Y-239498D01*
X328004Y-239476D01*
X328018Y-239443D01*
X328040Y-239400D01*
X328069Y-239349D01*
X328106Y-239291D01*
X328146Y-239232D01*
X328197Y-239171D01*
Y-239167D01*
X328204Y-239163D01*
X328222Y-239141D01*
X328255Y-239109D01*
X328302Y-239061D01*
X328357Y-239007D01*
X328426Y-238941D01*
X328510Y-238868D01*
X328601Y-238792D01*
X328604Y-238788D01*
X328619Y-238777D01*
X328641Y-238759D01*
X328666Y-238737D01*
X328699Y-238708D01*
X328739Y-238675D01*
X328779Y-238639D01*
X328826Y-238599D01*
X328918Y-238512D01*
X329009Y-238424D01*
X329052Y-238381D01*
X329092Y-238337D01*
X329129Y-238297D01*
X329158Y-238257D01*
Y-238253D01*
X329165Y-238250D01*
X329172Y-238239D01*
X329180Y-238224D01*
X329205Y-238184D01*
X329234Y-238137D01*
X329260Y-238078D01*
X329285Y-238017D01*
X329300Y-237948D01*
X329307Y-237882D01*
Y-237878D01*
Y-237875D01*
X329303Y-237853D01*
X329300Y-237816D01*
X329289Y-237776D01*
X329274Y-237725D01*
X329249Y-237674D01*
X329216Y-237624D01*
X329172Y-237573D01*
X329165Y-237565D01*
X329147Y-237551D01*
X329121Y-237532D01*
X329081Y-237507D01*
X329030Y-237485D01*
X328972Y-237463D01*
X328903Y-237449D01*
X328826Y-237445D01*
X328805D01*
X328790Y-237449D01*
X328746Y-237452D01*
X328695Y-237463D01*
X328641Y-237478D01*
X328579Y-237503D01*
X328521Y-237536D01*
X328466Y-237580D01*
X328459Y-237587D01*
X328444Y-237605D01*
X328422Y-237634D01*
X328401Y-237678D01*
X328375Y-237729D01*
X328353Y-237795D01*
X328339Y-237867D01*
X328331Y-237951D01*
X328015Y-237918D01*
Y-237915D01*
X328018Y-237904D01*
Y-237886D01*
X328022Y-237860D01*
X328029Y-237831D01*
X328037Y-237798D01*
X328047Y-237758D01*
X328058Y-237718D01*
X328087Y-237631D01*
X328131Y-237543D01*
X328157Y-237500D01*
X328189Y-237456D01*
X328222Y-237416D01*
X328259Y-237380D01*
X328262Y-237376D01*
X328270Y-237372D01*
X328280Y-237361D01*
X328299Y-237351D01*
X328321Y-237336D01*
X328346Y-237321D01*
X328375Y-237303D01*
X328412Y-237285D01*
X328451Y-237267D01*
X328495Y-237249D01*
X328542Y-237234D01*
X328593Y-237220D01*
X328648Y-237209D01*
X328706Y-237198D01*
X328768Y-237194D01*
X328834Y-237190D01*
X328870D01*
X328896Y-237194D01*
D02*
G37*
G36*
X34277Y-2710D02*
X33967D01*
Y-740D01*
X33964Y-744D01*
X33945Y-759D01*
X33924Y-780D01*
X33887Y-806D01*
X33847Y-839D01*
X33796Y-875D01*
X33738Y-915D01*
X33672Y-955D01*
X33669D01*
X33665Y-959D01*
X33643Y-973D01*
X33607Y-991D01*
X33563Y-1013D01*
X33512Y-1039D01*
X33458Y-1064D01*
X33403Y-1090D01*
X33348Y-1112D01*
Y-813D01*
X33352D01*
X33359Y-806D01*
X33374Y-802D01*
X33392Y-791D01*
X33414Y-780D01*
X33439Y-766D01*
X33501Y-729D01*
X33574Y-689D01*
X33647Y-638D01*
X33723Y-580D01*
X33800Y-518D01*
X33803Y-515D01*
X33807Y-511D01*
X33818Y-500D01*
X33832Y-489D01*
X33865Y-453D01*
X33909Y-409D01*
X33953Y-358D01*
X34000Y-300D01*
X34040Y-242D01*
X34076Y-180D01*
X34277D01*
Y-2710D01*
D02*
G37*
G36*
X32318D02*
X32009D01*
Y-740D01*
X32005Y-744D01*
X31987Y-759D01*
X31965Y-780D01*
X31929Y-806D01*
X31889Y-839D01*
X31838Y-875D01*
X31780Y-915D01*
X31714Y-955D01*
X31710D01*
X31707Y-959D01*
X31685Y-973D01*
X31648Y-991D01*
X31605Y-1013D01*
X31554Y-1039D01*
X31499Y-1064D01*
X31445Y-1090D01*
X31390Y-1112D01*
Y-813D01*
X31394D01*
X31401Y-806D01*
X31416Y-802D01*
X31434Y-791D01*
X31456Y-780D01*
X31481Y-766D01*
X31543Y-729D01*
X31616Y-689D01*
X31689Y-638D01*
X31765Y-580D01*
X31841Y-518D01*
X31845Y-515D01*
X31849Y-511D01*
X31860Y-500D01*
X31874Y-489D01*
X31907Y-453D01*
X31951Y-409D01*
X31994Y-358D01*
X32042Y-300D01*
X32082Y-242D01*
X32118Y-180D01*
X32318D01*
Y-2710D01*
D02*
G37*
G36*
X29774Y-194D02*
X29847Y-198D01*
X29919Y-205D01*
X29992Y-216D01*
X30054Y-227D01*
X30058D01*
X30065Y-231D01*
X30076D01*
X30091Y-238D01*
X30131Y-249D01*
X30182Y-267D01*
X30240Y-293D01*
X30302Y-325D01*
X30364Y-362D01*
X30422Y-409D01*
X30426Y-413D01*
X30429Y-416D01*
X30440Y-427D01*
X30455Y-438D01*
X30491Y-475D01*
X30535Y-526D01*
X30582Y-587D01*
X30633Y-660D01*
X30680Y-744D01*
X30720Y-839D01*
Y-842D01*
X30724Y-850D01*
X30731Y-864D01*
X30735Y-886D01*
X30746Y-912D01*
X30753Y-941D01*
X30760Y-973D01*
X30771Y-1013D01*
X30782Y-1053D01*
X30790Y-1101D01*
X30808Y-1203D01*
X30819Y-1316D01*
X30822Y-1439D01*
Y-1443D01*
Y-1450D01*
Y-1468D01*
Y-1487D01*
X30819Y-1512D01*
Y-1541D01*
X30815Y-1610D01*
X30804Y-1690D01*
X30793Y-1774D01*
X30775Y-1861D01*
X30753Y-1949D01*
Y-1953D01*
X30749Y-1960D01*
X30746Y-1971D01*
X30742Y-1985D01*
X30728Y-2025D01*
X30706Y-2076D01*
X30684Y-2135D01*
X30655Y-2193D01*
X30618Y-2255D01*
X30582Y-2313D01*
X30578Y-2320D01*
X30564Y-2338D01*
X30542Y-2364D01*
X30513Y-2397D01*
X30480Y-2433D01*
X30440Y-2469D01*
X30400Y-2509D01*
X30353Y-2542D01*
X30345Y-2546D01*
X30331Y-2557D01*
X30305Y-2571D01*
X30269Y-2589D01*
X30225Y-2611D01*
X30174Y-2630D01*
X30116Y-2651D01*
X30051Y-2670D01*
X30043D01*
X30032Y-2673D01*
X30021Y-2677D01*
X29985Y-2681D01*
X29934Y-2688D01*
X29876Y-2695D01*
X29807Y-2702D01*
X29730Y-2706D01*
X29647Y-2710D01*
X28740D01*
Y-191D01*
X29708D01*
X29774Y-194D01*
D02*
G37*
G36*
X32318Y4224D02*
X32009D01*
Y6193D01*
X32005Y6189D01*
X31987Y6175D01*
X31965Y6153D01*
X31929Y6128D01*
X31889Y6095D01*
X31838Y6058D01*
X31780Y6018D01*
X31714Y5978D01*
X31710D01*
X31707Y5975D01*
X31685Y5960D01*
X31648Y5942D01*
X31605Y5920D01*
X31554Y5895D01*
X31499Y5869D01*
X31445Y5844D01*
X31390Y5822D01*
Y6120D01*
X31394D01*
X31401Y6128D01*
X31416Y6131D01*
X31434Y6142D01*
X31456Y6153D01*
X31481Y6168D01*
X31543Y6204D01*
X31616Y6244D01*
X31689Y6295D01*
X31765Y6353D01*
X31841Y6415D01*
X31845Y6419D01*
X31849Y6422D01*
X31860Y6433D01*
X31874Y6444D01*
X31907Y6481D01*
X31951Y6524D01*
X31994Y6575D01*
X32042Y6634D01*
X32082Y6692D01*
X32118Y6754D01*
X32318D01*
Y4224D01*
D02*
G37*
G36*
X29774Y6739D02*
X29847Y6735D01*
X29919Y6728D01*
X29992Y6717D01*
X30054Y6706D01*
X30058D01*
X30065Y6703D01*
X30076D01*
X30091Y6695D01*
X30131Y6684D01*
X30182Y6666D01*
X30240Y6641D01*
X30302Y6608D01*
X30364Y6572D01*
X30422Y6524D01*
X30426Y6521D01*
X30429Y6517D01*
X30440Y6506D01*
X30455Y6495D01*
X30491Y6459D01*
X30535Y6408D01*
X30582Y6346D01*
X30633Y6273D01*
X30680Y6189D01*
X30720Y6095D01*
Y6091D01*
X30724Y6084D01*
X30731Y6069D01*
X30735Y6047D01*
X30746Y6022D01*
X30753Y5993D01*
X30760Y5960D01*
X30771Y5920D01*
X30782Y5880D01*
X30790Y5833D01*
X30808Y5731D01*
X30819Y5618D01*
X30822Y5494D01*
Y5491D01*
Y5483D01*
Y5465D01*
Y5447D01*
X30819Y5421D01*
Y5392D01*
X30815Y5323D01*
X30804Y5243D01*
X30793Y5159D01*
X30775Y5072D01*
X30753Y4985D01*
Y4981D01*
X30749Y4974D01*
X30746Y4963D01*
X30742Y4948D01*
X30728Y4908D01*
X30706Y4857D01*
X30684Y4799D01*
X30655Y4741D01*
X30618Y4679D01*
X30582Y4621D01*
X30578Y4613D01*
X30564Y4595D01*
X30542Y4570D01*
X30513Y4537D01*
X30480Y4501D01*
X30440Y4464D01*
X30400Y4424D01*
X30353Y4391D01*
X30345Y4388D01*
X30331Y4377D01*
X30305Y4362D01*
X30269Y4344D01*
X30225Y4322D01*
X30174Y4304D01*
X30116Y4282D01*
X30051Y4264D01*
X30043D01*
X30032Y4260D01*
X30021Y4257D01*
X29985Y4253D01*
X29934Y4246D01*
X29876Y4238D01*
X29807Y4231D01*
X29730Y4228D01*
X29647Y4224D01*
X28740D01*
Y6743D01*
X29708D01*
X29774Y6739D01*
D02*
G37*
G36*
X34007Y6750D02*
X34055Y6743D01*
X34109Y6732D01*
X34167Y6717D01*
X34229Y6699D01*
X34288Y6670D01*
X34291D01*
X34295Y6666D01*
X34313Y6655D01*
X34342Y6637D01*
X34378Y6612D01*
X34419Y6575D01*
X34462Y6535D01*
X34502Y6488D01*
X34542Y6433D01*
X34546Y6426D01*
X34560Y6408D01*
X34575Y6375D01*
X34601Y6328D01*
X34622Y6273D01*
X34651Y6211D01*
X34677Y6138D01*
X34699Y6058D01*
Y6055D01*
X34703Y6047D01*
X34706Y6036D01*
X34710Y6018D01*
X34713Y5996D01*
X34717Y5971D01*
X34724Y5938D01*
X34728Y5902D01*
X34735Y5862D01*
X34739Y5818D01*
X34743Y5767D01*
X34750Y5716D01*
X34753Y5658D01*
Y5600D01*
X34757Y5534D01*
Y5465D01*
Y5461D01*
Y5447D01*
Y5421D01*
Y5392D01*
X34753Y5352D01*
Y5308D01*
X34750Y5261D01*
X34746Y5210D01*
X34735Y5094D01*
X34717Y4974D01*
X34695Y4857D01*
X34681Y4803D01*
X34662Y4748D01*
Y4744D01*
X34659Y4737D01*
X34651Y4722D01*
X34644Y4704D01*
X34637Y4679D01*
X34622Y4653D01*
X34593Y4592D01*
X34557Y4526D01*
X34510Y4453D01*
X34455Y4388D01*
X34389Y4326D01*
X34386D01*
X34382Y4318D01*
X34371Y4311D01*
X34357Y4304D01*
X34339Y4293D01*
X34320Y4278D01*
X34266Y4253D01*
X34200Y4228D01*
X34124Y4202D01*
X34033Y4187D01*
X33934Y4180D01*
X33898D01*
X33873Y4184D01*
X33843Y4187D01*
X33807Y4195D01*
X33767Y4202D01*
X33723Y4213D01*
X33680Y4228D01*
X33632Y4242D01*
X33585Y4264D01*
X33538Y4289D01*
X33490Y4318D01*
X33443Y4355D01*
X33399Y4395D01*
X33359Y4439D01*
X33356Y4442D01*
X33348Y4453D01*
X33338Y4471D01*
X33319Y4501D01*
X33301Y4533D01*
X33283Y4577D01*
X33257Y4628D01*
X33236Y4686D01*
X33214Y4752D01*
X33192Y4828D01*
X33170Y4912D01*
X33152Y5006D01*
X33134Y5108D01*
X33123Y5218D01*
X33115Y5338D01*
X33112Y5465D01*
Y5469D01*
Y5483D01*
Y5509D01*
Y5538D01*
X33115Y5578D01*
Y5622D01*
X33119Y5669D01*
X33123Y5723D01*
X33134Y5836D01*
X33152Y5957D01*
X33174Y6077D01*
X33188Y6131D01*
X33203Y6186D01*
Y6189D01*
X33206Y6197D01*
X33214Y6211D01*
X33221Y6230D01*
X33228Y6255D01*
X33243Y6280D01*
X33272Y6342D01*
X33308Y6408D01*
X33356Y6477D01*
X33410Y6546D01*
X33476Y6604D01*
X33479D01*
X33483Y6612D01*
X33494Y6619D01*
X33509Y6626D01*
X33527Y6641D01*
X33549Y6652D01*
X33603Y6681D01*
X33669Y6706D01*
X33745Y6732D01*
X33836Y6746D01*
X33934Y6754D01*
X33967D01*
X34007Y6750D01*
D02*
G37*
G36*
X31987Y13640D02*
X32005D01*
X32031Y13636D01*
X32093Y13625D01*
X32162Y13611D01*
X32238Y13585D01*
X32315Y13552D01*
X32391Y13509D01*
X32395D01*
X32398Y13501D01*
X32409Y13494D01*
X32424Y13483D01*
X32460Y13454D01*
X32508Y13414D01*
X32555Y13360D01*
X32610Y13294D01*
X32657Y13217D01*
X32700Y13130D01*
Y13126D01*
X32704Y13119D01*
X32711Y13105D01*
X32719Y13086D01*
X32726Y13061D01*
X32737Y13028D01*
X32744Y12992D01*
X32755Y12952D01*
X32766Y12904D01*
X32777Y12850D01*
X32784Y12792D01*
X32792Y12730D01*
X32799Y12661D01*
X32806Y12588D01*
X32810Y12508D01*
Y12424D01*
Y12420D01*
Y12402D01*
Y12377D01*
Y12344D01*
X32806Y12304D01*
Y12257D01*
X32802Y12202D01*
X32795Y12147D01*
X32784Y12024D01*
X32766Y11892D01*
X32741Y11769D01*
X32722Y11707D01*
X32704Y11652D01*
Y11649D01*
X32700Y11641D01*
X32693Y11627D01*
X32686Y11605D01*
X32675Y11583D01*
X32660Y11554D01*
X32624Y11492D01*
X32580Y11423D01*
X32529Y11350D01*
X32464Y11281D01*
X32391Y11219D01*
X32387D01*
X32380Y11212D01*
X32369Y11205D01*
X32355Y11197D01*
X32333Y11186D01*
X32311Y11172D01*
X32282Y11157D01*
X32253Y11146D01*
X32184Y11117D01*
X32100Y11092D01*
X32009Y11077D01*
X31907Y11070D01*
X31878D01*
X31860Y11073D01*
X31834D01*
X31805Y11077D01*
X31736Y11092D01*
X31659Y11110D01*
X31579Y11139D01*
X31499Y11179D01*
X31459Y11205D01*
X31423Y11234D01*
X31419Y11237D01*
X31416Y11241D01*
X31405Y11252D01*
X31394Y11263D01*
X31379Y11281D01*
X31361Y11303D01*
X31325Y11354D01*
X31288Y11419D01*
X31252Y11499D01*
X31223Y11590D01*
X31201Y11696D01*
X31499Y11722D01*
Y11718D01*
X31503Y11710D01*
Y11703D01*
X31507Y11689D01*
X31517Y11649D01*
X31532Y11605D01*
X31550Y11554D01*
X31576Y11503D01*
X31605Y11456D01*
X31641Y11416D01*
X31645Y11412D01*
X31659Y11401D01*
X31685Y11387D01*
X31714Y11372D01*
X31754Y11354D01*
X31801Y11339D01*
X31856Y11328D01*
X31914Y11325D01*
X31940D01*
X31965Y11328D01*
X31998Y11332D01*
X32038Y11339D01*
X32078Y11350D01*
X32122Y11365D01*
X32162Y11387D01*
X32165Y11390D01*
X32180Y11398D01*
X32202Y11412D01*
X32224Y11434D01*
X32253Y11459D01*
X32282Y11489D01*
X32311Y11521D01*
X32340Y11561D01*
X32344Y11565D01*
X32351Y11583D01*
X32366Y11609D01*
X32380Y11641D01*
X32398Y11685D01*
X32417Y11736D01*
X32435Y11794D01*
X32453Y11860D01*
Y11863D01*
X32457Y11867D01*
Y11878D01*
X32460Y11892D01*
X32467Y11929D01*
X32478Y11976D01*
X32486Y12034D01*
X32493Y12096D01*
X32497Y12166D01*
X32500Y12238D01*
Y12242D01*
Y12253D01*
Y12271D01*
Y12300D01*
X32497Y12293D01*
X32482Y12275D01*
X32460Y12249D01*
X32435Y12213D01*
X32398Y12177D01*
X32355Y12136D01*
X32304Y12096D01*
X32245Y12060D01*
X32238Y12056D01*
X32216Y12045D01*
X32184Y12031D01*
X32144Y12016D01*
X32089Y11998D01*
X32031Y11983D01*
X31965Y11973D01*
X31896Y11969D01*
X31867D01*
X31845Y11973D01*
X31816Y11976D01*
X31787Y11980D01*
X31750Y11987D01*
X31714Y11998D01*
X31630Y12024D01*
X31587Y12042D01*
X31543Y12064D01*
X31496Y12089D01*
X31452Y12122D01*
X31408Y12155D01*
X31368Y12195D01*
X31365Y12198D01*
X31357Y12206D01*
X31350Y12217D01*
X31335Y12235D01*
X31317Y12260D01*
X31299Y12286D01*
X31281Y12318D01*
X31263Y12355D01*
X31241Y12395D01*
X31223Y12438D01*
X31204Y12489D01*
X31186Y12540D01*
X31172Y12599D01*
X31164Y12661D01*
X31157Y12722D01*
X31154Y12792D01*
Y12795D01*
Y12810D01*
Y12828D01*
X31157Y12854D01*
X31161Y12886D01*
X31164Y12926D01*
X31172Y12966D01*
X31183Y13014D01*
X31208Y13108D01*
X31226Y13159D01*
X31248Y13214D01*
X31274Y13265D01*
X31306Y13312D01*
X31339Y13363D01*
X31379Y13407D01*
X31383Y13410D01*
X31390Y13418D01*
X31401Y13429D01*
X31419Y13443D01*
X31441Y13461D01*
X31470Y13483D01*
X31499Y13501D01*
X31536Y13527D01*
X31572Y13549D01*
X31616Y13567D01*
X31714Y13607D01*
X31765Y13622D01*
X31823Y13633D01*
X31881Y13640D01*
X31943Y13643D01*
X31969D01*
X31987Y13640D01*
D02*
G37*
G36*
X29774Y13629D02*
X29847Y13625D01*
X29919Y13618D01*
X29992Y13607D01*
X30054Y13596D01*
X30058D01*
X30065Y13592D01*
X30076D01*
X30091Y13585D01*
X30131Y13574D01*
X30182Y13556D01*
X30240Y13531D01*
X30302Y13498D01*
X30364Y13461D01*
X30422Y13414D01*
X30426Y13410D01*
X30429Y13407D01*
X30440Y13396D01*
X30455Y13385D01*
X30491Y13349D01*
X30535Y13298D01*
X30582Y13236D01*
X30633Y13163D01*
X30680Y13079D01*
X30720Y12984D01*
Y12981D01*
X30724Y12974D01*
X30731Y12959D01*
X30735Y12937D01*
X30746Y12912D01*
X30753Y12883D01*
X30760Y12850D01*
X30771Y12810D01*
X30782Y12770D01*
X30790Y12722D01*
X30808Y12620D01*
X30819Y12508D01*
X30822Y12384D01*
Y12380D01*
Y12373D01*
Y12355D01*
Y12337D01*
X30819Y12311D01*
Y12282D01*
X30815Y12213D01*
X30804Y12133D01*
X30793Y12049D01*
X30775Y11962D01*
X30753Y11874D01*
Y11871D01*
X30749Y11863D01*
X30746Y11852D01*
X30742Y11838D01*
X30728Y11798D01*
X30706Y11747D01*
X30684Y11689D01*
X30655Y11631D01*
X30618Y11569D01*
X30582Y11510D01*
X30578Y11503D01*
X30564Y11485D01*
X30542Y11459D01*
X30513Y11427D01*
X30480Y11390D01*
X30440Y11354D01*
X30400Y11314D01*
X30353Y11281D01*
X30345Y11277D01*
X30331Y11266D01*
X30305Y11252D01*
X30269Y11234D01*
X30225Y11212D01*
X30174Y11194D01*
X30116Y11172D01*
X30051Y11154D01*
X30043D01*
X30032Y11150D01*
X30021Y11146D01*
X29985Y11143D01*
X29934Y11135D01*
X29876Y11128D01*
X29807Y11121D01*
X29730Y11117D01*
X29647Y11114D01*
X28740D01*
Y13633D01*
X29708D01*
X29774Y13629D01*
D02*
G37*
G36*
X32020Y20529D02*
X32067Y20522D01*
X32125Y20511D01*
X32191Y20493D01*
X32256Y20471D01*
X32322Y20442D01*
X32326D01*
X32329Y20438D01*
X32351Y20428D01*
X32384Y20406D01*
X32420Y20380D01*
X32464Y20344D01*
X32508Y20304D01*
X32551Y20256D01*
X32588Y20202D01*
X32591Y20195D01*
X32602Y20176D01*
X32617Y20144D01*
X32635Y20104D01*
X32653Y20056D01*
X32668Y20002D01*
X32679Y19940D01*
X32682Y19878D01*
Y19871D01*
Y19849D01*
X32679Y19820D01*
X32671Y19780D01*
X32660Y19732D01*
X32642Y19681D01*
X32620Y19630D01*
X32591Y19579D01*
X32588Y19572D01*
X32577Y19558D01*
X32555Y19532D01*
X32526Y19503D01*
X32489Y19470D01*
X32446Y19434D01*
X32395Y19401D01*
X32333Y19368D01*
X32337D01*
X32344Y19365D01*
X32355Y19361D01*
X32369Y19357D01*
X32409Y19343D01*
X32460Y19321D01*
X32519Y19292D01*
X32577Y19255D01*
X32631Y19208D01*
X32682Y19154D01*
X32686Y19146D01*
X32700Y19125D01*
X32722Y19088D01*
X32744Y19041D01*
X32766Y18982D01*
X32788Y18913D01*
X32802Y18833D01*
X32806Y18746D01*
Y18742D01*
Y18731D01*
Y18713D01*
X32802Y18691D01*
X32799Y18662D01*
X32792Y18629D01*
X32784Y18593D01*
X32777Y18553D01*
X32748Y18466D01*
X32726Y18418D01*
X32704Y18375D01*
X32675Y18327D01*
X32642Y18280D01*
X32606Y18233D01*
X32562Y18189D01*
X32559Y18185D01*
X32551Y18178D01*
X32537Y18167D01*
X32519Y18153D01*
X32497Y18134D01*
X32467Y18116D01*
X32435Y18094D01*
X32395Y18076D01*
X32355Y18054D01*
X32307Y18033D01*
X32260Y18014D01*
X32205Y17996D01*
X32147Y17981D01*
X32085Y17971D01*
X32023Y17963D01*
X31954Y17960D01*
X31921D01*
X31900Y17963D01*
X31871Y17967D01*
X31838Y17971D01*
X31801Y17978D01*
X31761Y17985D01*
X31674Y18007D01*
X31583Y18043D01*
X31536Y18065D01*
X31492Y18091D01*
X31448Y18124D01*
X31405Y18156D01*
X31401Y18160D01*
X31394Y18167D01*
X31383Y18178D01*
X31372Y18193D01*
X31354Y18211D01*
X31335Y18236D01*
X31314Y18262D01*
X31292Y18295D01*
X31270Y18331D01*
X31248Y18367D01*
X31208Y18455D01*
X31175Y18557D01*
X31164Y18611D01*
X31157Y18669D01*
X31466Y18710D01*
Y18706D01*
X31470Y18699D01*
X31474Y18684D01*
X31477Y18666D01*
X31481Y18644D01*
X31488Y18619D01*
X31507Y18564D01*
X31532Y18498D01*
X31565Y18437D01*
X31601Y18378D01*
X31645Y18327D01*
X31652Y18324D01*
X31667Y18309D01*
X31696Y18291D01*
X31732Y18273D01*
X31776Y18251D01*
X31830Y18233D01*
X31892Y18218D01*
X31958Y18214D01*
X31980D01*
X31994Y18218D01*
X32034Y18222D01*
X32085Y18233D01*
X32144Y18251D01*
X32205Y18276D01*
X32267Y18313D01*
X32326Y18364D01*
X32333Y18371D01*
X32351Y18393D01*
X32373Y18426D01*
X32402Y18469D01*
X32431Y18524D01*
X32453Y18586D01*
X32471Y18658D01*
X32478Y18739D01*
Y18742D01*
Y18749D01*
Y18760D01*
X32475Y18775D01*
X32471Y18815D01*
X32460Y18862D01*
X32446Y18921D01*
X32420Y18979D01*
X32384Y19037D01*
X32337Y19092D01*
X32329Y19099D01*
X32311Y19114D01*
X32282Y19135D01*
X32242Y19161D01*
X32191Y19186D01*
X32129Y19208D01*
X32060Y19223D01*
X31983Y19230D01*
X31951D01*
X31925Y19226D01*
X31892Y19223D01*
X31856Y19216D01*
X31812Y19208D01*
X31765Y19197D01*
X31801Y19470D01*
X31820D01*
X31834Y19467D01*
X31881D01*
X31921Y19474D01*
X31969Y19481D01*
X32023Y19492D01*
X32085Y19510D01*
X32144Y19536D01*
X32205Y19568D01*
X32209D01*
X32213Y19572D01*
X32231Y19587D01*
X32256Y19612D01*
X32285Y19645D01*
X32315Y19692D01*
X32340Y19747D01*
X32358Y19809D01*
X32366Y19845D01*
Y19885D01*
Y19889D01*
Y19893D01*
Y19914D01*
X32358Y19943D01*
X32351Y19984D01*
X32337Y20027D01*
X32318Y20075D01*
X32289Y20122D01*
X32249Y20166D01*
X32245Y20169D01*
X32227Y20184D01*
X32202Y20202D01*
X32169Y20224D01*
X32125Y20242D01*
X32074Y20260D01*
X32016Y20275D01*
X31951Y20278D01*
X31921D01*
X31889Y20271D01*
X31845Y20264D01*
X31798Y20249D01*
X31750Y20231D01*
X31699Y20202D01*
X31652Y20166D01*
X31648Y20162D01*
X31634Y20144D01*
X31612Y20118D01*
X31587Y20082D01*
X31561Y20034D01*
X31536Y19976D01*
X31514Y19907D01*
X31499Y19827D01*
X31190Y19882D01*
Y19885D01*
X31194Y19896D01*
X31197Y19911D01*
X31201Y19933D01*
X31208Y19958D01*
X31219Y19987D01*
X31241Y20056D01*
X31277Y20136D01*
X31321Y20216D01*
X31376Y20293D01*
X31445Y20362D01*
X31448Y20366D01*
X31456Y20369D01*
X31466Y20377D01*
X31481Y20388D01*
X31499Y20402D01*
X31525Y20417D01*
X31550Y20431D01*
X31583Y20449D01*
X31656Y20479D01*
X31740Y20508D01*
X31838Y20526D01*
X31889Y20533D01*
X31980D01*
X32020Y20529D01*
D02*
G37*
G36*
X29774Y20519D02*
X29847Y20515D01*
X29919Y20508D01*
X29992Y20497D01*
X30054Y20486D01*
X30058D01*
X30065Y20482D01*
X30076D01*
X30091Y20475D01*
X30131Y20464D01*
X30182Y20446D01*
X30240Y20420D01*
X30302Y20388D01*
X30364Y20351D01*
X30422Y20304D01*
X30426Y20300D01*
X30429Y20297D01*
X30440Y20286D01*
X30455Y20275D01*
X30491Y20238D01*
X30535Y20187D01*
X30582Y20125D01*
X30633Y20053D01*
X30680Y19969D01*
X30720Y19874D01*
Y19871D01*
X30724Y19863D01*
X30731Y19849D01*
X30735Y19827D01*
X30746Y19802D01*
X30753Y19772D01*
X30760Y19740D01*
X30771Y19700D01*
X30782Y19659D01*
X30790Y19612D01*
X30808Y19510D01*
X30819Y19398D01*
X30822Y19274D01*
Y19270D01*
Y19263D01*
Y19245D01*
Y19226D01*
X30819Y19201D01*
Y19172D01*
X30815Y19103D01*
X30804Y19023D01*
X30793Y18939D01*
X30775Y18851D01*
X30753Y18764D01*
Y18760D01*
X30749Y18753D01*
X30746Y18742D01*
X30742Y18728D01*
X30728Y18688D01*
X30706Y18637D01*
X30684Y18578D01*
X30655Y18520D01*
X30618Y18458D01*
X30582Y18400D01*
X30578Y18393D01*
X30564Y18375D01*
X30542Y18349D01*
X30513Y18316D01*
X30480Y18280D01*
X30440Y18244D01*
X30400Y18204D01*
X30353Y18171D01*
X30345Y18167D01*
X30331Y18156D01*
X30305Y18142D01*
X30269Y18124D01*
X30225Y18102D01*
X30174Y18083D01*
X30116Y18062D01*
X30051Y18043D01*
X30043D01*
X30032Y18040D01*
X30021Y18036D01*
X29985Y18033D01*
X29934Y18025D01*
X29876Y18018D01*
X29807Y18011D01*
X29730Y18007D01*
X29647Y18003D01*
X28740D01*
Y20522D01*
X29708D01*
X29774Y20519D01*
D02*
G37*
G36*
X149812Y-101583D02*
X149848D01*
X149885Y-101587D01*
X149932Y-101591D01*
X149979Y-101598D01*
X150085Y-101616D01*
X150201Y-101642D01*
X150318Y-101678D01*
X150431Y-101729D01*
X150434Y-101733D01*
X150445Y-101736D01*
X150460Y-101744D01*
X150478Y-101758D01*
X150504Y-101773D01*
X150533Y-101791D01*
X150598Y-101838D01*
X150671Y-101900D01*
X150744Y-101973D01*
X150817Y-102057D01*
X150879Y-102155D01*
X150882Y-102159D01*
X150886Y-102170D01*
X150893Y-102184D01*
X150904Y-102202D01*
X150915Y-102231D01*
X150926Y-102260D01*
X150940Y-102297D01*
X150955Y-102337D01*
X150970Y-102381D01*
X150984Y-102428D01*
X151006Y-102530D01*
X151024Y-102646D01*
X151031Y-102766D01*
Y-102803D01*
X151028Y-102828D01*
X151024Y-102861D01*
X151021Y-102901D01*
X151017Y-102941D01*
X151006Y-102989D01*
X150984Y-103087D01*
X150951Y-103196D01*
X150929Y-103251D01*
X150904Y-103302D01*
X150871Y-103352D01*
X150838Y-103403D01*
X150835Y-103407D01*
X150831Y-103414D01*
X150820Y-103429D01*
X150802Y-103447D01*
X150784Y-103465D01*
X150758Y-103491D01*
X150729Y-103516D01*
X150700Y-103545D01*
X150664Y-103575D01*
X150620Y-103604D01*
X150576Y-103636D01*
X150529Y-103665D01*
X150475Y-103691D01*
X150420Y-103720D01*
X150362Y-103742D01*
X150296Y-103764D01*
X150220Y-103436D01*
X150223D01*
X150231Y-103433D01*
X150245Y-103425D01*
X150263Y-103418D01*
X150285Y-103411D01*
X150314Y-103400D01*
X150373Y-103371D01*
X150438Y-103334D01*
X150504Y-103291D01*
X150566Y-103236D01*
X150620Y-103178D01*
X150627Y-103171D01*
X150642Y-103149D01*
X150660Y-103112D01*
X150686Y-103065D01*
X150707Y-103003D01*
X150729Y-102934D01*
X150744Y-102850D01*
X150748Y-102759D01*
Y-102730D01*
X150744Y-102712D01*
Y-102686D01*
X150740Y-102657D01*
X150729Y-102588D01*
X150715Y-102512D01*
X150689Y-102432D01*
X150653Y-102348D01*
X150605Y-102271D01*
Y-102268D01*
X150598Y-102264D01*
X150580Y-102239D01*
X150551Y-102206D01*
X150507Y-102166D01*
X150453Y-102119D01*
X150391Y-102075D01*
X150314Y-102035D01*
X150231Y-101998D01*
X150227D01*
X150220Y-101995D01*
X150209Y-101991D01*
X150190Y-101988D01*
X150169Y-101980D01*
X150143Y-101973D01*
X150081Y-101962D01*
X150008Y-101947D01*
X149928Y-101933D01*
X149841Y-101926D01*
X149747Y-101922D01*
X149743D01*
X149732D01*
X149714D01*
X149692D01*
X149666Y-101926D01*
X149634D01*
X149597Y-101929D01*
X149557Y-101933D01*
X149470Y-101944D01*
X149375Y-101962D01*
X149281Y-101984D01*
X149186Y-102013D01*
X149182D01*
X149175Y-102017D01*
X149164Y-102024D01*
X149146Y-102031D01*
X149102Y-102053D01*
X149051Y-102086D01*
X148993Y-102126D01*
X148931Y-102177D01*
X148877Y-102235D01*
X148826Y-102304D01*
Y-102308D01*
X148822Y-102315D01*
X148815Y-102326D01*
X148807Y-102341D01*
X148800Y-102359D01*
X148789Y-102381D01*
X148767Y-102432D01*
X148746Y-102497D01*
X148727Y-102570D01*
X148713Y-102650D01*
X148709Y-102734D01*
Y-102759D01*
X148713Y-102781D01*
Y-102806D01*
X148716Y-102832D01*
X148731Y-102898D01*
X148749Y-102974D01*
X148778Y-103050D01*
X148818Y-103130D01*
X148840Y-103171D01*
X148869Y-103207D01*
X148873Y-103210D01*
X148877Y-103214D01*
X148887Y-103225D01*
X148898Y-103240D01*
X148916Y-103254D01*
X148938Y-103272D01*
X148960Y-103294D01*
X148989Y-103312D01*
X149022Y-103334D01*
X149058Y-103360D01*
X149095Y-103382D01*
X149139Y-103403D01*
X149186Y-103422D01*
X149237Y-103440D01*
X149292Y-103458D01*
X149350Y-103473D01*
X149266Y-103807D01*
X149262D01*
X149248Y-103804D01*
X149226Y-103797D01*
X149197Y-103786D01*
X149164Y-103775D01*
X149124Y-103760D01*
X149080Y-103742D01*
X149033Y-103720D01*
X148931Y-103669D01*
X148829Y-103604D01*
X148778Y-103564D01*
X148727Y-103524D01*
X148684Y-103480D01*
X148640Y-103429D01*
X148636Y-103425D01*
X148629Y-103418D01*
X148622Y-103400D01*
X148607Y-103382D01*
X148589Y-103352D01*
X148571Y-103323D01*
X148553Y-103283D01*
X148534Y-103243D01*
X148512Y-103196D01*
X148494Y-103145D01*
X148476Y-103090D01*
X148458Y-103032D01*
X148443Y-102970D01*
X148436Y-102905D01*
X148429Y-102836D01*
X148425Y-102763D01*
Y-102723D01*
X148429Y-102694D01*
Y-102661D01*
X148432Y-102621D01*
X148440Y-102577D01*
X148447Y-102526D01*
X148465Y-102421D01*
X148494Y-102311D01*
X148534Y-102202D01*
X148560Y-102151D01*
X148589Y-102100D01*
X148593Y-102097D01*
X148596Y-102089D01*
X148607Y-102075D01*
X148622Y-102060D01*
X148636Y-102038D01*
X148658Y-102013D01*
X148684Y-101984D01*
X148713Y-101955D01*
X148746Y-101926D01*
X148778Y-101893D01*
X148862Y-101827D01*
X148960Y-101765D01*
X149069Y-101711D01*
X149073D01*
X149084Y-101704D01*
X149102Y-101700D01*
X149124Y-101689D01*
X149153Y-101682D01*
X149189Y-101671D01*
X149230Y-101656D01*
X149273Y-101645D01*
X149321Y-101634D01*
X149375Y-101620D01*
X149488Y-101602D01*
X149615Y-101587D01*
X149747Y-101580D01*
X149750D01*
X149765D01*
X149786D01*
X149812Y-101583D01*
D02*
G37*
G36*
X149233Y-104091D02*
X149255D01*
X149281Y-104095D01*
X149339Y-104102D01*
X149404Y-104117D01*
X149470Y-104139D01*
X149539Y-104172D01*
X149604Y-104211D01*
X149608D01*
X149612Y-104219D01*
X149630Y-104233D01*
X149659Y-104262D01*
X149696Y-104303D01*
X149732Y-104353D01*
X149772Y-104415D01*
X149805Y-104484D01*
X149830Y-104568D01*
Y-104565D01*
X149834Y-104561D01*
X149838Y-104550D01*
X149845Y-104535D01*
X149859Y-104503D01*
X149881Y-104459D01*
X149910Y-104412D01*
X149947Y-104364D01*
X149987Y-104321D01*
X150030Y-104281D01*
X150038Y-104277D01*
X150052Y-104266D01*
X150081Y-104252D01*
X150118Y-104237D01*
X150165Y-104219D01*
X150220Y-104204D01*
X150282Y-104193D01*
X150347Y-104190D01*
X150351D01*
X150358D01*
X150373D01*
X150394Y-104193D01*
X150416Y-104197D01*
X150445Y-104201D01*
X150507Y-104215D01*
X150580Y-104237D01*
X150656Y-104273D01*
X150697Y-104295D01*
X150736Y-104321D01*
X150773Y-104353D01*
X150809Y-104386D01*
X150813Y-104390D01*
X150817Y-104397D01*
X150828Y-104408D01*
X150838Y-104423D01*
X150853Y-104441D01*
X150868Y-104466D01*
X150886Y-104495D01*
X150904Y-104525D01*
X150922Y-104561D01*
X150940Y-104601D01*
X150955Y-104645D01*
X150970Y-104692D01*
X150991Y-104794D01*
X150995Y-104852D01*
X150999Y-104910D01*
Y-104943D01*
X150995Y-104965D01*
X150991Y-104994D01*
X150988Y-105027D01*
X150984Y-105063D01*
X150973Y-105100D01*
X150951Y-105187D01*
X150918Y-105274D01*
X150897Y-105318D01*
X150871Y-105362D01*
X150838Y-105402D01*
X150806Y-105442D01*
X150802Y-105446D01*
X150798Y-105449D01*
X150787Y-105460D01*
X150773Y-105475D01*
X150751Y-105489D01*
X150729Y-105507D01*
X150675Y-105544D01*
X150605Y-105580D01*
X150525Y-105613D01*
X150434Y-105638D01*
X150387Y-105642D01*
X150336Y-105646D01*
X150332D01*
X150329D01*
X150307D01*
X150274Y-105642D01*
X150234Y-105635D01*
X150183Y-105624D01*
X150132Y-105606D01*
X150081Y-105584D01*
X150030Y-105551D01*
X150023Y-105547D01*
X150008Y-105533D01*
X149987Y-105511D01*
X149958Y-105482D01*
X149925Y-105442D01*
X149892Y-105394D01*
X149859Y-105340D01*
X149830Y-105274D01*
Y-105278D01*
X149827Y-105285D01*
X149823Y-105296D01*
X149816Y-105311D01*
X149797Y-105354D01*
X149772Y-105405D01*
X149735Y-105460D01*
X149696Y-105518D01*
X149644Y-105573D01*
X149586Y-105624D01*
X149583D01*
X149579Y-105628D01*
X149557Y-105642D01*
X149521Y-105664D01*
X149474Y-105686D01*
X149415Y-105708D01*
X149346Y-105729D01*
X149270Y-105744D01*
X149186Y-105748D01*
X149182D01*
X149171D01*
X149153D01*
X149131Y-105744D01*
X149106Y-105740D01*
X149073Y-105737D01*
X149037Y-105729D01*
X148997Y-105719D01*
X148913Y-105693D01*
X148866Y-105675D01*
X148822Y-105649D01*
X148775Y-105624D01*
X148731Y-105595D01*
X148687Y-105558D01*
X148644Y-105518D01*
X148640Y-105515D01*
X148633Y-105507D01*
X148622Y-105496D01*
X148611Y-105478D01*
X148593Y-105453D01*
X148574Y-105427D01*
X148556Y-105394D01*
X148534Y-105358D01*
X148512Y-105318D01*
X148494Y-105271D01*
X148476Y-105220D01*
X148458Y-105169D01*
X148447Y-105111D01*
X148436Y-105049D01*
X148429Y-104987D01*
X148425Y-104918D01*
Y-104881D01*
X148429Y-104856D01*
X148432Y-104823D01*
X148436Y-104787D01*
X148443Y-104747D01*
X148454Y-104703D01*
X148480Y-104605D01*
X148498Y-104554D01*
X148516Y-104506D01*
X148542Y-104455D01*
X148571Y-104404D01*
X148603Y-104357D01*
X148644Y-104313D01*
X148647Y-104310D01*
X148654Y-104303D01*
X148665Y-104292D01*
X148684Y-104277D01*
X148705Y-104262D01*
X148731Y-104241D01*
X148760Y-104222D01*
X148796Y-104201D01*
X148833Y-104179D01*
X148877Y-104161D01*
X148968Y-104124D01*
X149022Y-104110D01*
X149077Y-104099D01*
X149135Y-104091D01*
X149193Y-104088D01*
X149197D01*
X149204D01*
X149219D01*
X149233Y-104091D01*
D02*
G37*
G36*
X154536Y-101578D02*
X154573D01*
X154609Y-101582D01*
X154657Y-101586D01*
X154704Y-101593D01*
X154809Y-101611D01*
X154926Y-101637D01*
X155042Y-101673D01*
X155155Y-101724D01*
X155159Y-101728D01*
X155170Y-101731D01*
X155184Y-101739D01*
X155202Y-101753D01*
X155228Y-101768D01*
X155257Y-101786D01*
X155323Y-101833D01*
X155395Y-101895D01*
X155468Y-101968D01*
X155541Y-102052D01*
X155603Y-102150D01*
X155607Y-102154D01*
X155610Y-102164D01*
X155617Y-102179D01*
X155628Y-102197D01*
X155639Y-102226D01*
X155650Y-102255D01*
X155665Y-102292D01*
X155679Y-102332D01*
X155694Y-102376D01*
X155709Y-102423D01*
X155730Y-102525D01*
X155748Y-102641D01*
X155756Y-102761D01*
Y-102798D01*
X155752Y-102823D01*
X155748Y-102856D01*
X155745Y-102896D01*
X155741Y-102936D01*
X155730Y-102983D01*
X155709Y-103082D01*
X155676Y-103191D01*
X155654Y-103245D01*
X155628Y-103296D01*
X155596Y-103348D01*
X155563Y-103398D01*
X155559Y-103402D01*
X155556Y-103409D01*
X155545Y-103424D01*
X155526Y-103442D01*
X155508Y-103460D01*
X155483Y-103486D01*
X155454Y-103511D01*
X155425Y-103540D01*
X155388Y-103569D01*
X155344Y-103599D01*
X155301Y-103631D01*
X155254Y-103661D01*
X155199Y-103686D01*
X155144Y-103715D01*
X155086Y-103737D01*
X155020Y-103759D01*
X154944Y-103431D01*
X154948D01*
X154955Y-103428D01*
X154970Y-103420D01*
X154988Y-103413D01*
X155010Y-103406D01*
X155039Y-103395D01*
X155097Y-103366D01*
X155163Y-103329D01*
X155228Y-103286D01*
X155290Y-103231D01*
X155344Y-103173D01*
X155352Y-103165D01*
X155366Y-103144D01*
X155385Y-103107D01*
X155410Y-103060D01*
X155432Y-102998D01*
X155454Y-102929D01*
X155468Y-102845D01*
X155472Y-102754D01*
Y-102725D01*
X155468Y-102707D01*
Y-102681D01*
X155465Y-102652D01*
X155454Y-102583D01*
X155439Y-102507D01*
X155414Y-102427D01*
X155377Y-102343D01*
X155330Y-102266D01*
Y-102263D01*
X155323Y-102259D01*
X155304Y-102234D01*
X155275Y-102201D01*
X155232Y-102161D01*
X155177Y-102113D01*
X155115Y-102070D01*
X155039Y-102030D01*
X154955Y-101993D01*
X154951D01*
X154944Y-101990D01*
X154933Y-101986D01*
X154915Y-101982D01*
X154893Y-101975D01*
X154868Y-101968D01*
X154806Y-101957D01*
X154733Y-101942D01*
X154653Y-101928D01*
X154566Y-101921D01*
X154471Y-101917D01*
X154467D01*
X154456D01*
X154438D01*
X154416D01*
X154391Y-101921D01*
X154358D01*
X154322Y-101924D01*
X154282Y-101928D01*
X154194Y-101939D01*
X154100Y-101957D01*
X154005Y-101979D01*
X153910Y-102008D01*
X153907D01*
X153899Y-102012D01*
X153888Y-102019D01*
X153870Y-102026D01*
X153827Y-102048D01*
X153776Y-102081D01*
X153717Y-102121D01*
X153656Y-102172D01*
X153601Y-102230D01*
X153550Y-102299D01*
Y-102303D01*
X153546Y-102310D01*
X153539Y-102321D01*
X153532Y-102336D01*
X153524Y-102354D01*
X153514Y-102376D01*
X153492Y-102427D01*
X153470Y-102492D01*
X153452Y-102565D01*
X153437Y-102645D01*
X153434Y-102729D01*
Y-102754D01*
X153437Y-102776D01*
Y-102801D01*
X153441Y-102827D01*
X153455Y-102892D01*
X153473Y-102969D01*
X153503Y-103045D01*
X153543Y-103125D01*
X153565Y-103165D01*
X153594Y-103202D01*
X153597Y-103206D01*
X153601Y-103209D01*
X153612Y-103220D01*
X153623Y-103235D01*
X153641Y-103249D01*
X153663Y-103267D01*
X153685Y-103289D01*
X153714Y-103307D01*
X153746Y-103329D01*
X153783Y-103355D01*
X153819Y-103377D01*
X153863Y-103398D01*
X153910Y-103417D01*
X153961Y-103435D01*
X154016Y-103453D01*
X154074Y-103468D01*
X153990Y-103802D01*
X153987D01*
X153972Y-103799D01*
X153950Y-103791D01*
X153921Y-103781D01*
X153888Y-103770D01*
X153848Y-103755D01*
X153805Y-103737D01*
X153757Y-103715D01*
X153656Y-103664D01*
X153554Y-103599D01*
X153503Y-103559D01*
X153452Y-103518D01*
X153408Y-103475D01*
X153364Y-103424D01*
X153361Y-103420D01*
X153353Y-103413D01*
X153346Y-103395D01*
X153332Y-103377D01*
X153313Y-103348D01*
X153295Y-103318D01*
X153277Y-103278D01*
X153259Y-103238D01*
X153237Y-103191D01*
X153219Y-103140D01*
X153200Y-103085D01*
X153182Y-103027D01*
X153168Y-102965D01*
X153161Y-102900D01*
X153153Y-102831D01*
X153150Y-102758D01*
Y-102718D01*
X153153Y-102689D01*
Y-102656D01*
X153157Y-102616D01*
X153164Y-102572D01*
X153171Y-102521D01*
X153190Y-102416D01*
X153219Y-102306D01*
X153259Y-102197D01*
X153284Y-102146D01*
X153313Y-102095D01*
X153317Y-102092D01*
X153321Y-102084D01*
X153332Y-102070D01*
X153346Y-102055D01*
X153361Y-102033D01*
X153383Y-102008D01*
X153408Y-101979D01*
X153437Y-101950D01*
X153470Y-101921D01*
X153503Y-101888D01*
X153586Y-101822D01*
X153685Y-101760D01*
X153794Y-101706D01*
X153797D01*
X153808Y-101699D01*
X153827Y-101695D01*
X153848Y-101684D01*
X153878Y-101677D01*
X153914Y-101666D01*
X153954Y-101651D01*
X153998Y-101640D01*
X154045Y-101629D01*
X154100Y-101615D01*
X154212Y-101597D01*
X154340Y-101582D01*
X154471Y-101575D01*
X154474D01*
X154489D01*
X154511D01*
X154536Y-101578D01*
D02*
G37*
G36*
X153899Y-104399D02*
X153896D01*
X153888Y-104403D01*
X153874Y-104407D01*
X153856Y-104410D01*
X153834Y-104414D01*
X153808Y-104421D01*
X153754Y-104439D01*
X153688Y-104465D01*
X153626Y-104498D01*
X153568Y-104534D01*
X153517Y-104578D01*
X153514Y-104585D01*
X153499Y-104600D01*
X153481Y-104629D01*
X153463Y-104665D01*
X153441Y-104709D01*
X153423Y-104763D01*
X153408Y-104825D01*
X153404Y-104891D01*
Y-104913D01*
X153408Y-104927D01*
X153412Y-104967D01*
X153423Y-105018D01*
X153441Y-105076D01*
X153466Y-105138D01*
X153503Y-105200D01*
X153554Y-105258D01*
X153561Y-105266D01*
X153583Y-105284D01*
X153615Y-105306D01*
X153659Y-105335D01*
X153714Y-105364D01*
X153776Y-105386D01*
X153848Y-105404D01*
X153928Y-105411D01*
X153932D01*
X153939D01*
X153950D01*
X153965Y-105408D01*
X154005Y-105404D01*
X154052Y-105393D01*
X154111Y-105379D01*
X154169Y-105353D01*
X154227Y-105317D01*
X154282Y-105269D01*
X154289Y-105262D01*
X154303Y-105244D01*
X154325Y-105215D01*
X154351Y-105175D01*
X154376Y-105124D01*
X154398Y-105062D01*
X154413Y-104993D01*
X154420Y-104916D01*
Y-104884D01*
X154416Y-104858D01*
X154413Y-104825D01*
X154405Y-104789D01*
X154398Y-104745D01*
X154387Y-104698D01*
X154660Y-104734D01*
Y-104753D01*
X154657Y-104767D01*
Y-104814D01*
X154664Y-104854D01*
X154671Y-104902D01*
X154682Y-104956D01*
X154700Y-105018D01*
X154726Y-105076D01*
X154758Y-105138D01*
Y-105142D01*
X154762Y-105146D01*
X154777Y-105164D01*
X154802Y-105189D01*
X154835Y-105218D01*
X154882Y-105247D01*
X154937Y-105273D01*
X154999Y-105291D01*
X155035Y-105298D01*
X155075D01*
X155079D01*
X155082D01*
X155104D01*
X155133Y-105291D01*
X155173Y-105284D01*
X155217Y-105269D01*
X155264Y-105251D01*
X155312Y-105222D01*
X155355Y-105182D01*
X155359Y-105178D01*
X155374Y-105160D01*
X155392Y-105135D01*
X155414Y-105102D01*
X155432Y-105058D01*
X155450Y-105007D01*
X155465Y-104949D01*
X155468Y-104884D01*
Y-104854D01*
X155461Y-104822D01*
X155454Y-104778D01*
X155439Y-104731D01*
X155421Y-104683D01*
X155392Y-104632D01*
X155355Y-104585D01*
X155352Y-104581D01*
X155334Y-104567D01*
X155308Y-104545D01*
X155272Y-104519D01*
X155224Y-104494D01*
X155166Y-104469D01*
X155097Y-104447D01*
X155017Y-104432D01*
X155071Y-104123D01*
X155075D01*
X155086Y-104126D01*
X155101Y-104130D01*
X155122Y-104134D01*
X155148Y-104141D01*
X155177Y-104152D01*
X155246Y-104174D01*
X155326Y-104210D01*
X155406Y-104254D01*
X155483Y-104308D01*
X155552Y-104378D01*
X155556Y-104381D01*
X155559Y-104388D01*
X155567Y-104399D01*
X155577Y-104414D01*
X155592Y-104432D01*
X155607Y-104458D01*
X155621Y-104483D01*
X155639Y-104516D01*
X155668Y-104589D01*
X155698Y-104672D01*
X155716Y-104771D01*
X155723Y-104822D01*
Y-104913D01*
X155719Y-104953D01*
X155712Y-105000D01*
X155701Y-105058D01*
X155683Y-105124D01*
X155661Y-105189D01*
X155632Y-105255D01*
Y-105258D01*
X155628Y-105262D01*
X155617Y-105284D01*
X155596Y-105317D01*
X155570Y-105353D01*
X155534Y-105397D01*
X155494Y-105440D01*
X155446Y-105484D01*
X155392Y-105520D01*
X155385Y-105524D01*
X155366Y-105535D01*
X155334Y-105550D01*
X155294Y-105568D01*
X155246Y-105586D01*
X155192Y-105601D01*
X155130Y-105612D01*
X155068Y-105615D01*
X155061D01*
X155039D01*
X155010Y-105612D01*
X154970Y-105604D01*
X154922Y-105593D01*
X154871Y-105575D01*
X154820Y-105553D01*
X154769Y-105524D01*
X154762Y-105520D01*
X154747Y-105510D01*
X154722Y-105488D01*
X154693Y-105459D01*
X154660Y-105422D01*
X154624Y-105379D01*
X154591Y-105328D01*
X154558Y-105266D01*
Y-105269D01*
X154555Y-105277D01*
X154551Y-105288D01*
X154547Y-105302D01*
X154533Y-105342D01*
X154511Y-105393D01*
X154482Y-105451D01*
X154445Y-105510D01*
X154398Y-105564D01*
X154343Y-105615D01*
X154336Y-105619D01*
X154314Y-105633D01*
X154278Y-105655D01*
X154231Y-105677D01*
X154172Y-105699D01*
X154103Y-105721D01*
X154023Y-105735D01*
X153936Y-105739D01*
X153932D01*
X153921D01*
X153903D01*
X153881Y-105735D01*
X153852Y-105732D01*
X153819Y-105724D01*
X153783Y-105717D01*
X153743Y-105710D01*
X153656Y-105681D01*
X153608Y-105659D01*
X153565Y-105637D01*
X153517Y-105608D01*
X153470Y-105575D01*
X153423Y-105539D01*
X153379Y-105495D01*
X153375Y-105491D01*
X153368Y-105484D01*
X153357Y-105470D01*
X153342Y-105451D01*
X153324Y-105429D01*
X153306Y-105400D01*
X153284Y-105368D01*
X153266Y-105328D01*
X153244Y-105288D01*
X153222Y-105240D01*
X153204Y-105193D01*
X153186Y-105138D01*
X153171Y-105080D01*
X153161Y-105018D01*
X153153Y-104956D01*
X153150Y-104887D01*
Y-104854D01*
X153153Y-104833D01*
X153157Y-104803D01*
X153161Y-104771D01*
X153168Y-104734D01*
X153175Y-104694D01*
X153197Y-104607D01*
X153233Y-104516D01*
X153255Y-104469D01*
X153281Y-104425D01*
X153313Y-104381D01*
X153346Y-104338D01*
X153350Y-104334D01*
X153357Y-104327D01*
X153368Y-104316D01*
X153383Y-104305D01*
X153401Y-104287D01*
X153426Y-104268D01*
X153452Y-104246D01*
X153484Y-104225D01*
X153521Y-104203D01*
X153557Y-104181D01*
X153645Y-104141D01*
X153746Y-104108D01*
X153801Y-104097D01*
X153859Y-104090D01*
X153899Y-104399D01*
D02*
G37*
G36*
X153262Y-106005D02*
X153295Y-106008D01*
X153332Y-106016D01*
X153368Y-106023D01*
X153408Y-106037D01*
X153412D01*
X153415Y-106041D01*
X153437Y-106048D01*
X153470Y-106063D01*
X153514Y-106085D01*
X153565Y-106114D01*
X153623Y-106150D01*
X153681Y-106190D01*
X153743Y-106241D01*
X153746D01*
X153750Y-106248D01*
X153772Y-106267D01*
X153805Y-106299D01*
X153852Y-106347D01*
X153907Y-106401D01*
X153972Y-106471D01*
X154045Y-106554D01*
X154121Y-106645D01*
X154125Y-106649D01*
X154136Y-106664D01*
X154154Y-106685D01*
X154176Y-106711D01*
X154205Y-106744D01*
X154238Y-106784D01*
X154274Y-106824D01*
X154314Y-106871D01*
X154402Y-106962D01*
X154489Y-107053D01*
X154533Y-107097D01*
X154576Y-107137D01*
X154616Y-107173D01*
X154657Y-107202D01*
X154660D01*
X154664Y-107210D01*
X154675Y-107217D01*
X154689Y-107224D01*
X154729Y-107249D01*
X154777Y-107279D01*
X154835Y-107304D01*
X154897Y-107330D01*
X154966Y-107344D01*
X155031Y-107351D01*
X155035D01*
X155039D01*
X155061Y-107348D01*
X155097Y-107344D01*
X155137Y-107333D01*
X155188Y-107319D01*
X155239Y-107293D01*
X155290Y-107260D01*
X155341Y-107217D01*
X155348Y-107210D01*
X155363Y-107191D01*
X155381Y-107166D01*
X155406Y-107126D01*
X155428Y-107075D01*
X155450Y-107017D01*
X155465Y-106947D01*
X155468Y-106871D01*
Y-106849D01*
X155465Y-106835D01*
X155461Y-106791D01*
X155450Y-106740D01*
X155436Y-106685D01*
X155410Y-106623D01*
X155377Y-106565D01*
X155334Y-106511D01*
X155326Y-106503D01*
X155308Y-106489D01*
X155279Y-106467D01*
X155235Y-106445D01*
X155184Y-106420D01*
X155119Y-106398D01*
X155046Y-106383D01*
X154962Y-106376D01*
X154995Y-106059D01*
X154999D01*
X155010Y-106063D01*
X155028D01*
X155053Y-106067D01*
X155082Y-106074D01*
X155115Y-106081D01*
X155155Y-106092D01*
X155195Y-106103D01*
X155283Y-106132D01*
X155370Y-106176D01*
X155414Y-106201D01*
X155457Y-106234D01*
X155497Y-106267D01*
X155534Y-106303D01*
X155537Y-106307D01*
X155541Y-106314D01*
X155552Y-106325D01*
X155563Y-106343D01*
X155577Y-106365D01*
X155592Y-106391D01*
X155610Y-106420D01*
X155628Y-106456D01*
X155647Y-106496D01*
X155665Y-106540D01*
X155679Y-106587D01*
X155694Y-106638D01*
X155705Y-106693D01*
X155716Y-106751D01*
X155719Y-106813D01*
X155723Y-106878D01*
Y-106915D01*
X155719Y-106940D01*
X155716Y-106969D01*
X155712Y-107006D01*
X155705Y-107046D01*
X155698Y-107086D01*
X155672Y-107180D01*
X155636Y-107275D01*
X155614Y-107322D01*
X155588Y-107370D01*
X155556Y-107413D01*
X155519Y-107453D01*
X155516Y-107457D01*
X155512Y-107464D01*
X155497Y-107472D01*
X155483Y-107486D01*
X155465Y-107504D01*
X155439Y-107522D01*
X155414Y-107541D01*
X155381Y-107563D01*
X155312Y-107599D01*
X155224Y-107635D01*
X155181Y-107650D01*
X155130Y-107657D01*
X155079Y-107665D01*
X155024Y-107668D01*
X155017D01*
X154999D01*
X154970Y-107665D01*
X154929Y-107661D01*
X154886Y-107654D01*
X154835Y-107639D01*
X154780Y-107624D01*
X154726Y-107603D01*
X154718Y-107599D01*
X154700Y-107592D01*
X154671Y-107577D01*
X154631Y-107555D01*
X154587Y-107526D01*
X154533Y-107490D01*
X154478Y-107446D01*
X154416Y-107395D01*
X154409Y-107388D01*
X154387Y-107370D01*
X154369Y-107351D01*
X154351Y-107333D01*
X154329Y-107311D01*
X154300Y-107282D01*
X154271Y-107253D01*
X154238Y-107217D01*
X154201Y-107180D01*
X154162Y-107137D01*
X154121Y-107089D01*
X154074Y-107038D01*
X154027Y-106980D01*
X153976Y-106922D01*
X153972Y-106918D01*
X153965Y-106911D01*
X153954Y-106896D01*
X153939Y-106878D01*
X153918Y-106856D01*
X153896Y-106831D01*
X153848Y-106773D01*
X153794Y-106711D01*
X153739Y-106653D01*
X153692Y-106602D01*
X153674Y-106580D01*
X153656Y-106562D01*
X153652Y-106558D01*
X153641Y-106547D01*
X153626Y-106532D01*
X153605Y-106514D01*
X153579Y-106496D01*
X153554Y-106474D01*
X153492Y-106430D01*
Y-107672D01*
X153193D01*
Y-106001D01*
X153197D01*
X153211D01*
X153233D01*
X153262Y-106005D01*
D02*
G37*
G36*
X615864Y-254123D02*
X615911Y-254130D01*
X615970Y-254141D01*
X616035Y-254159D01*
X616101Y-254181D01*
X616166Y-254210D01*
X616170D01*
X616174Y-254214D01*
X616195Y-254225D01*
X616228Y-254247D01*
X616265Y-254272D01*
X616308Y-254309D01*
X616352Y-254349D01*
X616396Y-254396D01*
X616432Y-254451D01*
X616436Y-254458D01*
X616447Y-254476D01*
X616461Y-254509D01*
X616479Y-254549D01*
X616498Y-254596D01*
X616512Y-254651D01*
X616523Y-254713D01*
X616527Y-254775D01*
Y-254782D01*
Y-254804D01*
X616523Y-254833D01*
X616516Y-254873D01*
X616505Y-254920D01*
X616487Y-254971D01*
X616465Y-255022D01*
X616436Y-255073D01*
X616432Y-255080D01*
X616421Y-255095D01*
X616399Y-255120D01*
X616370Y-255150D01*
X616334Y-255182D01*
X616290Y-255219D01*
X616239Y-255252D01*
X616177Y-255284D01*
X616181D01*
X616188Y-255288D01*
X616199Y-255292D01*
X616214Y-255295D01*
X616254Y-255310D01*
X616305Y-255332D01*
X616363Y-255361D01*
X616421Y-255397D01*
X616476Y-255444D01*
X616527Y-255499D01*
X616530Y-255506D01*
X616545Y-255528D01*
X616567Y-255565D01*
X616589Y-255612D01*
X616610Y-255670D01*
X616632Y-255739D01*
X616647Y-255819D01*
X616650Y-255907D01*
Y-255910D01*
Y-255921D01*
Y-255940D01*
X616647Y-255961D01*
X616643Y-255990D01*
X616636Y-256023D01*
X616629Y-256060D01*
X616621Y-256100D01*
X616592Y-256187D01*
X616570Y-256234D01*
X616548Y-256278D01*
X616519Y-256325D01*
X616487Y-256373D01*
X616450Y-256420D01*
X616406Y-256464D01*
X616403Y-256467D01*
X616396Y-256475D01*
X616381Y-256486D01*
X616363Y-256500D01*
X616341Y-256518D01*
X616312Y-256536D01*
X616279Y-256558D01*
X616239Y-256576D01*
X616199Y-256598D01*
X616152Y-256620D01*
X616104Y-256638D01*
X616050Y-256657D01*
X615992Y-256671D01*
X615930Y-256682D01*
X615868Y-256689D01*
X615799Y-256693D01*
X615766D01*
X615744Y-256689D01*
X615715Y-256686D01*
X615682Y-256682D01*
X615646Y-256675D01*
X615606Y-256667D01*
X615518Y-256646D01*
X615427Y-256609D01*
X615380Y-256587D01*
X615336Y-256562D01*
X615293Y-256529D01*
X615249Y-256496D01*
X615245Y-256493D01*
X615238Y-256486D01*
X615227Y-256475D01*
X615216Y-256460D01*
X615198Y-256442D01*
X615180Y-256416D01*
X615158Y-256391D01*
X615136Y-256358D01*
X615114Y-256322D01*
X615093Y-256285D01*
X615053Y-256198D01*
X615020Y-256096D01*
X615009Y-256041D01*
X615001Y-255983D01*
X615311Y-255943D01*
Y-255947D01*
X615314Y-255954D01*
X615318Y-255969D01*
X615322Y-255987D01*
X615325Y-256009D01*
X615333Y-256034D01*
X615351Y-256089D01*
X615376Y-256154D01*
X615409Y-256216D01*
X615446Y-256274D01*
X615489Y-256325D01*
X615497Y-256329D01*
X615511Y-256344D01*
X615540Y-256362D01*
X615577Y-256380D01*
X615620Y-256402D01*
X615675Y-256420D01*
X615737Y-256434D01*
X615802Y-256438D01*
X615824D01*
X615839Y-256434D01*
X615879Y-256431D01*
X615930Y-256420D01*
X615988Y-256402D01*
X616050Y-256376D01*
X616112Y-256340D01*
X616170Y-256289D01*
X616177Y-256282D01*
X616195Y-256260D01*
X616217Y-256227D01*
X616246Y-256183D01*
X616276Y-256129D01*
X616297Y-256067D01*
X616316Y-255994D01*
X616323Y-255914D01*
Y-255910D01*
Y-255903D01*
Y-255892D01*
X616319Y-255878D01*
X616316Y-255838D01*
X616305Y-255790D01*
X616290Y-255732D01*
X616265Y-255674D01*
X616228Y-255615D01*
X616181Y-255561D01*
X616174Y-255554D01*
X616155Y-255539D01*
X616126Y-255517D01*
X616086Y-255492D01*
X616035Y-255466D01*
X615973Y-255444D01*
X615904Y-255430D01*
X615828Y-255423D01*
X615795D01*
X615769Y-255426D01*
X615737Y-255430D01*
X615700Y-255437D01*
X615657Y-255444D01*
X615609Y-255455D01*
X615646Y-255182D01*
X615664D01*
X615679Y-255186D01*
X615726D01*
X615766Y-255179D01*
X615813Y-255171D01*
X615868Y-255160D01*
X615930Y-255142D01*
X615988Y-255117D01*
X616050Y-255084D01*
X616053D01*
X616057Y-255080D01*
X616075Y-255066D01*
X616101Y-255040D01*
X616130Y-255008D01*
X616159Y-254960D01*
X616185Y-254906D01*
X616203Y-254844D01*
X616210Y-254807D01*
Y-254767D01*
Y-254764D01*
Y-254760D01*
Y-254738D01*
X616203Y-254709D01*
X616195Y-254669D01*
X616181Y-254625D01*
X616163Y-254578D01*
X616134Y-254531D01*
X616093Y-254487D01*
X616090Y-254484D01*
X616072Y-254469D01*
X616046Y-254451D01*
X616013Y-254429D01*
X615970Y-254411D01*
X615919Y-254393D01*
X615861Y-254378D01*
X615795Y-254374D01*
X615766D01*
X615733Y-254382D01*
X615690Y-254389D01*
X615642Y-254403D01*
X615595Y-254422D01*
X615544Y-254451D01*
X615497Y-254487D01*
X615493Y-254491D01*
X615478Y-254509D01*
X615456Y-254534D01*
X615431Y-254571D01*
X615406Y-254618D01*
X615380Y-254676D01*
X615358Y-254746D01*
X615344Y-254826D01*
X615034Y-254771D01*
Y-254767D01*
X615038Y-254756D01*
X615042Y-254742D01*
X615045Y-254720D01*
X615053Y-254695D01*
X615063Y-254665D01*
X615085Y-254596D01*
X615122Y-254516D01*
X615165Y-254436D01*
X615220Y-254360D01*
X615289Y-254291D01*
X615293Y-254287D01*
X615300Y-254283D01*
X615311Y-254276D01*
X615325Y-254265D01*
X615344Y-254251D01*
X615369Y-254236D01*
X615395Y-254221D01*
X615427Y-254203D01*
X615500Y-254174D01*
X615584Y-254145D01*
X615682Y-254127D01*
X615733Y-254119D01*
X615824D01*
X615864Y-254123D01*
D02*
G37*
G36*
X611827Y-254134D02*
X611860D01*
X611937Y-254138D01*
X612017Y-254149D01*
X612104Y-254159D01*
X612184Y-254178D01*
X612224Y-254189D01*
X612257Y-254200D01*
X612261D01*
X612264Y-254203D01*
X612286Y-254214D01*
X612319Y-254229D01*
X612359Y-254254D01*
X612402Y-254287D01*
X612450Y-254331D01*
X612494Y-254382D01*
X612537Y-254440D01*
Y-254443D01*
X612541Y-254447D01*
X612555Y-254469D01*
X612570Y-254505D01*
X612592Y-254553D01*
X612610Y-254607D01*
X612628Y-254673D01*
X612639Y-254742D01*
X612643Y-254818D01*
Y-254822D01*
Y-254829D01*
Y-254844D01*
X612639Y-254862D01*
Y-254888D01*
X612636Y-254913D01*
X612621Y-254975D01*
X612599Y-255048D01*
X612570Y-255124D01*
X612526Y-255201D01*
X612497Y-255237D01*
X612468Y-255273D01*
X612464Y-255277D01*
X612461Y-255281D01*
X612450Y-255292D01*
X612435Y-255303D01*
X612417Y-255317D01*
X612395Y-255332D01*
X612366Y-255350D01*
X612337Y-255372D01*
X612301Y-255390D01*
X612261Y-255408D01*
X612217Y-255430D01*
X612170Y-255448D01*
X612115Y-255463D01*
X612060Y-255481D01*
X611999Y-255492D01*
X611933Y-255503D01*
X611940Y-255506D01*
X611955Y-255514D01*
X611977Y-255528D01*
X612006Y-255543D01*
X612071Y-255583D01*
X612104Y-255608D01*
X612133Y-255630D01*
X612141Y-255637D01*
X612159Y-255656D01*
X612188Y-255685D01*
X612224Y-255721D01*
X612264Y-255772D01*
X612312Y-255827D01*
X612359Y-255892D01*
X612410Y-255965D01*
X612843Y-256649D01*
X612428D01*
X612097Y-256125D01*
Y-256121D01*
X612089Y-256114D01*
X612082Y-256103D01*
X612071Y-256089D01*
X612046Y-256049D01*
X612013Y-255998D01*
X611973Y-255943D01*
X611933Y-255885D01*
X611893Y-255830D01*
X611857Y-255779D01*
X611853Y-255776D01*
X611842Y-255761D01*
X611824Y-255739D01*
X611798Y-255714D01*
X611744Y-255659D01*
X611715Y-255634D01*
X611686Y-255612D01*
X611682Y-255608D01*
X611674Y-255605D01*
X611660Y-255597D01*
X611638Y-255586D01*
X611616Y-255575D01*
X611591Y-255565D01*
X611533Y-255546D01*
X611529D01*
X611522Y-255543D01*
X611507D01*
X611489Y-255539D01*
X611463Y-255535D01*
X611434D01*
X611394Y-255532D01*
X610965D01*
Y-256649D01*
X610630D01*
Y-254130D01*
X611798D01*
X611827Y-254134D01*
D02*
G37*
G36*
X613913Y-254123D02*
X613942Y-254127D01*
X613975Y-254130D01*
X614011Y-254134D01*
X614048Y-254145D01*
X614135Y-254167D01*
X614222Y-254200D01*
X614266Y-254221D01*
X614310Y-254247D01*
X614350Y-254280D01*
X614390Y-254312D01*
X614394Y-254316D01*
X614397Y-254320D01*
X614408Y-254331D01*
X614423Y-254345D01*
X614437Y-254367D01*
X614456Y-254389D01*
X614492Y-254443D01*
X614528Y-254513D01*
X614561Y-254593D01*
X614586Y-254684D01*
X614590Y-254731D01*
X614594Y-254782D01*
Y-254786D01*
Y-254789D01*
Y-254811D01*
X614590Y-254844D01*
X614583Y-254884D01*
X614572Y-254935D01*
X614554Y-254986D01*
X614532Y-255037D01*
X614499Y-255088D01*
X614496Y-255095D01*
X614481Y-255110D01*
X614459Y-255131D01*
X614430Y-255160D01*
X614390Y-255193D01*
X614343Y-255226D01*
X614288Y-255259D01*
X614222Y-255288D01*
X614226D01*
X614233Y-255292D01*
X614244Y-255295D01*
X614259Y-255303D01*
X614303Y-255321D01*
X614354Y-255346D01*
X614408Y-255383D01*
X614466Y-255423D01*
X614521Y-255474D01*
X614572Y-255532D01*
Y-255535D01*
X614576Y-255539D01*
X614590Y-255561D01*
X614612Y-255597D01*
X614634Y-255645D01*
X614656Y-255703D01*
X614677Y-255772D01*
X614692Y-255849D01*
X614696Y-255932D01*
Y-255936D01*
Y-255947D01*
Y-255965D01*
X614692Y-255987D01*
X614688Y-256012D01*
X614685Y-256045D01*
X614677Y-256081D01*
X614667Y-256121D01*
X614641Y-256205D01*
X614623Y-256253D01*
X614598Y-256296D01*
X614572Y-256344D01*
X614543Y-256387D01*
X614506Y-256431D01*
X614466Y-256475D01*
X614463Y-256478D01*
X614456Y-256486D01*
X614445Y-256496D01*
X614426Y-256507D01*
X614401Y-256525D01*
X614375Y-256544D01*
X614343Y-256562D01*
X614306Y-256584D01*
X614266Y-256606D01*
X614219Y-256624D01*
X614168Y-256642D01*
X614117Y-256660D01*
X614059Y-256671D01*
X613997Y-256682D01*
X613935Y-256689D01*
X613866Y-256693D01*
X613829D01*
X613804Y-256689D01*
X613771Y-256686D01*
X613735Y-256682D01*
X613695Y-256675D01*
X613651Y-256664D01*
X613553Y-256638D01*
X613502Y-256620D01*
X613454Y-256602D01*
X613404Y-256576D01*
X613353Y-256547D01*
X613305Y-256515D01*
X613262Y-256475D01*
X613258Y-256471D01*
X613251Y-256464D01*
X613240Y-256453D01*
X613225Y-256434D01*
X613211Y-256413D01*
X613189Y-256387D01*
X613171Y-256358D01*
X613149Y-256322D01*
X613127Y-256285D01*
X613109Y-256242D01*
X613072Y-256151D01*
X613058Y-256096D01*
X613047Y-256041D01*
X613039Y-255983D01*
X613036Y-255925D01*
Y-255921D01*
Y-255914D01*
Y-255899D01*
X613039Y-255885D01*
Y-255863D01*
X613043Y-255838D01*
X613051Y-255779D01*
X613065Y-255714D01*
X613087Y-255648D01*
X613120Y-255579D01*
X613160Y-255514D01*
Y-255510D01*
X613167Y-255506D01*
X613181Y-255488D01*
X613211Y-255459D01*
X613251Y-255423D01*
X613302Y-255386D01*
X613364Y-255346D01*
X613433Y-255313D01*
X613516Y-255288D01*
X613513D01*
X613509Y-255284D01*
X613498Y-255281D01*
X613484Y-255273D01*
X613451Y-255259D01*
X613407Y-255237D01*
X613360Y-255208D01*
X613313Y-255171D01*
X613269Y-255131D01*
X613229Y-255088D01*
X613225Y-255080D01*
X613214Y-255066D01*
X613200Y-255037D01*
X613185Y-255000D01*
X613167Y-254953D01*
X613152Y-254898D01*
X613141Y-254837D01*
X613138Y-254771D01*
Y-254767D01*
Y-254760D01*
Y-254746D01*
X613141Y-254724D01*
X613145Y-254702D01*
X613149Y-254673D01*
X613163Y-254611D01*
X613185Y-254538D01*
X613222Y-254462D01*
X613243Y-254422D01*
X613269Y-254382D01*
X613302Y-254345D01*
X613334Y-254309D01*
X613338Y-254305D01*
X613345Y-254302D01*
X613356Y-254291D01*
X613371Y-254280D01*
X613389Y-254265D01*
X613414Y-254251D01*
X613444Y-254232D01*
X613473Y-254214D01*
X613509Y-254196D01*
X613549Y-254178D01*
X613593Y-254163D01*
X613640Y-254149D01*
X613742Y-254127D01*
X613800Y-254123D01*
X613859Y-254119D01*
X613891D01*
X613913Y-254123D01*
D02*
G37*
G36*
X614825Y-234996D02*
X614869D01*
X614916Y-235000D01*
X614967Y-235003D01*
X615083Y-235015D01*
X615204Y-235033D01*
X615320Y-235054D01*
X615375Y-235069D01*
X615429Y-235087D01*
X615433D01*
X615440Y-235091D01*
X615455Y-235098D01*
X615473Y-235105D01*
X615498Y-235113D01*
X615524Y-235127D01*
X615586Y-235156D01*
X615651Y-235193D01*
X615724Y-235240D01*
X615790Y-235295D01*
X615851Y-235360D01*
Y-235364D01*
X615859Y-235367D01*
X615866Y-235379D01*
X615873Y-235393D01*
X615884Y-235411D01*
X615899Y-235429D01*
X615924Y-235484D01*
X615950Y-235549D01*
X615975Y-235626D01*
X615990Y-235717D01*
X615997Y-235815D01*
Y-235852D01*
X615993Y-235877D01*
X615990Y-235906D01*
X615982Y-235943D01*
X615975Y-235983D01*
X615964Y-236026D01*
X615950Y-236070D01*
X615935Y-236117D01*
X615913Y-236165D01*
X615888Y-236212D01*
X615859Y-236259D01*
X615822Y-236307D01*
X615782Y-236350D01*
X615739Y-236390D01*
X615735Y-236394D01*
X615724Y-236401D01*
X615706Y-236412D01*
X615677Y-236430D01*
X615644Y-236449D01*
X615600Y-236467D01*
X615549Y-236492D01*
X615491Y-236514D01*
X615425Y-236536D01*
X615349Y-236558D01*
X615265Y-236580D01*
X615171Y-236598D01*
X615069Y-236616D01*
X614960Y-236627D01*
X614840Y-236634D01*
X614712Y-236638D01*
X614709D01*
X614694D01*
X614668D01*
X614639D01*
X614599Y-236634D01*
X614556D01*
X614508Y-236631D01*
X614454Y-236627D01*
X614341Y-236616D01*
X614221Y-236598D01*
X614101Y-236576D01*
X614046Y-236561D01*
X613991Y-236547D01*
X613988D01*
X613980Y-236543D01*
X613966Y-236536D01*
X613948Y-236529D01*
X613922Y-236521D01*
X613897Y-236507D01*
X613835Y-236478D01*
X613769Y-236441D01*
X613700Y-236394D01*
X613631Y-236339D01*
X613573Y-236274D01*
Y-236270D01*
X613565Y-236267D01*
X613558Y-236256D01*
X613551Y-236241D01*
X613536Y-236223D01*
X613525Y-236201D01*
X613496Y-236146D01*
X613471Y-236081D01*
X613445Y-236004D01*
X613431Y-235913D01*
X613423Y-235815D01*
Y-235783D01*
X613427Y-235742D01*
X613435Y-235695D01*
X613445Y-235641D01*
X613460Y-235582D01*
X613478Y-235520D01*
X613507Y-235462D01*
Y-235458D01*
X613511Y-235455D01*
X613522Y-235437D01*
X613540Y-235408D01*
X613565Y-235371D01*
X613602Y-235331D01*
X613642Y-235287D01*
X613689Y-235247D01*
X613744Y-235207D01*
X613751Y-235204D01*
X613769Y-235189D01*
X613802Y-235175D01*
X613849Y-235149D01*
X613904Y-235127D01*
X613966Y-235098D01*
X614039Y-235073D01*
X614119Y-235051D01*
X614122D01*
X614130Y-235047D01*
X614141Y-235044D01*
X614159Y-235040D01*
X614181Y-235036D01*
X614206Y-235033D01*
X614239Y-235025D01*
X614275Y-235022D01*
X614315Y-235015D01*
X614359Y-235011D01*
X614410Y-235007D01*
X614461Y-235000D01*
X614519Y-234996D01*
X614577D01*
X614643Y-234993D01*
X614712D01*
X614716D01*
X614730D01*
X614756D01*
X614785D01*
X614825Y-234996D01*
D02*
G37*
G36*
X615953Y-238640D02*
X615950D01*
X615935D01*
X615913D01*
X615884Y-238636D01*
X615851Y-238633D01*
X615815Y-238625D01*
X615779Y-238618D01*
X615739Y-238603D01*
X615735D01*
X615731Y-238600D01*
X615709Y-238593D01*
X615677Y-238578D01*
X615633Y-238556D01*
X615582Y-238527D01*
X615524Y-238491D01*
X615466Y-238451D01*
X615404Y-238400D01*
X615400D01*
X615396Y-238392D01*
X615375Y-238374D01*
X615342Y-238341D01*
X615295Y-238294D01*
X615240Y-238240D01*
X615174Y-238170D01*
X615102Y-238087D01*
X615025Y-237996D01*
X615022Y-237992D01*
X615011Y-237977D01*
X614992Y-237956D01*
X614970Y-237930D01*
X614941Y-237897D01*
X614909Y-237857D01*
X614872Y-237817D01*
X614832Y-237770D01*
X614745Y-237679D01*
X614657Y-237588D01*
X614614Y-237544D01*
X614570Y-237504D01*
X614530Y-237468D01*
X614490Y-237439D01*
X614486D01*
X614483Y-237431D01*
X614472Y-237424D01*
X614457Y-237417D01*
X614417Y-237391D01*
X614370Y-237362D01*
X614312Y-237337D01*
X614250Y-237311D01*
X614181Y-237297D01*
X614115Y-237290D01*
X614112D01*
X614108D01*
X614086Y-237293D01*
X614050Y-237297D01*
X614010Y-237308D01*
X613959Y-237322D01*
X613908Y-237348D01*
X613857Y-237381D01*
X613806Y-237424D01*
X613799Y-237431D01*
X613784Y-237450D01*
X613766Y-237475D01*
X613740Y-237515D01*
X613718Y-237566D01*
X613696Y-237624D01*
X613682Y-237694D01*
X613678Y-237770D01*
Y-237792D01*
X613682Y-237806D01*
X613686Y-237850D01*
X613696Y-237901D01*
X613711Y-237956D01*
X613737Y-238018D01*
X613769Y-238076D01*
X613813Y-238130D01*
X613820Y-238138D01*
X613838Y-238152D01*
X613868Y-238174D01*
X613911Y-238196D01*
X613962Y-238221D01*
X614028Y-238243D01*
X614101Y-238258D01*
X614184Y-238265D01*
X614151Y-238582D01*
X614148D01*
X614137Y-238578D01*
X614119D01*
X614093Y-238574D01*
X614064Y-238567D01*
X614031Y-238560D01*
X613991Y-238549D01*
X613951Y-238538D01*
X613864Y-238509D01*
X613777Y-238465D01*
X613733Y-238440D01*
X613689Y-238407D01*
X613649Y-238374D01*
X613613Y-238338D01*
X613609Y-238334D01*
X613605Y-238327D01*
X613595Y-238316D01*
X613584Y-238298D01*
X613569Y-238276D01*
X613555Y-238250D01*
X613536Y-238221D01*
X613518Y-238185D01*
X613500Y-238145D01*
X613482Y-238101D01*
X613467Y-238054D01*
X613453Y-238003D01*
X613442Y-237948D01*
X613431Y-237890D01*
X613427Y-237828D01*
X613423Y-237763D01*
Y-237726D01*
X613427Y-237701D01*
X613431Y-237672D01*
X613435Y-237635D01*
X613442Y-237595D01*
X613449Y-237555D01*
X613475Y-237460D01*
X613511Y-237366D01*
X613533Y-237319D01*
X613558Y-237271D01*
X613591Y-237228D01*
X613627Y-237188D01*
X613631Y-237184D01*
X613635Y-237177D01*
X613649Y-237169D01*
X613664Y-237155D01*
X613682Y-237137D01*
X613707Y-237118D01*
X613733Y-237100D01*
X613766Y-237078D01*
X613835Y-237042D01*
X613922Y-237005D01*
X613966Y-236991D01*
X614017Y-236984D01*
X614068Y-236976D01*
X614122Y-236973D01*
X614130D01*
X614148D01*
X614177Y-236976D01*
X614217Y-236980D01*
X614261Y-236987D01*
X614312Y-237002D01*
X614366Y-237017D01*
X614421Y-237038D01*
X614428Y-237042D01*
X614446Y-237049D01*
X614475Y-237064D01*
X614515Y-237086D01*
X614559Y-237115D01*
X614614Y-237151D01*
X614668Y-237195D01*
X614730Y-237246D01*
X614738Y-237253D01*
X614759Y-237271D01*
X614778Y-237290D01*
X614796Y-237308D01*
X614818Y-237330D01*
X614847Y-237359D01*
X614876Y-237388D01*
X614909Y-237424D01*
X614945Y-237460D01*
X614985Y-237504D01*
X615025Y-237551D01*
X615072Y-237602D01*
X615120Y-237661D01*
X615171Y-237719D01*
X615174Y-237723D01*
X615182Y-237730D01*
X615193Y-237744D01*
X615207Y-237763D01*
X615229Y-237785D01*
X615251Y-237810D01*
X615298Y-237868D01*
X615353Y-237930D01*
X615407Y-237988D01*
X615455Y-238039D01*
X615473Y-238061D01*
X615491Y-238079D01*
X615495Y-238083D01*
X615506Y-238094D01*
X615520Y-238108D01*
X615542Y-238127D01*
X615567Y-238145D01*
X615593Y-238167D01*
X615655Y-238210D01*
Y-236969D01*
X615953D01*
Y-238640D01*
D02*
G37*
G36*
X614985Y-239029D02*
X615022D01*
X615065Y-239033D01*
X615109Y-239037D01*
X615207Y-239048D01*
X615309Y-239062D01*
X615407Y-239084D01*
X615455Y-239099D01*
X615498Y-239113D01*
X615502D01*
X615509Y-239117D01*
X615520Y-239124D01*
X615535Y-239131D01*
X615575Y-239153D01*
X615626Y-239186D01*
X615684Y-239230D01*
X615742Y-239281D01*
X615804Y-239346D01*
X615859Y-239426D01*
Y-239430D01*
X615866Y-239437D01*
X615870Y-239448D01*
X615880Y-239466D01*
X615892Y-239488D01*
X615902Y-239517D01*
X615913Y-239546D01*
X615928Y-239583D01*
X615942Y-239623D01*
X615953Y-239666D01*
X615964Y-239714D01*
X615975Y-239768D01*
X615982Y-239823D01*
X615990Y-239881D01*
X615997Y-240012D01*
Y-240045D01*
X615993Y-240070D01*
Y-240100D01*
X615990Y-240136D01*
X615986Y-240176D01*
X615982Y-240216D01*
X615968Y-240307D01*
X615946Y-240405D01*
X615917Y-240500D01*
X615877Y-240591D01*
Y-240595D01*
X615870Y-240602D01*
X615862Y-240613D01*
X615855Y-240627D01*
X615826Y-240667D01*
X615786Y-240715D01*
X615735Y-240769D01*
X615677Y-240820D01*
X615604Y-240871D01*
X615524Y-240911D01*
X615520D01*
X615513Y-240915D01*
X615498Y-240918D01*
X615480Y-240926D01*
X615458Y-240933D01*
X615429Y-240940D01*
X615396Y-240951D01*
X615356Y-240959D01*
X615313Y-240966D01*
X615265Y-240977D01*
X615214Y-240984D01*
X615160Y-240991D01*
X615098Y-240999D01*
X615032Y-241002D01*
X614963Y-241006D01*
X614890D01*
X613435D01*
Y-240671D01*
X614890D01*
X614894D01*
X614905D01*
X614923D01*
X614945D01*
X614970Y-240667D01*
X615003D01*
X615072Y-240664D01*
X615153Y-240656D01*
X615233Y-240646D01*
X615309Y-240631D01*
X615342Y-240624D01*
X615375Y-240613D01*
X615382Y-240609D01*
X615400Y-240602D01*
X615425Y-240584D01*
X615462Y-240562D01*
X615498Y-240536D01*
X615538Y-240500D01*
X615578Y-240456D01*
X615611Y-240405D01*
X615615Y-240398D01*
X615626Y-240380D01*
X615637Y-240347D01*
X615651Y-240303D01*
X615669Y-240252D01*
X615680Y-240187D01*
X615691Y-240118D01*
X615695Y-240041D01*
Y-240005D01*
X615691Y-239983D01*
Y-239950D01*
X615688Y-239917D01*
X615673Y-239838D01*
X615655Y-239750D01*
X615626Y-239666D01*
X615586Y-239586D01*
X615560Y-239550D01*
X615531Y-239517D01*
X615527Y-239513D01*
X615524Y-239510D01*
X615513Y-239503D01*
X615498Y-239492D01*
X615477Y-239481D01*
X615455Y-239466D01*
X615422Y-239452D01*
X615389Y-239437D01*
X615349Y-239422D01*
X615302Y-239412D01*
X615247Y-239397D01*
X615189Y-239386D01*
X615123Y-239375D01*
X615054Y-239368D01*
X614974Y-239361D01*
X614890D01*
X613435D01*
Y-239026D01*
X614890D01*
X614894D01*
X614909D01*
X614927D01*
X614952D01*
X614985Y-239029D01*
D02*
G37*
G36*
X607884Y-300000D02*
X607575D01*
Y-298031D01*
X607571Y-298035D01*
X607553Y-298049D01*
X607531Y-298071D01*
X607494Y-298096D01*
X607454Y-298129D01*
X607404Y-298165D01*
X607345Y-298205D01*
X607280Y-298246D01*
X607276D01*
X607272Y-298249D01*
X607251Y-298264D01*
X607214Y-298282D01*
X607171Y-298304D01*
X607120Y-298329D01*
X607065Y-298355D01*
X607010Y-298380D01*
X606956Y-298402D01*
Y-298104D01*
X606959D01*
X606967Y-298096D01*
X606981Y-298093D01*
X606999Y-298082D01*
X607021Y-298071D01*
X607047Y-298056D01*
X607109Y-298020D01*
X607182Y-297980D01*
X607254Y-297929D01*
X607331Y-297871D01*
X607407Y-297809D01*
X607411Y-297805D01*
X607414Y-297801D01*
X607425Y-297791D01*
X607440Y-297780D01*
X607473Y-297743D01*
X607516Y-297700D01*
X607560Y-297649D01*
X607607Y-297590D01*
X607647Y-297532D01*
X607684Y-297470D01*
X607884D01*
Y-300000D01*
D02*
G37*
G36*
X605500Y-297485D02*
X605529D01*
X605594Y-297492D01*
X605667Y-297499D01*
X605744Y-297514D01*
X605820Y-297532D01*
X605889Y-297558D01*
X605893D01*
X605897Y-297561D01*
X605918Y-297572D01*
X605951Y-297590D01*
X605988Y-297616D01*
X606031Y-297649D01*
X606079Y-297689D01*
X606122Y-297740D01*
X606162Y-297794D01*
X606166Y-297801D01*
X606177Y-297823D01*
X606195Y-297852D01*
X606213Y-297896D01*
X606231Y-297947D01*
X606250Y-298002D01*
X606261Y-298064D01*
X606264Y-298126D01*
Y-298133D01*
Y-298151D01*
X606261Y-298184D01*
X606253Y-298224D01*
X606242Y-298271D01*
X606224Y-298322D01*
X606202Y-298373D01*
X606173Y-298428D01*
X606170Y-298435D01*
X606159Y-298449D01*
X606137Y-298479D01*
X606108Y-298508D01*
X606071Y-298544D01*
X606028Y-298584D01*
X605973Y-298621D01*
X605911Y-298657D01*
X605915D01*
X605922Y-298660D01*
X605933Y-298664D01*
X605947Y-298672D01*
X605991Y-298686D01*
X606042Y-298711D01*
X606097Y-298744D01*
X606159Y-298784D01*
X606213Y-298832D01*
X606264Y-298890D01*
X606268Y-298897D01*
X606282Y-298919D01*
X606304Y-298952D01*
X606326Y-298995D01*
X606348Y-299054D01*
X606370Y-299115D01*
X606384Y-299188D01*
X606388Y-299268D01*
Y-299272D01*
Y-299276D01*
Y-299297D01*
X606384Y-299334D01*
X606377Y-299378D01*
X606370Y-299429D01*
X606355Y-299483D01*
X606337Y-299541D01*
X606312Y-299600D01*
X606308Y-299607D01*
X606297Y-299625D01*
X606282Y-299651D01*
X606261Y-299687D01*
X606231Y-299723D01*
X606202Y-299763D01*
X606166Y-299803D01*
X606126Y-299836D01*
X606122Y-299840D01*
X606108Y-299851D01*
X606082Y-299865D01*
X606049Y-299880D01*
X606009Y-299902D01*
X605962Y-299924D01*
X605911Y-299942D01*
X605849Y-299960D01*
X605842D01*
X605820Y-299967D01*
X605784Y-299971D01*
X605736Y-299978D01*
X605678Y-299986D01*
X605609Y-299993D01*
X605533Y-299996D01*
X605445Y-300000D01*
X604484D01*
Y-297481D01*
X605474D01*
X605500Y-297485D01*
D02*
G37*
G36*
X604066Y-297780D02*
X602697D01*
Y-298559D01*
X603880D01*
Y-298857D01*
X602697D01*
Y-300000D01*
X602362D01*
Y-297481D01*
X604066D01*
Y-297780D01*
D02*
G37*
G36*
X615815Y-300153D02*
X615848Y-300157D01*
X615888Y-300161D01*
X615928Y-300164D01*
X615976Y-300175D01*
X616074Y-300197D01*
X616183Y-300230D01*
X616238Y-300252D01*
X616289Y-300277D01*
X616340Y-300310D01*
X616391Y-300343D01*
X616394Y-300346D01*
X616401Y-300350D01*
X616416Y-300361D01*
X616434Y-300379D01*
X616452Y-300397D01*
X616478Y-300423D01*
X616503Y-300452D01*
X616533Y-300481D01*
X616562Y-300517D01*
X616591Y-300561D01*
X616623Y-300605D01*
X616653Y-300652D01*
X616678Y-300707D01*
X616707Y-300761D01*
X616729Y-300819D01*
X616751Y-300885D01*
X616423Y-300961D01*
Y-300958D01*
X616420Y-300951D01*
X616412Y-300936D01*
X616405Y-300918D01*
X616398Y-300896D01*
X616387Y-300867D01*
X616358Y-300809D01*
X616321Y-300743D01*
X616278Y-300677D01*
X616223Y-300616D01*
X616165Y-300561D01*
X616158Y-300554D01*
X616136Y-300539D01*
X616099Y-300521D01*
X616052Y-300496D01*
X615990Y-300474D01*
X615921Y-300452D01*
X615837Y-300437D01*
X615746Y-300434D01*
X615717D01*
X615699Y-300437D01*
X615673D01*
X615644Y-300441D01*
X615575Y-300452D01*
X615499Y-300466D01*
X615419Y-300492D01*
X615335Y-300528D01*
X615259Y-300576D01*
X615255D01*
X615251Y-300583D01*
X615226Y-300601D01*
X615193Y-300630D01*
X615153Y-300674D01*
X615106Y-300729D01*
X615062Y-300790D01*
X615022Y-300867D01*
X614986Y-300951D01*
Y-300954D01*
X614982Y-300961D01*
X614978Y-300972D01*
X614975Y-300991D01*
X614967Y-301012D01*
X614960Y-301038D01*
X614949Y-301100D01*
X614934Y-301173D01*
X614920Y-301253D01*
X614913Y-301340D01*
X614909Y-301435D01*
Y-301438D01*
Y-301449D01*
Y-301467D01*
Y-301489D01*
X614913Y-301515D01*
Y-301548D01*
X614916Y-301584D01*
X614920Y-301624D01*
X614931Y-301711D01*
X614949Y-301806D01*
X614971Y-301901D01*
X615000Y-301995D01*
Y-301999D01*
X615004Y-302006D01*
X615011Y-302017D01*
X615018Y-302035D01*
X615040Y-302079D01*
X615073Y-302130D01*
X615113Y-302188D01*
X615164Y-302250D01*
X615222Y-302305D01*
X615291Y-302356D01*
X615295D01*
X615302Y-302359D01*
X615313Y-302366D01*
X615328Y-302374D01*
X615346Y-302381D01*
X615368Y-302392D01*
X615419Y-302414D01*
X615484Y-302436D01*
X615557Y-302454D01*
X615637Y-302468D01*
X615721Y-302472D01*
X615746D01*
X615768Y-302468D01*
X615794D01*
X615819Y-302465D01*
X615885Y-302450D01*
X615961Y-302432D01*
X616037Y-302403D01*
X616117Y-302363D01*
X616158Y-302341D01*
X616194Y-302312D01*
X616198Y-302308D01*
X616201Y-302305D01*
X616212Y-302294D01*
X616227Y-302283D01*
X616241Y-302265D01*
X616259Y-302243D01*
X616281Y-302221D01*
X616299Y-302192D01*
X616321Y-302159D01*
X616347Y-302123D01*
X616369Y-302086D01*
X616391Y-302043D01*
X616409Y-301995D01*
X616427Y-301944D01*
X616445Y-301890D01*
X616460Y-301831D01*
X616795Y-301915D01*
Y-301919D01*
X616791Y-301933D01*
X616784Y-301955D01*
X616773Y-301984D01*
X616762Y-302017D01*
X616747Y-302057D01*
X616729Y-302101D01*
X616707Y-302148D01*
X616656Y-302250D01*
X616591Y-302352D01*
X616551Y-302403D01*
X616511Y-302454D01*
X616467Y-302498D01*
X616416Y-302541D01*
X616412Y-302545D01*
X616405Y-302552D01*
X616387Y-302559D01*
X616369Y-302574D01*
X616340Y-302592D01*
X616310Y-302610D01*
X616270Y-302629D01*
X616230Y-302647D01*
X616183Y-302669D01*
X616132Y-302687D01*
X616078Y-302705D01*
X616019Y-302723D01*
X615957Y-302738D01*
X615892Y-302745D01*
X615823Y-302752D01*
X615750Y-302756D01*
X615710D01*
X615681Y-302752D01*
X615648D01*
X615608Y-302749D01*
X615564Y-302741D01*
X615513Y-302734D01*
X615408Y-302716D01*
X615299Y-302687D01*
X615189Y-302647D01*
X615138Y-302621D01*
X615087Y-302592D01*
X615084Y-302589D01*
X615076Y-302585D01*
X615062Y-302574D01*
X615047Y-302559D01*
X615026Y-302545D01*
X615000Y-302523D01*
X614971Y-302498D01*
X614942Y-302468D01*
X614913Y-302436D01*
X614880Y-302403D01*
X614814Y-302319D01*
X614752Y-302221D01*
X614698Y-302112D01*
Y-302108D01*
X614691Y-302097D01*
X614687Y-302079D01*
X614676Y-302057D01*
X614669Y-302028D01*
X614658Y-301992D01*
X614643Y-301952D01*
X614632Y-301908D01*
X614621Y-301860D01*
X614607Y-301806D01*
X614589Y-301693D01*
X614574Y-301566D01*
X614567Y-301435D01*
Y-301431D01*
Y-301416D01*
Y-301395D01*
X614571Y-301369D01*
Y-301333D01*
X614574Y-301296D01*
X614578Y-301249D01*
X614585Y-301202D01*
X614603Y-301096D01*
X614629Y-300980D01*
X614665Y-300863D01*
X614716Y-300750D01*
X614720Y-300747D01*
X614723Y-300736D01*
X614731Y-300721D01*
X614745Y-300703D01*
X614760Y-300677D01*
X614778Y-300648D01*
X614825Y-300583D01*
X614887Y-300510D01*
X614960Y-300437D01*
X615044Y-300364D01*
X615142Y-300303D01*
X615146Y-300299D01*
X615157Y-300295D01*
X615171Y-300288D01*
X615189Y-300277D01*
X615218Y-300266D01*
X615248Y-300255D01*
X615284Y-300241D01*
X615324Y-300226D01*
X615368Y-300212D01*
X615415Y-300197D01*
X615517Y-300175D01*
X615633Y-300157D01*
X615754Y-300150D01*
X615790D01*
X615815Y-300153D01*
D02*
G37*
G36*
X619870Y-300186D02*
X619889D01*
X619914Y-300190D01*
X619976Y-300201D01*
X620045Y-300215D01*
X620121Y-300241D01*
X620198Y-300273D01*
X620274Y-300317D01*
X620278D01*
X620282Y-300324D01*
X620293Y-300332D01*
X620307Y-300343D01*
X620344Y-300372D01*
X620391Y-300412D01*
X620438Y-300466D01*
X620493Y-300532D01*
X620540Y-300608D01*
X620584Y-300696D01*
Y-300699D01*
X620587Y-300707D01*
X620595Y-300721D01*
X620602Y-300739D01*
X620609Y-300765D01*
X620620Y-300798D01*
X620627Y-300834D01*
X620638Y-300874D01*
X620649Y-300921D01*
X620660Y-300976D01*
X620668Y-301034D01*
X620675Y-301096D01*
X620682Y-301165D01*
X620689Y-301238D01*
X620693Y-301318D01*
Y-301402D01*
Y-301406D01*
Y-301424D01*
Y-301449D01*
Y-301482D01*
X620689Y-301522D01*
Y-301569D01*
X620686Y-301624D01*
X620678Y-301678D01*
X620668Y-301802D01*
X620649Y-301933D01*
X620624Y-302057D01*
X620606Y-302119D01*
X620587Y-302174D01*
Y-302177D01*
X620584Y-302185D01*
X620576Y-302199D01*
X620569Y-302221D01*
X620558Y-302243D01*
X620544Y-302272D01*
X620507Y-302334D01*
X620464Y-302403D01*
X620413Y-302476D01*
X620347Y-302545D01*
X620274Y-302607D01*
X620271D01*
X620263Y-302614D01*
X620253Y-302621D01*
X620238Y-302629D01*
X620216Y-302640D01*
X620194Y-302654D01*
X620165Y-302669D01*
X620136Y-302679D01*
X620067Y-302709D01*
X619983Y-302734D01*
X619892Y-302749D01*
X619790Y-302756D01*
X619761D01*
X619743Y-302752D01*
X619718D01*
X619688Y-302749D01*
X619619Y-302734D01*
X619543Y-302716D01*
X619463Y-302687D01*
X619383Y-302647D01*
X619343Y-302621D01*
X619306Y-302592D01*
X619303Y-302589D01*
X619299Y-302585D01*
X619288Y-302574D01*
X619277Y-302563D01*
X619263Y-302545D01*
X619244Y-302523D01*
X619208Y-302472D01*
X619171Y-302407D01*
X619135Y-302326D01*
X619106Y-302235D01*
X619084Y-302130D01*
X619383Y-302104D01*
Y-302108D01*
X619386Y-302115D01*
Y-302123D01*
X619390Y-302137D01*
X619401Y-302177D01*
X619415Y-302221D01*
X619434Y-302272D01*
X619459Y-302323D01*
X619488Y-302370D01*
X619525Y-302410D01*
X619528Y-302414D01*
X619543Y-302425D01*
X619568Y-302439D01*
X619597Y-302454D01*
X619637Y-302472D01*
X619685Y-302487D01*
X619739Y-302498D01*
X619798Y-302501D01*
X619823D01*
X619848Y-302498D01*
X619881Y-302494D01*
X619921Y-302487D01*
X619961Y-302476D01*
X620005Y-302461D01*
X620045Y-302439D01*
X620049Y-302436D01*
X620063Y-302428D01*
X620085Y-302414D01*
X620107Y-302392D01*
X620136Y-302366D01*
X620165Y-302337D01*
X620194Y-302305D01*
X620223Y-302265D01*
X620227Y-302261D01*
X620234Y-302243D01*
X620249Y-302217D01*
X620263Y-302185D01*
X620282Y-302141D01*
X620300Y-302090D01*
X620318Y-302032D01*
X620336Y-301966D01*
Y-301962D01*
X620340Y-301959D01*
Y-301948D01*
X620344Y-301933D01*
X620351Y-301897D01*
X620362Y-301850D01*
X620369Y-301791D01*
X620376Y-301729D01*
X620380Y-301660D01*
X620384Y-301588D01*
Y-301584D01*
Y-301573D01*
Y-301555D01*
Y-301526D01*
X620380Y-301533D01*
X620365Y-301551D01*
X620344Y-301577D01*
X620318Y-301613D01*
X620282Y-301649D01*
X620238Y-301689D01*
X620187Y-301729D01*
X620129Y-301766D01*
X620121Y-301769D01*
X620100Y-301780D01*
X620067Y-301795D01*
X620027Y-301810D01*
X619972Y-301828D01*
X619914Y-301842D01*
X619848Y-301853D01*
X619779Y-301857D01*
X619750D01*
X619728Y-301853D01*
X619699Y-301850D01*
X619670Y-301846D01*
X619634Y-301839D01*
X619597Y-301828D01*
X619514Y-301802D01*
X619470Y-301784D01*
X619426Y-301762D01*
X619379Y-301737D01*
X619335Y-301704D01*
X619292Y-301671D01*
X619252Y-301631D01*
X619248Y-301628D01*
X619241Y-301620D01*
X619233Y-301609D01*
X619219Y-301591D01*
X619201Y-301566D01*
X619182Y-301540D01*
X619164Y-301507D01*
X619146Y-301471D01*
X619124Y-301431D01*
X619106Y-301387D01*
X619088Y-301336D01*
X619070Y-301285D01*
X619055Y-301227D01*
X619048Y-301165D01*
X619040Y-301103D01*
X619037Y-301034D01*
Y-301031D01*
Y-301016D01*
Y-300998D01*
X619040Y-300972D01*
X619044Y-300940D01*
X619048Y-300900D01*
X619055Y-300859D01*
X619066Y-300812D01*
X619091Y-300718D01*
X619110Y-300667D01*
X619131Y-300612D01*
X619157Y-300561D01*
X619190Y-300514D01*
X619222Y-300463D01*
X619263Y-300419D01*
X619266Y-300415D01*
X619273Y-300408D01*
X619284Y-300397D01*
X619303Y-300383D01*
X619324Y-300364D01*
X619353Y-300343D01*
X619383Y-300324D01*
X619419Y-300299D01*
X619455Y-300277D01*
X619499Y-300259D01*
X619597Y-300219D01*
X619648Y-300204D01*
X619707Y-300193D01*
X619765Y-300186D01*
X619827Y-300183D01*
X619852D01*
X619870Y-300186D01*
D02*
G37*
G36*
X617952D02*
X617981Y-300190D01*
X618014Y-300193D01*
X618050Y-300197D01*
X618087Y-300208D01*
X618174Y-300230D01*
X618261Y-300263D01*
X618305Y-300284D01*
X618349Y-300310D01*
X618389Y-300343D01*
X618429Y-300375D01*
X618433Y-300379D01*
X618436Y-300383D01*
X618447Y-300394D01*
X618462Y-300408D01*
X618476Y-300430D01*
X618494Y-300452D01*
X618531Y-300506D01*
X618567Y-300576D01*
X618600Y-300656D01*
X618625Y-300747D01*
X618629Y-300794D01*
X618633Y-300845D01*
Y-300849D01*
Y-300852D01*
Y-300874D01*
X618629Y-300907D01*
X618622Y-300947D01*
X618611Y-300998D01*
X618593Y-301049D01*
X618571Y-301100D01*
X618538Y-301151D01*
X618535Y-301158D01*
X618520Y-301173D01*
X618498Y-301194D01*
X618469Y-301223D01*
X618429Y-301256D01*
X618382Y-301289D01*
X618327Y-301322D01*
X618261Y-301351D01*
X618265D01*
X618272Y-301355D01*
X618283Y-301358D01*
X618298Y-301365D01*
X618342Y-301384D01*
X618393Y-301409D01*
X618447Y-301446D01*
X618505Y-301486D01*
X618560Y-301537D01*
X618611Y-301595D01*
Y-301598D01*
X618615Y-301602D01*
X618629Y-301624D01*
X618651Y-301660D01*
X618673Y-301708D01*
X618695Y-301766D01*
X618716Y-301835D01*
X618731Y-301911D01*
X618735Y-301995D01*
Y-301999D01*
Y-302010D01*
Y-302028D01*
X618731Y-302050D01*
X618727Y-302075D01*
X618724Y-302108D01*
X618716Y-302144D01*
X618706Y-302185D01*
X618680Y-302268D01*
X618662Y-302315D01*
X618636Y-302359D01*
X618611Y-302407D01*
X618582Y-302450D01*
X618545Y-302494D01*
X618505Y-302538D01*
X618502Y-302541D01*
X618494Y-302549D01*
X618483Y-302559D01*
X618465Y-302570D01*
X618440Y-302589D01*
X618414Y-302607D01*
X618382Y-302625D01*
X618345Y-302647D01*
X618305Y-302669D01*
X618258Y-302687D01*
X618207Y-302705D01*
X618156Y-302723D01*
X618098Y-302734D01*
X618036Y-302745D01*
X617974Y-302752D01*
X617905Y-302756D01*
X617868D01*
X617843Y-302752D01*
X617810Y-302749D01*
X617774Y-302745D01*
X617734Y-302738D01*
X617690Y-302727D01*
X617592Y-302701D01*
X617541Y-302683D01*
X617493Y-302665D01*
X617443Y-302640D01*
X617391Y-302610D01*
X617344Y-302578D01*
X617301Y-302538D01*
X617297Y-302534D01*
X617290Y-302527D01*
X617279Y-302516D01*
X617264Y-302498D01*
X617250Y-302476D01*
X617228Y-302450D01*
X617209Y-302421D01*
X617188Y-302385D01*
X617166Y-302348D01*
X617148Y-302305D01*
X617111Y-302214D01*
X617097Y-302159D01*
X617086Y-302104D01*
X617078Y-302046D01*
X617075Y-301988D01*
Y-301984D01*
Y-301977D01*
Y-301962D01*
X617078Y-301948D01*
Y-301926D01*
X617082Y-301901D01*
X617089Y-301842D01*
X617104Y-301777D01*
X617126Y-301711D01*
X617159Y-301642D01*
X617199Y-301577D01*
Y-301573D01*
X617206Y-301569D01*
X617220Y-301551D01*
X617250Y-301522D01*
X617290Y-301486D01*
X617341Y-301449D01*
X617402Y-301409D01*
X617472Y-301376D01*
X617555Y-301351D01*
X617552D01*
X617548Y-301347D01*
X617537Y-301344D01*
X617523Y-301336D01*
X617490Y-301322D01*
X617446Y-301300D01*
X617399Y-301271D01*
X617351Y-301234D01*
X617308Y-301194D01*
X617268Y-301151D01*
X617264Y-301143D01*
X617253Y-301129D01*
X617239Y-301100D01*
X617224Y-301063D01*
X617206Y-301016D01*
X617191Y-300961D01*
X617180Y-300900D01*
X617177Y-300834D01*
Y-300830D01*
Y-300823D01*
Y-300809D01*
X617180Y-300787D01*
X617184Y-300765D01*
X617188Y-300736D01*
X617202Y-300674D01*
X617224Y-300601D01*
X617261Y-300525D01*
X617282Y-300485D01*
X617308Y-300445D01*
X617341Y-300408D01*
X617373Y-300372D01*
X617377Y-300368D01*
X617384Y-300364D01*
X617395Y-300354D01*
X617410Y-300343D01*
X617428Y-300328D01*
X617453Y-300313D01*
X617483Y-300295D01*
X617512Y-300277D01*
X617548Y-300259D01*
X617588Y-300241D01*
X617632Y-300226D01*
X617679Y-300212D01*
X617781Y-300190D01*
X617839Y-300186D01*
X617898Y-300183D01*
X617930D01*
X617952Y-300186D01*
D02*
G37*
G36*
X592739Y-292130D02*
X592768D01*
X592801Y-292133D01*
X592837Y-292141D01*
X592881Y-292151D01*
X592925Y-292162D01*
X592976Y-292177D01*
X593027Y-292195D01*
X593078Y-292217D01*
X593132Y-292246D01*
X593183Y-292279D01*
X593234Y-292315D01*
X593285Y-292359D01*
X593332Y-292410D01*
X593336Y-292413D01*
X593343Y-292424D01*
X593354Y-292439D01*
X593369Y-292464D01*
X593391Y-292497D01*
X593409Y-292534D01*
X593431Y-292581D01*
X593452Y-292632D01*
X593478Y-292694D01*
X593500Y-292763D01*
X593518Y-292839D01*
X593536Y-292923D01*
X593554Y-293018D01*
X593565Y-293120D01*
X593573Y-293229D01*
X593576Y-293345D01*
Y-293349D01*
Y-293353D01*
Y-293363D01*
Y-293378D01*
X593573Y-293414D01*
Y-293465D01*
X593569Y-293524D01*
X593562Y-293593D01*
X593554Y-293669D01*
X593543Y-293753D01*
X593529Y-293837D01*
X593511Y-293928D01*
X593489Y-294015D01*
X593463Y-294103D01*
X593431Y-294186D01*
X593394Y-294266D01*
X593354Y-294343D01*
X593307Y-294408D01*
X593303Y-294412D01*
X593296Y-294419D01*
X593281Y-294434D01*
X593263Y-294456D01*
X593241Y-294477D01*
X593212Y-294499D01*
X593176Y-294528D01*
X593139Y-294554D01*
X593096Y-294579D01*
X593048Y-294608D01*
X592994Y-294630D01*
X592939Y-294656D01*
X592877Y-294674D01*
X592812Y-294689D01*
X592743Y-294696D01*
X592670Y-294699D01*
X592641D01*
X592619Y-294696D01*
X592593D01*
X592564Y-294692D01*
X592495Y-294678D01*
X592419Y-294659D01*
X592339Y-294630D01*
X592259Y-294587D01*
X592218Y-294561D01*
X592182Y-294532D01*
X592178Y-294528D01*
X592175Y-294525D01*
X592164Y-294514D01*
X592153Y-294503D01*
X592135Y-294485D01*
X592120Y-294463D01*
X592080Y-294412D01*
X592040Y-294346D01*
X592004Y-294266D01*
X591971Y-294175D01*
X591949Y-294073D01*
X592259Y-294048D01*
Y-294052D01*
X592262Y-294055D01*
X592266Y-294077D01*
X592277Y-294110D01*
X592291Y-294150D01*
X592306Y-294194D01*
X592328Y-294237D01*
X592353Y-294277D01*
X592379Y-294310D01*
X592386Y-294317D01*
X592401Y-294332D01*
X592426Y-294354D01*
X592462Y-294379D01*
X592510Y-294401D01*
X592561Y-294423D01*
X592623Y-294437D01*
X592688Y-294445D01*
X592713D01*
X592743Y-294441D01*
X592775Y-294434D01*
X592819Y-294423D01*
X592863Y-294408D01*
X592906Y-294390D01*
X592950Y-294361D01*
X592957Y-294357D01*
X592976Y-294343D01*
X593001Y-294317D01*
X593034Y-294281D01*
X593070Y-294237D01*
X593110Y-294186D01*
X593147Y-294121D01*
X593183Y-294048D01*
Y-294044D01*
X593187Y-294037D01*
X593190Y-294026D01*
X593198Y-294011D01*
X593201Y-293990D01*
X593209Y-293964D01*
X593216Y-293935D01*
X593223Y-293899D01*
X593234Y-293859D01*
X593241Y-293815D01*
X593249Y-293768D01*
X593252Y-293717D01*
X593259Y-293658D01*
X593263Y-293600D01*
X593267Y-293535D01*
Y-293469D01*
X593263Y-293473D01*
X593249Y-293495D01*
X593223Y-293524D01*
X593190Y-293560D01*
X593154Y-293604D01*
X593107Y-293644D01*
X593056Y-293684D01*
X592997Y-293720D01*
X592994D01*
X592990Y-293724D01*
X592968Y-293735D01*
X592936Y-293746D01*
X592892Y-293764D01*
X592841Y-293778D01*
X592783Y-293789D01*
X592721Y-293800D01*
X592655Y-293804D01*
X592626D01*
X592604Y-293800D01*
X592575Y-293797D01*
X592546Y-293793D01*
X592510Y-293786D01*
X592473Y-293775D01*
X592389Y-293749D01*
X592346Y-293731D01*
X592302Y-293706D01*
X592259Y-293680D01*
X592211Y-293651D01*
X592168Y-293615D01*
X592128Y-293575D01*
X592124Y-293571D01*
X592117Y-293564D01*
X592106Y-293553D01*
X592095Y-293535D01*
X592076Y-293509D01*
X592058Y-293484D01*
X592040Y-293451D01*
X592018Y-293414D01*
X591996Y-293374D01*
X591978Y-293331D01*
X591960Y-293280D01*
X591942Y-293229D01*
X591931Y-293174D01*
X591920Y-293112D01*
X591913Y-293051D01*
X591909Y-292985D01*
Y-292981D01*
Y-292974D01*
Y-292963D01*
Y-292945D01*
X591913Y-292923D01*
Y-292901D01*
X591924Y-292843D01*
X591935Y-292774D01*
X591953Y-292701D01*
X591978Y-292621D01*
X592015Y-292545D01*
Y-292541D01*
X592018Y-292537D01*
X592026Y-292526D01*
X592033Y-292512D01*
X592055Y-292475D01*
X592087Y-292428D01*
X592128Y-292377D01*
X592175Y-292326D01*
X592233Y-292275D01*
X592295Y-292231D01*
X592299D01*
X592302Y-292228D01*
X592313Y-292221D01*
X592328Y-292217D01*
X592364Y-292199D01*
X592411Y-292180D01*
X592473Y-292159D01*
X592542Y-292144D01*
X592619Y-292130D01*
X592703Y-292126D01*
X592721D01*
X592739Y-292130D01*
D02*
G37*
G36*
X596918D02*
X596950D01*
X596990Y-292133D01*
X597034Y-292141D01*
X597085Y-292148D01*
X597191Y-292166D01*
X597300Y-292195D01*
X597409Y-292235D01*
X597460Y-292261D01*
X597511Y-292290D01*
X597515Y-292293D01*
X597522Y-292297D01*
X597537Y-292308D01*
X597551Y-292322D01*
X597573Y-292337D01*
X597598Y-292359D01*
X597627Y-292384D01*
X597657Y-292413D01*
X597686Y-292446D01*
X597718Y-292479D01*
X597784Y-292563D01*
X597846Y-292661D01*
X597900Y-292770D01*
Y-292774D01*
X597908Y-292785D01*
X597911Y-292803D01*
X597922Y-292825D01*
X597930Y-292854D01*
X597940Y-292890D01*
X597955Y-292930D01*
X597966Y-292974D01*
X597977Y-293021D01*
X597992Y-293076D01*
X598010Y-293189D01*
X598024Y-293316D01*
X598032Y-293447D01*
Y-293451D01*
Y-293465D01*
Y-293487D01*
X598028Y-293513D01*
Y-293549D01*
X598024Y-293586D01*
X598021Y-293633D01*
X598013Y-293680D01*
X597995Y-293786D01*
X597970Y-293902D01*
X597933Y-294019D01*
X597882Y-294132D01*
X597879Y-294135D01*
X597875Y-294146D01*
X597868Y-294161D01*
X597853Y-294179D01*
X597839Y-294204D01*
X597820Y-294233D01*
X597773Y-294299D01*
X597711Y-294372D01*
X597638Y-294445D01*
X597555Y-294517D01*
X597456Y-294579D01*
X597453Y-294583D01*
X597442Y-294587D01*
X597427Y-294594D01*
X597409Y-294605D01*
X597380Y-294616D01*
X597351Y-294627D01*
X597315Y-294641D01*
X597274Y-294656D01*
X597231Y-294670D01*
X597183Y-294685D01*
X597082Y-294707D01*
X596965Y-294725D01*
X596845Y-294732D01*
X596808D01*
X596783Y-294728D01*
X596750Y-294725D01*
X596710Y-294721D01*
X596670Y-294718D01*
X596623Y-294707D01*
X596525Y-294685D01*
X596415Y-294652D01*
X596361Y-294630D01*
X596310Y-294605D01*
X596259Y-294572D01*
X596208Y-294539D01*
X596204Y-294536D01*
X596197Y-294532D01*
X596182Y-294521D01*
X596164Y-294503D01*
X596146Y-294485D01*
X596121Y-294459D01*
X596095Y-294430D01*
X596066Y-294401D01*
X596037Y-294365D01*
X596008Y-294321D01*
X595975Y-294277D01*
X595946Y-294230D01*
X595920Y-294175D01*
X595891Y-294121D01*
X595869Y-294062D01*
X595848Y-293997D01*
X596175Y-293920D01*
Y-293924D01*
X596179Y-293931D01*
X596186Y-293946D01*
X596193Y-293964D01*
X596201Y-293986D01*
X596211Y-294015D01*
X596241Y-294073D01*
X596277Y-294139D01*
X596321Y-294204D01*
X596375Y-294266D01*
X596434Y-294321D01*
X596441Y-294328D01*
X596463Y-294343D01*
X596499Y-294361D01*
X596546Y-294386D01*
X596608Y-294408D01*
X596677Y-294430D01*
X596761Y-294445D01*
X596852Y-294448D01*
X596881D01*
X596900Y-294445D01*
X596925D01*
X596954Y-294441D01*
X597023Y-294430D01*
X597100Y-294415D01*
X597180Y-294390D01*
X597263Y-294354D01*
X597340Y-294306D01*
X597344D01*
X597347Y-294299D01*
X597373Y-294281D01*
X597405Y-294252D01*
X597445Y-294208D01*
X597493Y-294153D01*
X597537Y-294092D01*
X597577Y-294015D01*
X597613Y-293931D01*
Y-293928D01*
X597617Y-293920D01*
X597620Y-293910D01*
X597624Y-293891D01*
X597631Y-293869D01*
X597638Y-293844D01*
X597649Y-293782D01*
X597664Y-293709D01*
X597679Y-293629D01*
X597686Y-293542D01*
X597689Y-293447D01*
Y-293444D01*
Y-293433D01*
Y-293414D01*
Y-293393D01*
X597686Y-293367D01*
Y-293334D01*
X597682Y-293298D01*
X597679Y-293258D01*
X597668Y-293171D01*
X597649Y-293076D01*
X597627Y-292981D01*
X597598Y-292887D01*
Y-292883D01*
X597595Y-292876D01*
X597587Y-292865D01*
X597580Y-292847D01*
X597558Y-292803D01*
X597526Y-292752D01*
X597485Y-292694D01*
X597435Y-292632D01*
X597376Y-292577D01*
X597307Y-292526D01*
X597303D01*
X597296Y-292523D01*
X597285Y-292515D01*
X597271Y-292508D01*
X597253Y-292501D01*
X597231Y-292490D01*
X597180Y-292468D01*
X597114Y-292446D01*
X597042Y-292428D01*
X596961Y-292413D01*
X596878Y-292410D01*
X596852D01*
X596830Y-292413D01*
X596805D01*
X596779Y-292417D01*
X596714Y-292432D01*
X596637Y-292450D01*
X596561Y-292479D01*
X596481Y-292519D01*
X596441Y-292541D01*
X596405Y-292570D01*
X596401Y-292574D01*
X596397Y-292577D01*
X596386Y-292588D01*
X596372Y-292599D01*
X596357Y-292617D01*
X596339Y-292639D01*
X596317Y-292661D01*
X596299Y-292690D01*
X596277Y-292723D01*
X596252Y-292759D01*
X596230Y-292796D01*
X596208Y-292839D01*
X596190Y-292887D01*
X596172Y-292938D01*
X596153Y-292992D01*
X596139Y-293051D01*
X595804Y-292967D01*
Y-292963D01*
X595808Y-292949D01*
X595815Y-292927D01*
X595826Y-292898D01*
X595837Y-292865D01*
X595851Y-292825D01*
X595869Y-292781D01*
X595891Y-292734D01*
X595942Y-292632D01*
X596008Y-292530D01*
X596048Y-292479D01*
X596088Y-292428D01*
X596132Y-292384D01*
X596182Y-292341D01*
X596186Y-292337D01*
X596193Y-292330D01*
X596211Y-292322D01*
X596230Y-292308D01*
X596259Y-292290D01*
X596288Y-292271D01*
X596328Y-292253D01*
X596368Y-292235D01*
X596415Y-292213D01*
X596466Y-292195D01*
X596521Y-292177D01*
X596579Y-292159D01*
X596641Y-292144D01*
X596707Y-292137D01*
X596776Y-292130D01*
X596848Y-292126D01*
X596889D01*
X596918Y-292130D01*
D02*
G37*
G36*
X594756D02*
X594788Y-292133D01*
X594825Y-292137D01*
X594865Y-292144D01*
X594908Y-292155D01*
X595007Y-292180D01*
X595058Y-292199D01*
X595105Y-292217D01*
X595156Y-292242D01*
X595207Y-292271D01*
X595254Y-292304D01*
X595298Y-292344D01*
X595302Y-292348D01*
X595309Y-292355D01*
X595320Y-292366D01*
X595334Y-292384D01*
X595349Y-292406D01*
X595371Y-292432D01*
X595389Y-292461D01*
X595411Y-292497D01*
X595433Y-292534D01*
X595451Y-292577D01*
X595487Y-292668D01*
X595502Y-292723D01*
X595513Y-292777D01*
X595520Y-292836D01*
X595524Y-292894D01*
Y-292898D01*
Y-292905D01*
Y-292919D01*
X595520Y-292934D01*
Y-292956D01*
X595516Y-292981D01*
X595509Y-293040D01*
X595495Y-293105D01*
X595473Y-293171D01*
X595440Y-293240D01*
X595400Y-293305D01*
Y-293309D01*
X595393Y-293313D01*
X595378Y-293331D01*
X595349Y-293360D01*
X595309Y-293396D01*
X595258Y-293433D01*
X595196Y-293473D01*
X595127Y-293506D01*
X595043Y-293531D01*
X595047D01*
X595050Y-293535D01*
X595061Y-293538D01*
X595076Y-293546D01*
X595109Y-293560D01*
X595152Y-293582D01*
X595200Y-293611D01*
X595247Y-293648D01*
X595291Y-293688D01*
X595331Y-293731D01*
X595334Y-293739D01*
X595345Y-293753D01*
X595360Y-293782D01*
X595374Y-293819D01*
X595393Y-293866D01*
X595407Y-293920D01*
X595418Y-293982D01*
X595422Y-294048D01*
Y-294052D01*
Y-294059D01*
Y-294073D01*
X595418Y-294095D01*
X595414Y-294117D01*
X595411Y-294146D01*
X595396Y-294208D01*
X595374Y-294281D01*
X595338Y-294357D01*
X595316Y-294397D01*
X595291Y-294437D01*
X595258Y-294474D01*
X595225Y-294510D01*
X595222Y-294514D01*
X595214Y-294517D01*
X595203Y-294528D01*
X595189Y-294539D01*
X595170Y-294554D01*
X595145Y-294568D01*
X595116Y-294587D01*
X595087Y-294605D01*
X595050Y-294623D01*
X595010Y-294641D01*
X594967Y-294656D01*
X594919Y-294670D01*
X594817Y-294692D01*
X594759Y-294696D01*
X594701Y-294699D01*
X594668D01*
X594646Y-294696D01*
X594617Y-294692D01*
X594585Y-294689D01*
X594548Y-294685D01*
X594512Y-294674D01*
X594424Y-294652D01*
X594337Y-294619D01*
X594293Y-294598D01*
X594250Y-294572D01*
X594210Y-294539D01*
X594170Y-294507D01*
X594166Y-294503D01*
X594162Y-294499D01*
X594151Y-294488D01*
X594137Y-294474D01*
X594122Y-294452D01*
X594104Y-294430D01*
X594068Y-294375D01*
X594031Y-294306D01*
X593998Y-294226D01*
X593973Y-294135D01*
X593969Y-294088D01*
X593966Y-294037D01*
Y-294033D01*
Y-294030D01*
Y-294008D01*
X593969Y-293975D01*
X593977Y-293935D01*
X593988Y-293884D01*
X594006Y-293833D01*
X594028Y-293782D01*
X594060Y-293731D01*
X594064Y-293724D01*
X594078Y-293709D01*
X594100Y-293688D01*
X594130Y-293658D01*
X594170Y-293626D01*
X594217Y-293593D01*
X594271Y-293560D01*
X594337Y-293531D01*
X594333D01*
X594326Y-293527D01*
X594315Y-293524D01*
X594301Y-293516D01*
X594257Y-293498D01*
X594206Y-293473D01*
X594151Y-293436D01*
X594093Y-293396D01*
X594038Y-293345D01*
X593988Y-293287D01*
Y-293284D01*
X593984Y-293280D01*
X593969Y-293258D01*
X593948Y-293222D01*
X593926Y-293174D01*
X593904Y-293116D01*
X593882Y-293047D01*
X593867Y-292970D01*
X593864Y-292887D01*
Y-292883D01*
Y-292872D01*
Y-292854D01*
X593867Y-292832D01*
X593871Y-292807D01*
X593875Y-292774D01*
X593882Y-292738D01*
X593893Y-292697D01*
X593918Y-292614D01*
X593936Y-292566D01*
X593962Y-292523D01*
X593988Y-292475D01*
X594017Y-292432D01*
X594053Y-292388D01*
X594093Y-292344D01*
X594097Y-292341D01*
X594104Y-292333D01*
X594115Y-292322D01*
X594133Y-292312D01*
X594159Y-292293D01*
X594184Y-292275D01*
X594217Y-292257D01*
X594253Y-292235D01*
X594293Y-292213D01*
X594341Y-292195D01*
X594392Y-292177D01*
X594443Y-292159D01*
X594501Y-292148D01*
X594563Y-292137D01*
X594625Y-292130D01*
X594694Y-292126D01*
X594730D01*
X594756Y-292130D01*
D02*
G37*
G36*
X607412Y-261027D02*
X607438D01*
X607467Y-261031D01*
X607536Y-261045D01*
X607612Y-261064D01*
X607692Y-261093D01*
X607773Y-261133D01*
X607813Y-261158D01*
X607849Y-261187D01*
X607853Y-261191D01*
X607856Y-261195D01*
X607867Y-261206D01*
X607878Y-261216D01*
X607893Y-261235D01*
X607911Y-261257D01*
X607947Y-261308D01*
X607984Y-261373D01*
X608020Y-261453D01*
X608049Y-261544D01*
X608071Y-261650D01*
X607773Y-261675D01*
Y-261671D01*
X607769Y-261664D01*
Y-261657D01*
X607765Y-261642D01*
X607754Y-261602D01*
X607740Y-261559D01*
X607722Y-261508D01*
X607696Y-261457D01*
X607667Y-261409D01*
X607631Y-261369D01*
X607627Y-261366D01*
X607612Y-261355D01*
X607587Y-261340D01*
X607558Y-261326D01*
X607518Y-261308D01*
X607470Y-261293D01*
X607416Y-261282D01*
X607358Y-261278D01*
X607332D01*
X607307Y-261282D01*
X607274Y-261286D01*
X607234Y-261293D01*
X607194Y-261304D01*
X607150Y-261318D01*
X607110Y-261340D01*
X607106Y-261344D01*
X607092Y-261351D01*
X607070Y-261366D01*
X607048Y-261388D01*
X607019Y-261413D01*
X606990Y-261442D01*
X606961Y-261475D01*
X606932Y-261515D01*
X606928Y-261519D01*
X606921Y-261537D01*
X606906Y-261562D01*
X606892Y-261595D01*
X606874Y-261639D01*
X606855Y-261690D01*
X606837Y-261748D01*
X606819Y-261813D01*
Y-261817D01*
X606815Y-261821D01*
Y-261832D01*
X606812Y-261846D01*
X606804Y-261883D01*
X606793Y-261930D01*
X606786Y-261988D01*
X606779Y-262050D01*
X606775Y-262119D01*
X606772Y-262192D01*
Y-262196D01*
Y-262207D01*
Y-262225D01*
Y-262254D01*
X606775Y-262247D01*
X606790Y-262228D01*
X606812Y-262203D01*
X606837Y-262167D01*
X606874Y-262130D01*
X606917Y-262090D01*
X606968Y-262050D01*
X607026Y-262014D01*
X607034Y-262010D01*
X607056Y-261999D01*
X607088Y-261984D01*
X607128Y-261970D01*
X607183Y-261952D01*
X607241Y-261937D01*
X607307Y-261926D01*
X607376Y-261923D01*
X607405D01*
X607427Y-261926D01*
X607456Y-261930D01*
X607485Y-261934D01*
X607521Y-261941D01*
X607558Y-261952D01*
X607642Y-261977D01*
X607685Y-261996D01*
X607729Y-262017D01*
X607776Y-262043D01*
X607820Y-262076D01*
X607864Y-262108D01*
X607904Y-262148D01*
X607907Y-262152D01*
X607914Y-262159D01*
X607922Y-262170D01*
X607936Y-262188D01*
X607955Y-262214D01*
X607973Y-262239D01*
X607991Y-262272D01*
X608009Y-262309D01*
X608031Y-262349D01*
X608049Y-262392D01*
X608067Y-262443D01*
X608086Y-262494D01*
X608100Y-262552D01*
X608107Y-262614D01*
X608115Y-262676D01*
X608118Y-262745D01*
Y-262749D01*
Y-262764D01*
Y-262782D01*
X608115Y-262807D01*
X608111Y-262840D01*
X608107Y-262880D01*
X608100Y-262920D01*
X608089Y-262967D01*
X608064Y-263062D01*
X608046Y-263113D01*
X608024Y-263168D01*
X607998Y-263218D01*
X607966Y-263266D01*
X607933Y-263317D01*
X607893Y-263361D01*
X607889Y-263364D01*
X607882Y-263371D01*
X607871Y-263382D01*
X607853Y-263397D01*
X607831Y-263415D01*
X607802Y-263437D01*
X607773Y-263455D01*
X607736Y-263481D01*
X607700Y-263502D01*
X607656Y-263521D01*
X607558Y-263561D01*
X607507Y-263575D01*
X607449Y-263586D01*
X607390Y-263593D01*
X607329Y-263597D01*
X607303D01*
X607285Y-263593D01*
X607267D01*
X607241Y-263590D01*
X607179Y-263579D01*
X607110Y-263564D01*
X607034Y-263539D01*
X606957Y-263506D01*
X606881Y-263462D01*
X606877D01*
X606874Y-263455D01*
X606863Y-263448D01*
X606848Y-263437D01*
X606812Y-263408D01*
X606764Y-263368D01*
X606717Y-263313D01*
X606662Y-263248D01*
X606615Y-263171D01*
X606571Y-263084D01*
Y-263080D01*
X606568Y-263073D01*
X606561Y-263058D01*
X606553Y-263040D01*
X606546Y-263015D01*
X606535Y-262982D01*
X606528Y-262946D01*
X606517Y-262906D01*
X606506Y-262858D01*
X606495Y-262804D01*
X606488Y-262745D01*
X606480Y-262683D01*
X606473Y-262614D01*
X606466Y-262542D01*
X606462Y-262461D01*
Y-262378D01*
Y-262374D01*
Y-262356D01*
Y-262330D01*
Y-262298D01*
X606466Y-262258D01*
Y-262210D01*
X606469Y-262156D01*
X606477Y-262101D01*
X606488Y-261977D01*
X606506Y-261846D01*
X606531Y-261722D01*
X606550Y-261661D01*
X606568Y-261606D01*
Y-261602D01*
X606571Y-261595D01*
X606579Y-261580D01*
X606586Y-261559D01*
X606597Y-261537D01*
X606611Y-261508D01*
X606648Y-261446D01*
X606692Y-261377D01*
X606742Y-261304D01*
X606808Y-261235D01*
X606881Y-261173D01*
X606884D01*
X606892Y-261165D01*
X606903Y-261158D01*
X606917Y-261151D01*
X606939Y-261140D01*
X606961Y-261125D01*
X606990Y-261111D01*
X607019Y-261100D01*
X607088Y-261071D01*
X607172Y-261045D01*
X607263Y-261031D01*
X607365Y-261024D01*
X607394D01*
X607412Y-261027D01*
D02*
G37*
G36*
X609516D02*
X609549D01*
X609589Y-261031D01*
X609633Y-261038D01*
X609684Y-261045D01*
X609789Y-261064D01*
X609898Y-261093D01*
X610007Y-261133D01*
X610058Y-261158D01*
X610110Y-261187D01*
X610113Y-261191D01*
X610120Y-261195D01*
X610135Y-261206D01*
X610149Y-261220D01*
X610171Y-261235D01*
X610197Y-261257D01*
X610226Y-261282D01*
X610255Y-261311D01*
X610284Y-261344D01*
X610317Y-261377D01*
X610382Y-261460D01*
X610444Y-261559D01*
X610499Y-261668D01*
Y-261671D01*
X610506Y-261682D01*
X610510Y-261701D01*
X610521Y-261722D01*
X610528Y-261752D01*
X610539Y-261788D01*
X610554Y-261828D01*
X610565Y-261872D01*
X610575Y-261919D01*
X610590Y-261974D01*
X610608Y-262087D01*
X610623Y-262214D01*
X610630Y-262345D01*
Y-262349D01*
Y-262363D01*
Y-262385D01*
X610626Y-262410D01*
Y-262447D01*
X610623Y-262483D01*
X610619Y-262530D01*
X610612Y-262578D01*
X610594Y-262683D01*
X610568Y-262800D01*
X610532Y-262916D01*
X610481Y-263029D01*
X610477Y-263033D01*
X610473Y-263044D01*
X610466Y-263058D01*
X610452Y-263076D01*
X610437Y-263102D01*
X610419Y-263131D01*
X610371Y-263197D01*
X610310Y-263269D01*
X610237Y-263342D01*
X610153Y-263415D01*
X610055Y-263477D01*
X610051Y-263481D01*
X610040Y-263484D01*
X610026Y-263492D01*
X610007Y-263502D01*
X609978Y-263513D01*
X609949Y-263524D01*
X609913Y-263539D01*
X609873Y-263553D01*
X609829Y-263568D01*
X609782Y-263582D01*
X609680Y-263604D01*
X609563Y-263623D01*
X609443Y-263630D01*
X609407D01*
X609381Y-263626D01*
X609349Y-263623D01*
X609309Y-263619D01*
X609269Y-263615D01*
X609221Y-263604D01*
X609123Y-263582D01*
X609014Y-263550D01*
X608959Y-263528D01*
X608908Y-263502D01*
X608857Y-263470D01*
X608806Y-263437D01*
X608803Y-263433D01*
X608795Y-263430D01*
X608781Y-263419D01*
X608763Y-263401D01*
X608744Y-263382D01*
X608719Y-263357D01*
X608694Y-263328D01*
X608664Y-263299D01*
X608635Y-263262D01*
X608606Y-263218D01*
X608573Y-263175D01*
X608544Y-263127D01*
X608519Y-263073D01*
X608490Y-263018D01*
X608468Y-262960D01*
X608446Y-262895D01*
X608774Y-262818D01*
Y-262822D01*
X608777Y-262829D01*
X608784Y-262844D01*
X608792Y-262862D01*
X608799Y-262884D01*
X608810Y-262913D01*
X608839Y-262971D01*
X608876Y-263036D01*
X608919Y-263102D01*
X608974Y-263164D01*
X609032Y-263218D01*
X609039Y-263226D01*
X609061Y-263240D01*
X609097Y-263259D01*
X609145Y-263284D01*
X609207Y-263306D01*
X609276Y-263328D01*
X609360Y-263342D01*
X609451Y-263346D01*
X609480D01*
X609498Y-263342D01*
X609523D01*
X609552Y-263339D01*
X609622Y-263328D01*
X609698Y-263313D01*
X609778Y-263288D01*
X609862Y-263251D01*
X609938Y-263204D01*
X609942D01*
X609946Y-263197D01*
X609971Y-263178D01*
X610004Y-263149D01*
X610044Y-263106D01*
X610091Y-263051D01*
X610135Y-262989D01*
X610175Y-262913D01*
X610211Y-262829D01*
Y-262825D01*
X610215Y-262818D01*
X610219Y-262807D01*
X610222Y-262789D01*
X610230Y-262767D01*
X610237Y-262742D01*
X610248Y-262680D01*
X610262Y-262607D01*
X610277Y-262527D01*
X610284Y-262440D01*
X610288Y-262345D01*
Y-262341D01*
Y-262330D01*
Y-262312D01*
Y-262290D01*
X610284Y-262265D01*
Y-262232D01*
X610281Y-262196D01*
X610277Y-262156D01*
X610266Y-262068D01*
X610248Y-261974D01*
X610226Y-261879D01*
X610197Y-261784D01*
Y-261781D01*
X610193Y-261773D01*
X610186Y-261762D01*
X610179Y-261744D01*
X610157Y-261701D01*
X610124Y-261650D01*
X610084Y-261591D01*
X610033Y-261530D01*
X609975Y-261475D01*
X609906Y-261424D01*
X609902D01*
X609895Y-261420D01*
X609884Y-261413D01*
X609869Y-261406D01*
X609851Y-261399D01*
X609829Y-261388D01*
X609778Y-261366D01*
X609713Y-261344D01*
X609640Y-261326D01*
X609560Y-261311D01*
X609476Y-261308D01*
X609451D01*
X609429Y-261311D01*
X609403D01*
X609378Y-261315D01*
X609312Y-261329D01*
X609236Y-261348D01*
X609159Y-261377D01*
X609079Y-261417D01*
X609039Y-261438D01*
X609003Y-261468D01*
X608999Y-261471D01*
X608996Y-261475D01*
X608985Y-261486D01*
X608970Y-261497D01*
X608956Y-261515D01*
X608937Y-261537D01*
X608916Y-261559D01*
X608897Y-261588D01*
X608876Y-261621D01*
X608850Y-261657D01*
X608828Y-261693D01*
X608806Y-261737D01*
X608788Y-261784D01*
X608770Y-261835D01*
X608752Y-261890D01*
X608737Y-261948D01*
X608402Y-261864D01*
Y-261861D01*
X608406Y-261846D01*
X608413Y-261824D01*
X608424Y-261795D01*
X608435Y-261762D01*
X608450Y-261722D01*
X608468Y-261679D01*
X608490Y-261631D01*
X608541Y-261530D01*
X608606Y-261428D01*
X608646Y-261377D01*
X608686Y-261326D01*
X608730Y-261282D01*
X608781Y-261238D01*
X608784Y-261235D01*
X608792Y-261227D01*
X608810Y-261220D01*
X608828Y-261206D01*
X608857Y-261187D01*
X608886Y-261169D01*
X608926Y-261151D01*
X608966Y-261133D01*
X609014Y-261111D01*
X609065Y-261093D01*
X609119Y-261074D01*
X609178Y-261056D01*
X609239Y-261042D01*
X609305Y-261034D01*
X609374Y-261027D01*
X609447Y-261024D01*
X609487D01*
X609516Y-261027D01*
D02*
G37*
G36*
X605305Y-263036D02*
X605308Y-263033D01*
X605327Y-263018D01*
X605348Y-262997D01*
X605385Y-262971D01*
X605425Y-262938D01*
X605476Y-262902D01*
X605534Y-262862D01*
X605599Y-262822D01*
X605603D01*
X605607Y-262818D01*
X605629Y-262804D01*
X605665Y-262785D01*
X605709Y-262764D01*
X605760Y-262738D01*
X605814Y-262713D01*
X605869Y-262687D01*
X605923Y-262665D01*
Y-262964D01*
X605920D01*
X605912Y-262971D01*
X605898Y-262975D01*
X605880Y-262986D01*
X605858Y-262997D01*
X605832Y-263011D01*
X605771Y-263047D01*
X605698Y-263088D01*
X605625Y-263138D01*
X605548Y-263197D01*
X605472Y-263259D01*
X605469Y-263262D01*
X605465Y-263266D01*
X605454Y-263277D01*
X605439Y-263288D01*
X605407Y-263324D01*
X605363Y-263368D01*
X605319Y-263419D01*
X605272Y-263477D01*
X605232Y-263535D01*
X605195Y-263597D01*
X604995D01*
Y-261067D01*
X605305D01*
Y-263036D01*
D02*
G37*
G36*
X341350Y-291807D02*
Y-291810D01*
Y-291825D01*
Y-291843D01*
Y-291869D01*
X341347Y-291901D01*
Y-291938D01*
X341343Y-291982D01*
X341339Y-292025D01*
X341328Y-292124D01*
X341314Y-292226D01*
X341292Y-292324D01*
X341277Y-292371D01*
X341263Y-292415D01*
Y-292418D01*
X341259Y-292426D01*
X341252Y-292437D01*
X341245Y-292451D01*
X341223Y-292491D01*
X341190Y-292542D01*
X341146Y-292600D01*
X341095Y-292659D01*
X341030Y-292721D01*
X340950Y-292775D01*
X340946D01*
X340939Y-292782D01*
X340928Y-292786D01*
X340910Y-292797D01*
X340888Y-292808D01*
X340859Y-292819D01*
X340830Y-292830D01*
X340793Y-292844D01*
X340753Y-292859D01*
X340709Y-292870D01*
X340662Y-292881D01*
X340608Y-292892D01*
X340553Y-292899D01*
X340495Y-292906D01*
X340364Y-292913D01*
X340331D01*
X340305Y-292910D01*
X340276D01*
X340240Y-292906D01*
X340200Y-292902D01*
X340160Y-292899D01*
X340069Y-292884D01*
X339971Y-292863D01*
X339876Y-292833D01*
X339785Y-292793D01*
X339781D01*
X339774Y-292786D01*
X339763Y-292779D01*
X339749Y-292772D01*
X339709Y-292742D01*
X339661Y-292702D01*
X339607Y-292651D01*
X339556Y-292593D01*
X339505Y-292520D01*
X339465Y-292440D01*
Y-292437D01*
X339461Y-292429D01*
X339457Y-292415D01*
X339450Y-292397D01*
X339443Y-292375D01*
X339436Y-292346D01*
X339425Y-292313D01*
X339417Y-292273D01*
X339410Y-292229D01*
X339399Y-292182D01*
X339392Y-292131D01*
X339385Y-292076D01*
X339377Y-292014D01*
X339374Y-291949D01*
X339370Y-291880D01*
Y-291807D01*
Y-290351D01*
X339705D01*
Y-291807D01*
Y-291810D01*
Y-291821D01*
Y-291840D01*
Y-291862D01*
X339709Y-291887D01*
Y-291920D01*
X339712Y-291989D01*
X339720Y-292069D01*
X339730Y-292149D01*
X339745Y-292226D01*
X339752Y-292258D01*
X339763Y-292291D01*
X339767Y-292298D01*
X339774Y-292317D01*
X339792Y-292342D01*
X339814Y-292378D01*
X339840Y-292415D01*
X339876Y-292455D01*
X339920Y-292495D01*
X339971Y-292528D01*
X339978Y-292531D01*
X339996Y-292542D01*
X340029Y-292553D01*
X340073Y-292568D01*
X340124Y-292586D01*
X340189Y-292597D01*
X340258Y-292608D01*
X340335Y-292611D01*
X340371D01*
X340393Y-292608D01*
X340426D01*
X340458Y-292604D01*
X340539Y-292589D01*
X340626Y-292571D01*
X340709Y-292542D01*
X340790Y-292502D01*
X340826Y-292477D01*
X340859Y-292447D01*
X340862Y-292444D01*
X340866Y-292440D01*
X340873Y-292429D01*
X340884Y-292415D01*
X340895Y-292393D01*
X340910Y-292371D01*
X340924Y-292338D01*
X340939Y-292306D01*
X340953Y-292266D01*
X340964Y-292218D01*
X340979Y-292164D01*
X340990Y-292105D01*
X341001Y-292040D01*
X341008Y-291971D01*
X341015Y-291891D01*
Y-291807D01*
Y-290351D01*
X341350D01*
Y-291807D01*
D02*
G37*
G36*
X344903Y-292870D02*
X344593D01*
Y-290900D01*
X344590Y-290904D01*
X344572Y-290919D01*
X344550Y-290941D01*
X344513Y-290966D01*
X344473Y-290999D01*
X344422Y-291035D01*
X344364Y-291075D01*
X344299Y-291115D01*
X344295D01*
X344291Y-291119D01*
X344269Y-291133D01*
X344233Y-291152D01*
X344189Y-291174D01*
X344138Y-291199D01*
X344084Y-291225D01*
X344029Y-291250D01*
X343975Y-291272D01*
Y-290973D01*
X343978D01*
X343986Y-290966D01*
X344000Y-290962D01*
X344018Y-290951D01*
X344040Y-290941D01*
X344066Y-290926D01*
X344127Y-290890D01*
X344200Y-290850D01*
X344273Y-290799D01*
X344350Y-290740D01*
X344426Y-290679D01*
X344430Y-290675D01*
X344433Y-290671D01*
X344444Y-290660D01*
X344459Y-290649D01*
X344492Y-290613D01*
X344535Y-290569D01*
X344579Y-290518D01*
X344626Y-290460D01*
X344666Y-290402D01*
X344703Y-290340D01*
X344903D01*
Y-292870D01*
D02*
G37*
G36*
X342675Y-290344D02*
X342704Y-290347D01*
X342741Y-290351D01*
X342781Y-290358D01*
X342821Y-290365D01*
X342915Y-290391D01*
X343010Y-290427D01*
X343057Y-290449D01*
X343105Y-290475D01*
X343148Y-290507D01*
X343188Y-290544D01*
X343192Y-290547D01*
X343199Y-290551D01*
X343207Y-290566D01*
X343221Y-290580D01*
X343239Y-290598D01*
X343257Y-290624D01*
X343276Y-290649D01*
X343298Y-290682D01*
X343334Y-290751D01*
X343370Y-290839D01*
X343385Y-290882D01*
X343392Y-290933D01*
X343400Y-290984D01*
X343403Y-291039D01*
Y-291046D01*
Y-291064D01*
X343400Y-291093D01*
X343396Y-291133D01*
X343389Y-291177D01*
X343374Y-291228D01*
X343359Y-291283D01*
X343338Y-291337D01*
X343334Y-291345D01*
X343327Y-291363D01*
X343312Y-291392D01*
X343290Y-291432D01*
X343261Y-291476D01*
X343225Y-291530D01*
X343181Y-291585D01*
X343130Y-291647D01*
X343123Y-291654D01*
X343105Y-291676D01*
X343087Y-291694D01*
X343068Y-291712D01*
X343046Y-291734D01*
X343017Y-291763D01*
X342988Y-291792D01*
X342952Y-291825D01*
X342915Y-291862D01*
X342872Y-291901D01*
X342824Y-291942D01*
X342773Y-291989D01*
X342715Y-292036D01*
X342657Y-292087D01*
X342653Y-292091D01*
X342646Y-292098D01*
X342632Y-292109D01*
X342613Y-292124D01*
X342591Y-292145D01*
X342566Y-292167D01*
X342508Y-292215D01*
X342446Y-292269D01*
X342388Y-292324D01*
X342337Y-292371D01*
X342315Y-292389D01*
X342297Y-292407D01*
X342293Y-292411D01*
X342282Y-292422D01*
X342267Y-292437D01*
X342249Y-292458D01*
X342231Y-292484D01*
X342209Y-292509D01*
X342165Y-292571D01*
X343407D01*
Y-292870D01*
X341736D01*
Y-292866D01*
Y-292852D01*
Y-292830D01*
X341740Y-292801D01*
X341743Y-292768D01*
X341751Y-292731D01*
X341758Y-292695D01*
X341772Y-292655D01*
Y-292651D01*
X341776Y-292648D01*
X341783Y-292626D01*
X341798Y-292593D01*
X341820Y-292549D01*
X341849Y-292498D01*
X341885Y-292440D01*
X341925Y-292382D01*
X341976Y-292320D01*
Y-292317D01*
X341984Y-292313D01*
X342002Y-292291D01*
X342035Y-292258D01*
X342082Y-292211D01*
X342136Y-292156D01*
X342206Y-292091D01*
X342289Y-292018D01*
X342380Y-291942D01*
X342384Y-291938D01*
X342399Y-291927D01*
X342420Y-291909D01*
X342446Y-291887D01*
X342479Y-291858D01*
X342519Y-291825D01*
X342559Y-291789D01*
X342606Y-291749D01*
X342697Y-291661D01*
X342788Y-291574D01*
X342832Y-291530D01*
X342872Y-291487D01*
X342908Y-291446D01*
X342937Y-291406D01*
Y-291403D01*
X342945Y-291399D01*
X342952Y-291388D01*
X342959Y-291374D01*
X342985Y-291334D01*
X343014Y-291286D01*
X343039Y-291228D01*
X343065Y-291166D01*
X343079Y-291097D01*
X343087Y-291032D01*
Y-291028D01*
Y-291024D01*
X343083Y-291002D01*
X343079Y-290966D01*
X343068Y-290926D01*
X343054Y-290875D01*
X343028Y-290824D01*
X342996Y-290773D01*
X342952Y-290722D01*
X342945Y-290715D01*
X342926Y-290700D01*
X342901Y-290682D01*
X342861Y-290657D01*
X342810Y-290635D01*
X342752Y-290613D01*
X342682Y-290598D01*
X342606Y-290595D01*
X342584D01*
X342570Y-290598D01*
X342526Y-290602D01*
X342475Y-290613D01*
X342420Y-290628D01*
X342358Y-290653D01*
X342300Y-290686D01*
X342246Y-290729D01*
X342238Y-290737D01*
X342224Y-290755D01*
X342202Y-290784D01*
X342180Y-290828D01*
X342155Y-290879D01*
X342133Y-290944D01*
X342118Y-291017D01*
X342111Y-291101D01*
X341794Y-291068D01*
Y-291064D01*
X341798Y-291053D01*
Y-291035D01*
X341802Y-291010D01*
X341809Y-290981D01*
X341816Y-290948D01*
X341827Y-290908D01*
X341838Y-290868D01*
X341867Y-290780D01*
X341911Y-290693D01*
X341936Y-290649D01*
X341969Y-290606D01*
X342002Y-290566D01*
X342038Y-290529D01*
X342042Y-290526D01*
X342049Y-290522D01*
X342060Y-290511D01*
X342078Y-290500D01*
X342100Y-290486D01*
X342126Y-290471D01*
X342155Y-290453D01*
X342191Y-290435D01*
X342231Y-290416D01*
X342275Y-290398D01*
X342322Y-290384D01*
X342373Y-290369D01*
X342428Y-290358D01*
X342486Y-290347D01*
X342548Y-290344D01*
X342613Y-290340D01*
X342650D01*
X342675Y-290344D01*
D02*
G37*
G36*
X322453Y-292594D02*
Y-292598D01*
Y-292613D01*
Y-292631D01*
Y-292656D01*
X322449Y-292689D01*
Y-292725D01*
X322445Y-292769D01*
X322442Y-292813D01*
X322431Y-292911D01*
X322416Y-293013D01*
X322394Y-293111D01*
X322380Y-293159D01*
X322365Y-293202D01*
Y-293206D01*
X322361Y-293213D01*
X322354Y-293224D01*
X322347Y-293239D01*
X322325Y-293279D01*
X322292Y-293330D01*
X322249Y-293388D01*
X322198Y-293446D01*
X322132Y-293508D01*
X322052Y-293563D01*
X322048D01*
X322041Y-293570D01*
X322030Y-293573D01*
X322012Y-293584D01*
X321990Y-293595D01*
X321961Y-293606D01*
X321932Y-293617D01*
X321896Y-293632D01*
X321856Y-293646D01*
X321812Y-293657D01*
X321765Y-293668D01*
X321710Y-293679D01*
X321655Y-293686D01*
X321597Y-293694D01*
X321466Y-293701D01*
X321433D01*
X321408Y-293697D01*
X321379D01*
X321342Y-293694D01*
X321302Y-293690D01*
X321262Y-293686D01*
X321171Y-293672D01*
X321073Y-293650D01*
X320978Y-293621D01*
X320887Y-293581D01*
X320884D01*
X320876Y-293573D01*
X320866Y-293566D01*
X320851Y-293559D01*
X320811Y-293530D01*
X320764Y-293490D01*
X320709Y-293439D01*
X320658Y-293380D01*
X320607Y-293308D01*
X320567Y-293228D01*
Y-293224D01*
X320563Y-293217D01*
X320560Y-293202D01*
X320552Y-293184D01*
X320545Y-293162D01*
X320538Y-293133D01*
X320527Y-293100D01*
X320520Y-293060D01*
X320512Y-293017D01*
X320501Y-292969D01*
X320494Y-292918D01*
X320487Y-292864D01*
X320480Y-292802D01*
X320476Y-292736D01*
X320472Y-292667D01*
Y-292594D01*
Y-291138D01*
X320807D01*
Y-292594D01*
Y-292598D01*
Y-292609D01*
Y-292627D01*
Y-292649D01*
X320811Y-292674D01*
Y-292707D01*
X320815Y-292776D01*
X320822Y-292856D01*
X320833Y-292936D01*
X320847Y-293013D01*
X320855Y-293046D01*
X320866Y-293078D01*
X320869Y-293086D01*
X320876Y-293104D01*
X320895Y-293129D01*
X320917Y-293166D01*
X320942Y-293202D01*
X320978Y-293242D01*
X321022Y-293282D01*
X321073Y-293315D01*
X321080Y-293319D01*
X321098Y-293330D01*
X321131Y-293340D01*
X321175Y-293355D01*
X321226Y-293373D01*
X321291Y-293384D01*
X321361Y-293395D01*
X321437Y-293399D01*
X321473D01*
X321495Y-293395D01*
X321528D01*
X321561Y-293391D01*
X321641Y-293377D01*
X321728Y-293359D01*
X321812Y-293330D01*
X321892Y-293289D01*
X321928Y-293264D01*
X321961Y-293235D01*
X321965Y-293231D01*
X321968Y-293228D01*
X321976Y-293217D01*
X321987Y-293202D01*
X321998Y-293180D01*
X322012Y-293159D01*
X322027Y-293126D01*
X322041Y-293093D01*
X322056Y-293053D01*
X322067Y-293006D01*
X322081Y-292951D01*
X322092Y-292893D01*
X322103Y-292827D01*
X322110Y-292758D01*
X322118Y-292678D01*
Y-292594D01*
Y-291138D01*
X322453D01*
Y-292594D01*
D02*
G37*
G36*
X325736Y-291131D02*
X325765Y-291135D01*
X325801Y-291138D01*
X325841Y-291146D01*
X325881Y-291153D01*
X325976Y-291178D01*
X326071Y-291215D01*
X326118Y-291237D01*
X326165Y-291262D01*
X326209Y-291295D01*
X326249Y-291331D01*
X326253Y-291335D01*
X326260Y-291338D01*
X326267Y-291353D01*
X326282Y-291368D01*
X326300Y-291386D01*
X326318Y-291411D01*
X326336Y-291437D01*
X326358Y-291470D01*
X326395Y-291539D01*
X326431Y-291626D01*
X326446Y-291670D01*
X326453Y-291721D01*
X326460Y-291772D01*
X326464Y-291826D01*
Y-291833D01*
Y-291852D01*
X326460Y-291881D01*
X326457Y-291921D01*
X326449Y-291965D01*
X326435Y-292016D01*
X326420Y-292070D01*
X326398Y-292125D01*
X326395Y-292132D01*
X326387Y-292150D01*
X326373Y-292179D01*
X326351Y-292219D01*
X326322Y-292263D01*
X326286Y-292318D01*
X326242Y-292372D01*
X326191Y-292434D01*
X326184Y-292441D01*
X326165Y-292463D01*
X326147Y-292481D01*
X326129Y-292500D01*
X326107Y-292522D01*
X326078Y-292551D01*
X326049Y-292580D01*
X326012Y-292613D01*
X325976Y-292649D01*
X325932Y-292689D01*
X325885Y-292729D01*
X325834Y-292776D01*
X325776Y-292824D01*
X325718Y-292875D01*
X325714Y-292878D01*
X325707Y-292885D01*
X325692Y-292896D01*
X325674Y-292911D01*
X325652Y-292933D01*
X325627Y-292955D01*
X325568Y-293002D01*
X325506Y-293057D01*
X325448Y-293111D01*
X325397Y-293159D01*
X325376Y-293177D01*
X325357Y-293195D01*
X325354Y-293198D01*
X325343Y-293209D01*
X325328Y-293224D01*
X325310Y-293246D01*
X325292Y-293271D01*
X325270Y-293297D01*
X325226Y-293359D01*
X326467D01*
Y-293657D01*
X324797D01*
Y-293653D01*
Y-293639D01*
Y-293617D01*
X324800Y-293588D01*
X324804Y-293555D01*
X324811Y-293519D01*
X324819Y-293482D01*
X324833Y-293442D01*
Y-293439D01*
X324837Y-293435D01*
X324844Y-293413D01*
X324859Y-293380D01*
X324880Y-293337D01*
X324909Y-293286D01*
X324946Y-293228D01*
X324986Y-293169D01*
X325037Y-293108D01*
Y-293104D01*
X325044Y-293100D01*
X325062Y-293078D01*
X325095Y-293046D01*
X325143Y-292998D01*
X325197Y-292944D01*
X325266Y-292878D01*
X325350Y-292805D01*
X325441Y-292729D01*
X325445Y-292725D01*
X325459Y-292714D01*
X325481Y-292696D01*
X325506Y-292674D01*
X325539Y-292645D01*
X325579Y-292613D01*
X325619Y-292576D01*
X325667Y-292536D01*
X325758Y-292449D01*
X325849Y-292361D01*
X325892Y-292318D01*
X325932Y-292274D01*
X325969Y-292234D01*
X325998Y-292194D01*
Y-292190D01*
X326005Y-292187D01*
X326012Y-292176D01*
X326020Y-292161D01*
X326045Y-292121D01*
X326074Y-292074D01*
X326100Y-292016D01*
X326125Y-291954D01*
X326140Y-291884D01*
X326147Y-291819D01*
Y-291815D01*
Y-291812D01*
X326144Y-291790D01*
X326140Y-291753D01*
X326129Y-291713D01*
X326114Y-291662D01*
X326089Y-291612D01*
X326056Y-291561D01*
X326012Y-291510D01*
X326005Y-291502D01*
X325987Y-291488D01*
X325961Y-291470D01*
X325922Y-291444D01*
X325870Y-291422D01*
X325812Y-291400D01*
X325743Y-291386D01*
X325667Y-291382D01*
X325645D01*
X325630Y-291386D01*
X325587Y-291389D01*
X325536Y-291400D01*
X325481Y-291415D01*
X325419Y-291440D01*
X325361Y-291473D01*
X325306Y-291517D01*
X325299Y-291524D01*
X325285Y-291542D01*
X325263Y-291571D01*
X325241Y-291615D01*
X325215Y-291666D01*
X325194Y-291732D01*
X325179Y-291804D01*
X325172Y-291888D01*
X324855Y-291855D01*
Y-291852D01*
X324859Y-291841D01*
Y-291823D01*
X324862Y-291797D01*
X324869Y-291768D01*
X324877Y-291735D01*
X324888Y-291695D01*
X324899Y-291655D01*
X324928Y-291568D01*
X324971Y-291480D01*
X324997Y-291437D01*
X325030Y-291393D01*
X325062Y-291353D01*
X325099Y-291317D01*
X325102Y-291313D01*
X325110Y-291309D01*
X325121Y-291298D01*
X325139Y-291287D01*
X325161Y-291273D01*
X325186Y-291258D01*
X325215Y-291240D01*
X325252Y-291222D01*
X325292Y-291204D01*
X325335Y-291186D01*
X325383Y-291171D01*
X325434Y-291157D01*
X325488Y-291146D01*
X325547Y-291135D01*
X325608Y-291131D01*
X325674Y-291127D01*
X325710D01*
X325736Y-291131D01*
D02*
G37*
G36*
X323778D02*
X323807Y-291135D01*
X323843Y-291138D01*
X323883Y-291146D01*
X323923Y-291153D01*
X324018Y-291178D01*
X324112Y-291215D01*
X324160Y-291237D01*
X324207Y-291262D01*
X324251Y-291295D01*
X324291Y-291331D01*
X324294Y-291335D01*
X324302Y-291338D01*
X324309Y-291353D01*
X324324Y-291368D01*
X324342Y-291386D01*
X324360Y-291411D01*
X324378Y-291437D01*
X324400Y-291470D01*
X324436Y-291539D01*
X324473Y-291626D01*
X324487Y-291670D01*
X324495Y-291721D01*
X324502Y-291772D01*
X324505Y-291826D01*
Y-291833D01*
Y-291852D01*
X324502Y-291881D01*
X324498Y-291921D01*
X324491Y-291965D01*
X324476Y-292016D01*
X324462Y-292070D01*
X324440Y-292125D01*
X324436Y-292132D01*
X324429Y-292150D01*
X324414Y-292179D01*
X324393Y-292219D01*
X324363Y-292263D01*
X324327Y-292318D01*
X324284Y-292372D01*
X324233Y-292434D01*
X324225Y-292441D01*
X324207Y-292463D01*
X324189Y-292481D01*
X324171Y-292500D01*
X324149Y-292522D01*
X324120Y-292551D01*
X324091Y-292580D01*
X324054Y-292613D01*
X324018Y-292649D01*
X323974Y-292689D01*
X323927Y-292729D01*
X323876Y-292776D01*
X323817Y-292824D01*
X323759Y-292875D01*
X323756Y-292878D01*
X323748Y-292885D01*
X323734Y-292896D01*
X323716Y-292911D01*
X323694Y-292933D01*
X323668Y-292955D01*
X323610Y-293002D01*
X323548Y-293057D01*
X323490Y-293111D01*
X323439Y-293159D01*
X323417Y-293177D01*
X323399Y-293195D01*
X323395Y-293198D01*
X323384Y-293209D01*
X323370Y-293224D01*
X323352Y-293246D01*
X323333Y-293271D01*
X323312Y-293297D01*
X323268Y-293359D01*
X324509D01*
Y-293657D01*
X322838D01*
Y-293653D01*
Y-293639D01*
Y-293617D01*
X322842Y-293588D01*
X322846Y-293555D01*
X322853Y-293519D01*
X322860Y-293482D01*
X322875Y-293442D01*
Y-293439D01*
X322878Y-293435D01*
X322886Y-293413D01*
X322900Y-293380D01*
X322922Y-293337D01*
X322951Y-293286D01*
X322988Y-293228D01*
X323028Y-293169D01*
X323079Y-293108D01*
Y-293104D01*
X323086Y-293100D01*
X323104Y-293078D01*
X323137Y-293046D01*
X323184Y-292998D01*
X323239Y-292944D01*
X323308Y-292878D01*
X323392Y-292805D01*
X323483Y-292729D01*
X323486Y-292725D01*
X323501Y-292714D01*
X323523Y-292696D01*
X323548Y-292674D01*
X323581Y-292645D01*
X323621Y-292613D01*
X323661Y-292576D01*
X323708Y-292536D01*
X323799Y-292449D01*
X323890Y-292361D01*
X323934Y-292318D01*
X323974Y-292274D01*
X324010Y-292234D01*
X324040Y-292194D01*
Y-292190D01*
X324047Y-292187D01*
X324054Y-292176D01*
X324061Y-292161D01*
X324087Y-292121D01*
X324116Y-292074D01*
X324142Y-292016D01*
X324167Y-291954D01*
X324182Y-291884D01*
X324189Y-291819D01*
Y-291815D01*
Y-291812D01*
X324185Y-291790D01*
X324182Y-291753D01*
X324171Y-291713D01*
X324156Y-291662D01*
X324131Y-291612D01*
X324098Y-291561D01*
X324054Y-291510D01*
X324047Y-291502D01*
X324029Y-291488D01*
X324003Y-291470D01*
X323963Y-291444D01*
X323912Y-291422D01*
X323854Y-291400D01*
X323785Y-291386D01*
X323708Y-291382D01*
X323687D01*
X323672Y-291386D01*
X323628Y-291389D01*
X323577Y-291400D01*
X323523Y-291415D01*
X323461Y-291440D01*
X323403Y-291473D01*
X323348Y-291517D01*
X323341Y-291524D01*
X323326Y-291542D01*
X323304Y-291571D01*
X323283Y-291615D01*
X323257Y-291666D01*
X323235Y-291732D01*
X323221Y-291804D01*
X323213Y-291888D01*
X322897Y-291855D01*
Y-291852D01*
X322900Y-291841D01*
Y-291823D01*
X322904Y-291797D01*
X322911Y-291768D01*
X322919Y-291735D01*
X322929Y-291695D01*
X322940Y-291655D01*
X322969Y-291568D01*
X323013Y-291480D01*
X323039Y-291437D01*
X323071Y-291393D01*
X323104Y-291353D01*
X323141Y-291317D01*
X323144Y-291313D01*
X323151Y-291309D01*
X323162Y-291298D01*
X323181Y-291287D01*
X323202Y-291273D01*
X323228Y-291258D01*
X323257Y-291240D01*
X323293Y-291222D01*
X323333Y-291204D01*
X323377Y-291186D01*
X323424Y-291171D01*
X323475Y-291157D01*
X323530Y-291146D01*
X323588Y-291135D01*
X323650Y-291131D01*
X323716Y-291127D01*
X323752D01*
X323778Y-291131D01*
D02*
G37*
G36*
X558662Y-64570D02*
X558691Y-64574D01*
X558724Y-64578D01*
X558760Y-64585D01*
X558800Y-64592D01*
X558887Y-64614D01*
X558978Y-64651D01*
X559026Y-64672D01*
X559069Y-64698D01*
X559113Y-64731D01*
X559157Y-64763D01*
X559160Y-64767D01*
X559168Y-64774D01*
X559179Y-64785D01*
X559190Y-64800D01*
X559208Y-64818D01*
X559226Y-64843D01*
X559248Y-64869D01*
X559270Y-64902D01*
X559291Y-64938D01*
X559313Y-64975D01*
X559353Y-65062D01*
X559386Y-65164D01*
X559397Y-65218D01*
X559404Y-65277D01*
X559095Y-65317D01*
Y-65313D01*
X559091Y-65306D01*
X559088Y-65291D01*
X559084Y-65273D01*
X559080Y-65251D01*
X559073Y-65226D01*
X559055Y-65171D01*
X559029Y-65106D01*
X558997Y-65044D01*
X558960Y-64986D01*
X558917Y-64934D01*
X558909Y-64931D01*
X558895Y-64916D01*
X558866Y-64898D01*
X558829Y-64880D01*
X558785Y-64858D01*
X558731Y-64840D01*
X558669Y-64825D01*
X558603Y-64822D01*
X558582D01*
X558567Y-64825D01*
X558527Y-64829D01*
X558476Y-64840D01*
X558418Y-64858D01*
X558356Y-64884D01*
X558294Y-64920D01*
X558236Y-64971D01*
X558229Y-64978D01*
X558210Y-65000D01*
X558188Y-65033D01*
X558159Y-65077D01*
X558130Y-65131D01*
X558108Y-65193D01*
X558090Y-65266D01*
X558083Y-65346D01*
Y-65350D01*
Y-65357D01*
Y-65368D01*
X558087Y-65382D01*
X558090Y-65422D01*
X558101Y-65470D01*
X558116Y-65528D01*
X558141Y-65586D01*
X558178Y-65644D01*
X558225Y-65699D01*
X558232Y-65706D01*
X558250Y-65721D01*
X558280Y-65743D01*
X558320Y-65768D01*
X558370Y-65794D01*
X558432Y-65815D01*
X558502Y-65830D01*
X558578Y-65837D01*
X558611D01*
X558636Y-65834D01*
X558669Y-65830D01*
X558705Y-65823D01*
X558749Y-65815D01*
X558796Y-65804D01*
X558760Y-66078D01*
X558742D01*
X558727Y-66074D01*
X558680D01*
X558640Y-66081D01*
X558593Y-66088D01*
X558538Y-66099D01*
X558476Y-66118D01*
X558418Y-66143D01*
X558356Y-66176D01*
X558352D01*
X558349Y-66179D01*
X558330Y-66194D01*
X558305Y-66219D01*
X558276Y-66252D01*
X558247Y-66299D01*
X558221Y-66354D01*
X558203Y-66416D01*
X558196Y-66452D01*
Y-66492D01*
Y-66496D01*
Y-66500D01*
Y-66522D01*
X558203Y-66551D01*
X558210Y-66591D01*
X558225Y-66634D01*
X558243Y-66682D01*
X558272Y-66729D01*
X558312Y-66773D01*
X558316Y-66776D01*
X558334Y-66791D01*
X558360Y-66809D01*
X558392Y-66831D01*
X558436Y-66849D01*
X558487Y-66867D01*
X558545Y-66882D01*
X558611Y-66886D01*
X558640D01*
X558673Y-66878D01*
X558716Y-66871D01*
X558764Y-66856D01*
X558811Y-66838D01*
X558862Y-66809D01*
X558909Y-66773D01*
X558913Y-66769D01*
X558927Y-66751D01*
X558949Y-66725D01*
X558975Y-66689D01*
X559000Y-66642D01*
X559026Y-66583D01*
X559048Y-66514D01*
X559062Y-66434D01*
X559372Y-66489D01*
Y-66492D01*
X559368Y-66503D01*
X559364Y-66518D01*
X559361Y-66540D01*
X559353Y-66565D01*
X559342Y-66594D01*
X559321Y-66663D01*
X559284Y-66744D01*
X559240Y-66824D01*
X559186Y-66900D01*
X559117Y-66969D01*
X559113Y-66973D01*
X559106Y-66977D01*
X559095Y-66984D01*
X559080Y-66995D01*
X559062Y-67009D01*
X559037Y-67024D01*
X559011Y-67038D01*
X558978Y-67057D01*
X558906Y-67086D01*
X558822Y-67115D01*
X558724Y-67133D01*
X558673Y-67140D01*
X558582D01*
X558542Y-67137D01*
X558494Y-67129D01*
X558436Y-67119D01*
X558370Y-67100D01*
X558305Y-67079D01*
X558240Y-67049D01*
X558236D01*
X558232Y-67046D01*
X558210Y-67035D01*
X558178Y-67013D01*
X558141Y-66988D01*
X558098Y-66951D01*
X558054Y-66911D01*
X558010Y-66864D01*
X557974Y-66809D01*
X557970Y-66802D01*
X557959Y-66784D01*
X557945Y-66751D01*
X557926Y-66711D01*
X557908Y-66663D01*
X557894Y-66609D01*
X557883Y-66547D01*
X557879Y-66485D01*
Y-66478D01*
Y-66456D01*
X557883Y-66427D01*
X557890Y-66387D01*
X557901Y-66340D01*
X557919Y-66289D01*
X557941Y-66238D01*
X557970Y-66187D01*
X557974Y-66179D01*
X557985Y-66165D01*
X558006Y-66139D01*
X558036Y-66110D01*
X558072Y-66078D01*
X558116Y-66041D01*
X558167Y-66008D01*
X558229Y-65976D01*
X558225D01*
X558218Y-65972D01*
X558207Y-65968D01*
X558192Y-65965D01*
X558152Y-65950D01*
X558101Y-65928D01*
X558043Y-65899D01*
X557985Y-65863D01*
X557930Y-65815D01*
X557879Y-65761D01*
X557875Y-65754D01*
X557861Y-65732D01*
X557839Y-65695D01*
X557817Y-65648D01*
X557795Y-65590D01*
X557774Y-65521D01*
X557759Y-65440D01*
X557755Y-65353D01*
Y-65350D01*
Y-65339D01*
Y-65320D01*
X557759Y-65298D01*
X557763Y-65269D01*
X557770Y-65237D01*
X557777Y-65200D01*
X557785Y-65160D01*
X557814Y-65073D01*
X557835Y-65026D01*
X557857Y-64982D01*
X557886Y-64934D01*
X557919Y-64887D01*
X557956Y-64840D01*
X557999Y-64796D01*
X558003Y-64793D01*
X558010Y-64785D01*
X558025Y-64774D01*
X558043Y-64760D01*
X558065Y-64742D01*
X558094Y-64723D01*
X558127Y-64702D01*
X558167Y-64683D01*
X558207Y-64662D01*
X558254Y-64640D01*
X558301Y-64622D01*
X558356Y-64603D01*
X558414Y-64589D01*
X558476Y-64578D01*
X558538Y-64570D01*
X558607Y-64567D01*
X558640D01*
X558662Y-64570D01*
D02*
G37*
G36*
X563780Y-67129D02*
X562811D01*
X562746Y-67126D01*
X562673Y-67122D01*
X562600Y-67115D01*
X562527Y-67104D01*
X562465Y-67093D01*
X562462D01*
X562455Y-67089D01*
X562444D01*
X562429Y-67082D01*
X562389Y-67071D01*
X562338Y-67053D01*
X562280Y-67027D01*
X562218Y-66995D01*
X562156Y-66958D01*
X562098Y-66911D01*
X562094Y-66907D01*
X562091Y-66904D01*
X562080Y-66893D01*
X562065Y-66882D01*
X562029Y-66846D01*
X561985Y-66795D01*
X561938Y-66733D01*
X561887Y-66660D01*
X561839Y-66576D01*
X561799Y-66482D01*
Y-66478D01*
X561796Y-66471D01*
X561789Y-66456D01*
X561785Y-66434D01*
X561774Y-66409D01*
X561767Y-66380D01*
X561759Y-66347D01*
X561748Y-66307D01*
X561737Y-66267D01*
X561730Y-66219D01*
X561712Y-66118D01*
X561701Y-66005D01*
X561697Y-65881D01*
Y-65877D01*
Y-65870D01*
Y-65852D01*
Y-65834D01*
X561701Y-65808D01*
Y-65779D01*
X561705Y-65710D01*
X561716Y-65630D01*
X561727Y-65546D01*
X561745Y-65459D01*
X561767Y-65371D01*
Y-65368D01*
X561770Y-65360D01*
X561774Y-65350D01*
X561778Y-65335D01*
X561792Y-65295D01*
X561814Y-65244D01*
X561836Y-65186D01*
X561865Y-65127D01*
X561901Y-65066D01*
X561938Y-65007D01*
X561941Y-65000D01*
X561956Y-64982D01*
X561978Y-64956D01*
X562007Y-64924D01*
X562040Y-64887D01*
X562080Y-64851D01*
X562120Y-64811D01*
X562167Y-64778D01*
X562174Y-64774D01*
X562189Y-64763D01*
X562214Y-64749D01*
X562251Y-64731D01*
X562294Y-64709D01*
X562345Y-64691D01*
X562404Y-64669D01*
X562469Y-64651D01*
X562476D01*
X562487Y-64647D01*
X562498Y-64643D01*
X562535Y-64640D01*
X562586Y-64632D01*
X562644Y-64625D01*
X562713Y-64618D01*
X562789Y-64614D01*
X562873Y-64611D01*
X563780D01*
Y-67129D01*
D02*
G37*
G36*
X561410Y-64614D02*
Y-64629D01*
Y-64651D01*
X561406Y-64680D01*
X561403Y-64713D01*
X561395Y-64749D01*
X561388Y-64785D01*
X561374Y-64825D01*
Y-64829D01*
X561370Y-64833D01*
X561363Y-64854D01*
X561348Y-64887D01*
X561326Y-64931D01*
X561297Y-64982D01*
X561261Y-65040D01*
X561221Y-65098D01*
X561170Y-65160D01*
Y-65164D01*
X561162Y-65167D01*
X561144Y-65189D01*
X561111Y-65222D01*
X561064Y-65269D01*
X561010Y-65324D01*
X560940Y-65390D01*
X560857Y-65462D01*
X560766Y-65539D01*
X560762Y-65542D01*
X560747Y-65553D01*
X560726Y-65571D01*
X560700Y-65593D01*
X560667Y-65623D01*
X560627Y-65655D01*
X560587Y-65692D01*
X560540Y-65732D01*
X560449Y-65819D01*
X560358Y-65906D01*
X560314Y-65950D01*
X560274Y-65994D01*
X560238Y-66034D01*
X560209Y-66074D01*
Y-66078D01*
X560201Y-66081D01*
X560194Y-66092D01*
X560187Y-66107D01*
X560161Y-66147D01*
X560132Y-66194D01*
X560107Y-66252D01*
X560081Y-66314D01*
X560067Y-66383D01*
X560059Y-66449D01*
Y-66452D01*
Y-66456D01*
X560063Y-66478D01*
X560067Y-66514D01*
X560078Y-66554D01*
X560092Y-66605D01*
X560118Y-66656D01*
X560150Y-66707D01*
X560194Y-66758D01*
X560201Y-66765D01*
X560220Y-66780D01*
X560245Y-66798D01*
X560285Y-66824D01*
X560336Y-66846D01*
X560394Y-66867D01*
X560463Y-66882D01*
X560540Y-66886D01*
X560562D01*
X560576Y-66882D01*
X560620Y-66878D01*
X560671Y-66867D01*
X560726Y-66853D01*
X560787Y-66827D01*
X560846Y-66795D01*
X560900Y-66751D01*
X560908Y-66744D01*
X560922Y-66725D01*
X560944Y-66696D01*
X560966Y-66653D01*
X560991Y-66602D01*
X561013Y-66536D01*
X561028Y-66463D01*
X561035Y-66380D01*
X561352Y-66412D01*
Y-66416D01*
X561348Y-66427D01*
Y-66445D01*
X561344Y-66471D01*
X561337Y-66500D01*
X561330Y-66532D01*
X561319Y-66572D01*
X561308Y-66613D01*
X561279Y-66700D01*
X561235Y-66787D01*
X561210Y-66831D01*
X561177Y-66875D01*
X561144Y-66915D01*
X561108Y-66951D01*
X561104Y-66955D01*
X561097Y-66958D01*
X561086Y-66969D01*
X561068Y-66980D01*
X561046Y-66995D01*
X561020Y-67009D01*
X560991Y-67027D01*
X560955Y-67046D01*
X560915Y-67064D01*
X560871Y-67082D01*
X560824Y-67097D01*
X560773Y-67111D01*
X560718Y-67122D01*
X560660Y-67133D01*
X560598Y-67137D01*
X560533Y-67140D01*
X560496D01*
X560471Y-67137D01*
X560442Y-67133D01*
X560405Y-67129D01*
X560365Y-67122D01*
X560325Y-67115D01*
X560231Y-67089D01*
X560136Y-67053D01*
X560089Y-67031D01*
X560041Y-67006D01*
X559998Y-66973D01*
X559958Y-66936D01*
X559954Y-66933D01*
X559947Y-66929D01*
X559939Y-66915D01*
X559925Y-66900D01*
X559907Y-66882D01*
X559888Y-66856D01*
X559870Y-66831D01*
X559848Y-66798D01*
X559812Y-66729D01*
X559776Y-66642D01*
X559761Y-66598D01*
X559754Y-66547D01*
X559746Y-66496D01*
X559743Y-66442D01*
Y-66434D01*
Y-66416D01*
X559746Y-66387D01*
X559750Y-66347D01*
X559757Y-66303D01*
X559772Y-66252D01*
X559787Y-66198D01*
X559808Y-66143D01*
X559812Y-66136D01*
X559819Y-66118D01*
X559834Y-66088D01*
X559856Y-66048D01*
X559885Y-66005D01*
X559921Y-65950D01*
X559965Y-65895D01*
X560016Y-65834D01*
X560023Y-65826D01*
X560041Y-65804D01*
X560059Y-65786D01*
X560078Y-65768D01*
X560100Y-65746D01*
X560129Y-65717D01*
X560158Y-65688D01*
X560194Y-65655D01*
X560231Y-65619D01*
X560274Y-65579D01*
X560322Y-65539D01*
X560372Y-65491D01*
X560431Y-65444D01*
X560489Y-65393D01*
X560493Y-65390D01*
X560500Y-65382D01*
X560514Y-65371D01*
X560533Y-65357D01*
X560555Y-65335D01*
X560580Y-65313D01*
X560638Y-65266D01*
X560700Y-65211D01*
X560758Y-65157D01*
X560809Y-65109D01*
X560831Y-65091D01*
X560849Y-65073D01*
X560853Y-65069D01*
X560864Y-65058D01*
X560879Y-65044D01*
X560897Y-65022D01*
X560915Y-64996D01*
X560937Y-64971D01*
X560980Y-64909D01*
X559739D01*
Y-64611D01*
X561410D01*
Y-64614D01*
D02*
G37*
G36*
X605862Y-70469D02*
X605858D01*
X605844D01*
X605822D01*
X605793Y-70465D01*
X605760Y-70461D01*
X605723Y-70454D01*
X605687Y-70447D01*
X605647Y-70432D01*
X605644D01*
X605640Y-70429D01*
X605618Y-70421D01*
X605585Y-70407D01*
X605542Y-70385D01*
X605491Y-70356D01*
X605432Y-70319D01*
X605374Y-70279D01*
X605312Y-70228D01*
X605309D01*
X605305Y-70221D01*
X605283Y-70203D01*
X605250Y-70170D01*
X605203Y-70123D01*
X605148Y-70068D01*
X605083Y-69999D01*
X605010Y-69915D01*
X604934Y-69824D01*
X604930Y-69821D01*
X604919Y-69806D01*
X604901Y-69784D01*
X604879Y-69759D01*
X604850Y-69726D01*
X604817Y-69686D01*
X604781Y-69646D01*
X604741Y-69599D01*
X604653Y-69508D01*
X604566Y-69417D01*
X604522Y-69373D01*
X604479Y-69333D01*
X604439Y-69297D01*
X604399Y-69267D01*
X604395D01*
X604391Y-69260D01*
X604380Y-69253D01*
X604366Y-69246D01*
X604326Y-69220D01*
X604279Y-69191D01*
X604220Y-69166D01*
X604158Y-69140D01*
X604089Y-69125D01*
X604024Y-69118D01*
X604020D01*
X604016D01*
X603995Y-69122D01*
X603958Y-69125D01*
X603918Y-69137D01*
X603867Y-69151D01*
X603816Y-69177D01*
X603765Y-69209D01*
X603714Y-69253D01*
X603707Y-69260D01*
X603692Y-69278D01*
X603674Y-69304D01*
X603649Y-69344D01*
X603627Y-69395D01*
X603605Y-69453D01*
X603590Y-69522D01*
X603587Y-69599D01*
Y-69621D01*
X603590Y-69635D01*
X603594Y-69679D01*
X603605Y-69730D01*
X603620Y-69784D01*
X603645Y-69846D01*
X603678Y-69905D01*
X603722Y-69959D01*
X603729Y-69966D01*
X603747Y-69981D01*
X603776Y-70003D01*
X603820Y-70025D01*
X603871Y-70050D01*
X603936Y-70072D01*
X604009Y-70086D01*
X604093Y-70094D01*
X604060Y-70411D01*
X604056D01*
X604045Y-70407D01*
X604027D01*
X604002Y-70403D01*
X603973Y-70396D01*
X603940Y-70389D01*
X603900Y-70378D01*
X603860Y-70367D01*
X603772Y-70338D01*
X603685Y-70294D01*
X603642Y-70268D01*
X603598Y-70236D01*
X603558Y-70203D01*
X603521Y-70167D01*
X603518Y-70163D01*
X603514Y-70156D01*
X603503Y-70145D01*
X603492Y-70126D01*
X603478Y-70105D01*
X603463Y-70079D01*
X603445Y-70050D01*
X603427Y-70014D01*
X603408Y-69974D01*
X603390Y-69930D01*
X603376Y-69883D01*
X603361Y-69832D01*
X603350Y-69777D01*
X603339Y-69719D01*
X603336Y-69657D01*
X603332Y-69591D01*
Y-69555D01*
X603336Y-69530D01*
X603339Y-69500D01*
X603343Y-69464D01*
X603350Y-69424D01*
X603358Y-69384D01*
X603383Y-69289D01*
X603419Y-69195D01*
X603441Y-69147D01*
X603467Y-69100D01*
X603500Y-69056D01*
X603536Y-69016D01*
X603540Y-69013D01*
X603543Y-69005D01*
X603558Y-68998D01*
X603572Y-68984D01*
X603590Y-68965D01*
X603616Y-68947D01*
X603642Y-68929D01*
X603674Y-68907D01*
X603743Y-68871D01*
X603831Y-68834D01*
X603874Y-68820D01*
X603925Y-68813D01*
X603976Y-68805D01*
X604031Y-68802D01*
X604038D01*
X604056D01*
X604085Y-68805D01*
X604126Y-68809D01*
X604169Y-68816D01*
X604220Y-68831D01*
X604275Y-68845D01*
X604329Y-68867D01*
X604337Y-68871D01*
X604355Y-68878D01*
X604384Y-68893D01*
X604424Y-68914D01*
X604468Y-68944D01*
X604522Y-68980D01*
X604577Y-69024D01*
X604639Y-69075D01*
X604646Y-69082D01*
X604668Y-69100D01*
X604686Y-69118D01*
X604704Y-69137D01*
X604726Y-69158D01*
X604755Y-69187D01*
X604784Y-69217D01*
X604817Y-69253D01*
X604854Y-69289D01*
X604894Y-69333D01*
X604934Y-69380D01*
X604981Y-69431D01*
X605028Y-69490D01*
X605079Y-69548D01*
X605083Y-69551D01*
X605090Y-69559D01*
X605101Y-69573D01*
X605116Y-69591D01*
X605137Y-69613D01*
X605159Y-69639D01*
X605207Y-69697D01*
X605261Y-69759D01*
X605316Y-69817D01*
X605363Y-69868D01*
X605381Y-69890D01*
X605400Y-69908D01*
X605403Y-69912D01*
X605414Y-69923D01*
X605429Y-69937D01*
X605451Y-69955D01*
X605476Y-69974D01*
X605502Y-69995D01*
X605563Y-70039D01*
Y-68798D01*
X605862D01*
Y-70469D01*
D02*
G37*
G36*
X604894Y-70858D02*
X604930D01*
X604974Y-70862D01*
X605017Y-70865D01*
X605116Y-70876D01*
X605218Y-70891D01*
X605316Y-70913D01*
X605363Y-70927D01*
X605407Y-70942D01*
X605410D01*
X605418Y-70946D01*
X605429Y-70953D01*
X605443Y-70960D01*
X605483Y-70982D01*
X605534Y-71015D01*
X605592Y-71058D01*
X605651Y-71109D01*
X605713Y-71175D01*
X605767Y-71255D01*
Y-71259D01*
X605774Y-71266D01*
X605778Y-71277D01*
X605789Y-71295D01*
X605800Y-71317D01*
X605811Y-71346D01*
X605822Y-71375D01*
X605836Y-71412D01*
X605851Y-71451D01*
X605862Y-71495D01*
X605873Y-71543D01*
X605884Y-71597D01*
X605891Y-71652D01*
X605898Y-71710D01*
X605906Y-71841D01*
Y-71874D01*
X605902Y-71899D01*
Y-71928D01*
X605898Y-71965D01*
X605895Y-72005D01*
X605891Y-72045D01*
X605876Y-72136D01*
X605855Y-72234D01*
X605826Y-72329D01*
X605785Y-72420D01*
Y-72423D01*
X605778Y-72431D01*
X605771Y-72442D01*
X605764Y-72456D01*
X605734Y-72496D01*
X605694Y-72544D01*
X605644Y-72598D01*
X605585Y-72649D01*
X605512Y-72700D01*
X605432Y-72740D01*
X605429D01*
X605421Y-72744D01*
X605407Y-72747D01*
X605389Y-72755D01*
X605367Y-72762D01*
X605338Y-72769D01*
X605305Y-72780D01*
X605265Y-72787D01*
X605221Y-72795D01*
X605174Y-72806D01*
X605123Y-72813D01*
X605068Y-72820D01*
X605007Y-72827D01*
X604941Y-72831D01*
X604872Y-72835D01*
X604799D01*
X603343D01*
Y-72500D01*
X604799D01*
X604803D01*
X604814D01*
X604832D01*
X604854D01*
X604879Y-72496D01*
X604912D01*
X604981Y-72493D01*
X605061Y-72485D01*
X605141Y-72474D01*
X605218Y-72460D01*
X605250Y-72452D01*
X605283Y-72442D01*
X605290Y-72438D01*
X605309Y-72431D01*
X605334Y-72413D01*
X605371Y-72391D01*
X605407Y-72365D01*
X605447Y-72329D01*
X605487Y-72285D01*
X605520Y-72234D01*
X605523Y-72227D01*
X605534Y-72209D01*
X605545Y-72176D01*
X605560Y-72132D01*
X605578Y-72081D01*
X605589Y-72016D01*
X605600Y-71947D01*
X605603Y-71870D01*
Y-71834D01*
X605600Y-71812D01*
Y-71779D01*
X605596Y-71746D01*
X605582Y-71666D01*
X605563Y-71579D01*
X605534Y-71495D01*
X605494Y-71415D01*
X605469Y-71379D01*
X605440Y-71346D01*
X605436Y-71342D01*
X605432Y-71339D01*
X605421Y-71331D01*
X605407Y-71320D01*
X605385Y-71310D01*
X605363Y-71295D01*
X605330Y-71280D01*
X605298Y-71266D01*
X605258Y-71251D01*
X605210Y-71240D01*
X605156Y-71226D01*
X605097Y-71215D01*
X605032Y-71204D01*
X604963Y-71197D01*
X604883Y-71189D01*
X604799D01*
X603343D01*
Y-70855D01*
X604799D01*
X604803D01*
X604817D01*
X604835D01*
X604861D01*
X604894Y-70858D01*
D02*
G37*
G36*
X133641Y-128685D02*
X132185D01*
X132181D01*
X132170D01*
X132152D01*
X132130D01*
X132105Y-128688D01*
X132072D01*
X132003Y-128692D01*
X131923Y-128699D01*
X131843Y-128710D01*
X131766Y-128725D01*
X131733Y-128732D01*
X131701Y-128743D01*
X131693Y-128747D01*
X131675Y-128754D01*
X131650Y-128772D01*
X131613Y-128794D01*
X131577Y-128820D01*
X131537Y-128856D01*
X131497Y-128900D01*
X131464Y-128951D01*
X131460Y-128958D01*
X131449Y-128976D01*
X131439Y-129009D01*
X131424Y-129052D01*
X131406Y-129103D01*
X131395Y-129169D01*
X131384Y-129238D01*
X131380Y-129314D01*
Y-129351D01*
X131384Y-129373D01*
Y-129405D01*
X131388Y-129438D01*
X131402Y-129518D01*
X131420Y-129606D01*
X131449Y-129689D01*
X131490Y-129770D01*
X131515Y-129806D01*
X131544Y-129839D01*
X131548Y-129842D01*
X131551Y-129846D01*
X131562Y-129853D01*
X131577Y-129864D01*
X131599Y-129875D01*
X131621Y-129890D01*
X131653Y-129904D01*
X131686Y-129919D01*
X131726Y-129933D01*
X131773Y-129944D01*
X131828Y-129959D01*
X131886Y-129970D01*
X131952Y-129981D01*
X132021Y-129988D01*
X132101Y-129995D01*
X132185D01*
X133641D01*
Y-130330D01*
X132185D01*
X132181D01*
X132167D01*
X132148D01*
X132123D01*
X132090Y-130326D01*
X132054D01*
X132010Y-130323D01*
X131966Y-130319D01*
X131868Y-130308D01*
X131766Y-130294D01*
X131668Y-130272D01*
X131621Y-130257D01*
X131577Y-130243D01*
X131573D01*
X131566Y-130239D01*
X131555Y-130232D01*
X131540Y-130225D01*
X131500Y-130203D01*
X131449Y-130170D01*
X131391Y-130126D01*
X131333Y-130075D01*
X131271Y-130010D01*
X131217Y-129930D01*
Y-129926D01*
X131209Y-129919D01*
X131205Y-129908D01*
X131195Y-129890D01*
X131184Y-129868D01*
X131173Y-129839D01*
X131162Y-129810D01*
X131147Y-129773D01*
X131133Y-129733D01*
X131122Y-129689D01*
X131111Y-129642D01*
X131100Y-129587D01*
X131093Y-129533D01*
X131085Y-129475D01*
X131078Y-129344D01*
Y-129311D01*
X131082Y-129285D01*
Y-129256D01*
X131085Y-129220D01*
X131089Y-129180D01*
X131093Y-129140D01*
X131107Y-129049D01*
X131129Y-128951D01*
X131158Y-128856D01*
X131198Y-128765D01*
Y-128761D01*
X131205Y-128754D01*
X131213Y-128743D01*
X131220Y-128728D01*
X131249Y-128688D01*
X131289Y-128641D01*
X131340Y-128586D01*
X131398Y-128536D01*
X131471Y-128485D01*
X131551Y-128445D01*
X131555D01*
X131562Y-128441D01*
X131577Y-128437D01*
X131595Y-128430D01*
X131617Y-128423D01*
X131646Y-128415D01*
X131679Y-128404D01*
X131719Y-128397D01*
X131763Y-128390D01*
X131810Y-128379D01*
X131861Y-128372D01*
X131915Y-128365D01*
X131977Y-128357D01*
X132043Y-128354D01*
X132112Y-128350D01*
X132185D01*
X133641D01*
Y-128685D01*
D02*
G37*
G36*
X133018Y-131000D02*
X133026Y-131007D01*
X133029Y-131022D01*
X133040Y-131040D01*
X133051Y-131062D01*
X133066Y-131087D01*
X133102Y-131149D01*
X133142Y-131222D01*
X133193Y-131295D01*
X133251Y-131371D01*
X133313Y-131448D01*
X133317Y-131451D01*
X133320Y-131455D01*
X133331Y-131466D01*
X133342Y-131480D01*
X133379Y-131513D01*
X133422Y-131557D01*
X133473Y-131600D01*
X133531Y-131648D01*
X133590Y-131688D01*
X133652Y-131724D01*
Y-131924D01*
X131122D01*
Y-131615D01*
X133091D01*
X133087Y-131611D01*
X133073Y-131593D01*
X133051Y-131571D01*
X133026Y-131535D01*
X132993Y-131495D01*
X132956Y-131444D01*
X132916Y-131386D01*
X132876Y-131320D01*
Y-131316D01*
X132873Y-131313D01*
X132858Y-131291D01*
X132840Y-131255D01*
X132818Y-131211D01*
X132793Y-131160D01*
X132767Y-131105D01*
X132742Y-131051D01*
X132720Y-130996D01*
X133018D01*
Y-131000D01*
D02*
G37*
G36*
X133641Y-133766D02*
Y-134017D01*
X132010D01*
Y-134360D01*
X131726D01*
Y-134017D01*
X131122D01*
Y-133708D01*
X131726D01*
Y-132612D01*
X132010D01*
X133641Y-133766D01*
D02*
G37*
%LPC*%
G36*
X587779Y4196D02*
X587776D01*
X587772D01*
X587750D01*
X587717Y4189D01*
X587677Y4182D01*
X587634Y4167D01*
X587586Y4145D01*
X587539Y4116D01*
X587492Y4076D01*
X587488Y4073D01*
X587473Y4054D01*
X587455Y4029D01*
X587433Y3996D01*
X587412Y3952D01*
X587393Y3905D01*
X587379Y3847D01*
X587375Y3785D01*
Y3756D01*
X587383Y3723D01*
X587390Y3679D01*
X587404Y3632D01*
X587423Y3581D01*
X587452Y3534D01*
X587492Y3486D01*
X587495Y3483D01*
X587510Y3468D01*
X587535Y3450D01*
X587568Y3432D01*
X587608Y3410D01*
X587655Y3392D01*
X587706Y3377D01*
X587765Y3374D01*
X587768D01*
X587772D01*
X587794Y3377D01*
X587827Y3381D01*
X587867Y3388D01*
X587914Y3403D01*
X587961Y3421D01*
X588012Y3450D01*
X588056Y3486D01*
X588060Y3490D01*
X588074Y3508D01*
X588092Y3534D01*
X588110Y3567D01*
X588132Y3610D01*
X588151Y3661D01*
X588165Y3719D01*
X588169Y3785D01*
Y3792D01*
X588165Y3814D01*
X588161Y3847D01*
X588154Y3890D01*
X588140Y3938D01*
X588121Y3985D01*
X588092Y4036D01*
X588056Y4080D01*
X588052Y4083D01*
X588034Y4098D01*
X588012Y4116D01*
X587979Y4138D01*
X587939Y4160D01*
X587892Y4178D01*
X587838Y4193D01*
X587779Y4196D01*
D02*
G37*
G36*
X588937Y4298D02*
X588933D01*
X588926D01*
X588915D01*
X588900Y4295D01*
X588860Y4291D01*
X588806Y4280D01*
X588751Y4262D01*
X588689Y4236D01*
X588627Y4200D01*
X588569Y4149D01*
X588562Y4142D01*
X588547Y4123D01*
X588522Y4091D01*
X588493Y4047D01*
X588467Y3992D01*
X588442Y3927D01*
X588427Y3854D01*
X588420Y3774D01*
Y3752D01*
X588423Y3738D01*
X588427Y3698D01*
X588438Y3647D01*
X588456Y3588D01*
X588482Y3530D01*
X588518Y3468D01*
X588565Y3414D01*
X588573Y3406D01*
X588591Y3392D01*
X588624Y3370D01*
X588664Y3345D01*
X588718Y3315D01*
X588780Y3294D01*
X588849Y3279D01*
X588926Y3272D01*
X588933D01*
X588948D01*
X588973Y3275D01*
X589006Y3279D01*
X589046Y3286D01*
X589090Y3297D01*
X589133Y3312D01*
X589181Y3330D01*
X589184Y3334D01*
X589202Y3341D01*
X589224Y3355D01*
X589250Y3377D01*
X589283Y3403D01*
X589315Y3435D01*
X589344Y3472D01*
X589373Y3516D01*
X589377Y3523D01*
X589385Y3537D01*
X589395Y3563D01*
X589406Y3596D01*
X589417Y3636D01*
X589428Y3683D01*
X589435Y3734D01*
X589439Y3785D01*
Y3807D01*
X589435Y3821D01*
X589432Y3865D01*
X589421Y3916D01*
X589403Y3974D01*
X589381Y4036D01*
X589344Y4094D01*
X589297Y4153D01*
X589290Y4160D01*
X589272Y4174D01*
X589239Y4200D01*
X589199Y4225D01*
X589148Y4251D01*
X589086Y4276D01*
X589013Y4291D01*
X588937Y4298D01*
D02*
G37*
G36*
X424764Y-153602D02*
X424760D01*
X424756D01*
X424735Y-153605D01*
X424702Y-153609D01*
X424662Y-153616D01*
X424615Y-153631D01*
X424567Y-153649D01*
X424516Y-153678D01*
X424473Y-153715D01*
X424469Y-153718D01*
X424454Y-153736D01*
X424436Y-153762D01*
X424418Y-153795D01*
X424396Y-153838D01*
X424378Y-153889D01*
X424363Y-153948D01*
X424360Y-154013D01*
Y-154020D01*
X424363Y-154042D01*
X424367Y-154075D01*
X424374Y-154119D01*
X424389Y-154166D01*
X424407Y-154213D01*
X424436Y-154264D01*
X424473Y-154308D01*
X424476Y-154312D01*
X424494Y-154326D01*
X424516Y-154344D01*
X424549Y-154366D01*
X424589Y-154388D01*
X424636Y-154406D01*
X424691Y-154421D01*
X424749Y-154425D01*
X424753D01*
X424756D01*
X424778D01*
X424811Y-154417D01*
X424851Y-154410D01*
X424895Y-154395D01*
X424942Y-154374D01*
X424990Y-154344D01*
X425037Y-154304D01*
X425040Y-154301D01*
X425055Y-154282D01*
X425073Y-154257D01*
X425095Y-154224D01*
X425117Y-154181D01*
X425135Y-154133D01*
X425150Y-154075D01*
X425153Y-154013D01*
Y-153984D01*
X425146Y-153951D01*
X425139Y-153908D01*
X425124Y-153860D01*
X425106Y-153809D01*
X425077Y-153762D01*
X425037Y-153715D01*
X425033Y-153711D01*
X425019Y-153697D01*
X424993Y-153678D01*
X424960Y-153660D01*
X424920Y-153638D01*
X424873Y-153620D01*
X424822Y-153605D01*
X424764Y-153602D01*
D02*
G37*
G36*
X423603Y-153500D02*
X423595D01*
X423581D01*
X423555Y-153504D01*
X423523Y-153507D01*
X423483Y-153515D01*
X423439Y-153525D01*
X423395Y-153540D01*
X423348Y-153558D01*
X423344Y-153562D01*
X423326Y-153569D01*
X423304Y-153584D01*
X423279Y-153605D01*
X423246Y-153631D01*
X423213Y-153664D01*
X423184Y-153700D01*
X423155Y-153744D01*
X423151Y-153751D01*
X423144Y-153766D01*
X423133Y-153791D01*
X423122Y-153824D01*
X423111Y-153864D01*
X423100Y-153911D01*
X423093Y-153962D01*
X423089Y-154013D01*
Y-154035D01*
X423093Y-154050D01*
X423097Y-154093D01*
X423108Y-154144D01*
X423126Y-154202D01*
X423148Y-154264D01*
X423184Y-154323D01*
X423231Y-154381D01*
X423239Y-154388D01*
X423257Y-154403D01*
X423290Y-154428D01*
X423330Y-154454D01*
X423381Y-154479D01*
X423443Y-154505D01*
X423515Y-154519D01*
X423592Y-154526D01*
X423595D01*
X423603D01*
X423614D01*
X423628Y-154523D01*
X423668Y-154519D01*
X423723Y-154508D01*
X423777Y-154490D01*
X423839Y-154464D01*
X423901Y-154428D01*
X423959Y-154377D01*
X423967Y-154370D01*
X423981Y-154352D01*
X424007Y-154319D01*
X424036Y-154275D01*
X424061Y-154221D01*
X424087Y-154155D01*
X424101Y-154082D01*
X424109Y-154002D01*
Y-153980D01*
X424105Y-153966D01*
X424101Y-153926D01*
X424090Y-153875D01*
X424072Y-153817D01*
X424047Y-153758D01*
X424010Y-153697D01*
X423963Y-153642D01*
X423956Y-153635D01*
X423938Y-153620D01*
X423905Y-153598D01*
X423865Y-153573D01*
X423810Y-153544D01*
X423748Y-153522D01*
X423679Y-153507D01*
X423603Y-153500D01*
D02*
G37*
G36*
X601705Y-231592D02*
X601122D01*
Y-233513D01*
X601719D01*
X601745Y-233510D01*
X601799Y-233506D01*
X601861Y-233503D01*
X601927Y-233495D01*
X601992Y-233484D01*
X602047Y-233470D01*
X602054Y-233466D01*
X602072Y-233463D01*
X602098Y-233452D01*
X602131Y-233437D01*
X602167Y-233415D01*
X602203Y-233393D01*
X602240Y-233368D01*
X602276Y-233339D01*
X602280Y-233331D01*
X602294Y-233317D01*
X602316Y-233292D01*
X602342Y-233255D01*
X602371Y-233208D01*
X602404Y-233153D01*
X602433Y-233091D01*
X602458Y-233022D01*
Y-233018D01*
X602462Y-233011D01*
X602465Y-233000D01*
X602469Y-232986D01*
X602473Y-232967D01*
X602480Y-232942D01*
X602487Y-232917D01*
X602495Y-232887D01*
X602505Y-232815D01*
X602516Y-232731D01*
X602524Y-232636D01*
X602527Y-232534D01*
Y-232531D01*
Y-232516D01*
Y-232498D01*
X602524Y-232469D01*
Y-232436D01*
X602520Y-232400D01*
X602516Y-232356D01*
X602513Y-232312D01*
X602495Y-232214D01*
X602473Y-232112D01*
X602440Y-232017D01*
X602418Y-231970D01*
X602396Y-231930D01*
Y-231926D01*
X602389Y-231919D01*
X602382Y-231908D01*
X602374Y-231894D01*
X602345Y-231857D01*
X602309Y-231814D01*
X602262Y-231766D01*
X602207Y-231719D01*
X602145Y-231679D01*
X602080Y-231646D01*
X602072Y-231643D01*
X602054Y-231639D01*
X602021Y-231628D01*
X601974Y-231617D01*
X601916Y-231610D01*
X601843Y-231599D01*
X601799Y-231595D01*
X601752D01*
X601705Y-231592D01*
D02*
G37*
G36*
X603870Y-184628D02*
X603288D01*
Y-186550D01*
X603885D01*
X603910Y-186546D01*
X603965Y-186543D01*
X604027Y-186539D01*
X604092Y-186532D01*
X604158Y-186521D01*
X604212Y-186506D01*
X604219Y-186503D01*
X604238Y-186499D01*
X604263Y-186488D01*
X604296Y-186474D01*
X604332Y-186452D01*
X604369Y-186430D01*
X604405Y-186404D01*
X604441Y-186375D01*
X604445Y-186368D01*
X604460Y-186353D01*
X604482Y-186328D01*
X604507Y-186292D01*
X604536Y-186244D01*
X604569Y-186190D01*
X604598Y-186128D01*
X604624Y-186058D01*
Y-186055D01*
X604627Y-186048D01*
X604631Y-186037D01*
X604634Y-186022D01*
X604638Y-186004D01*
X604645Y-185978D01*
X604653Y-185953D01*
X604660Y-185924D01*
X604671Y-185851D01*
X604682Y-185767D01*
X604689Y-185673D01*
X604693Y-185571D01*
Y-185567D01*
Y-185553D01*
Y-185534D01*
X604689Y-185505D01*
Y-185473D01*
X604685Y-185436D01*
X604682Y-185392D01*
X604678Y-185349D01*
X604660Y-185250D01*
X604638Y-185149D01*
X604605Y-185054D01*
X604584Y-185007D01*
X604562Y-184967D01*
Y-184963D01*
X604554Y-184956D01*
X604547Y-184945D01*
X604540Y-184930D01*
X604511Y-184894D01*
X604474Y-184850D01*
X604427Y-184803D01*
X604372Y-184755D01*
X604311Y-184715D01*
X604245Y-184683D01*
X604238Y-184679D01*
X604219Y-184675D01*
X604187Y-184664D01*
X604139Y-184653D01*
X604081Y-184646D01*
X604008Y-184635D01*
X603965Y-184632D01*
X603917D01*
X603870Y-184628D01*
D02*
G37*
G36*
X602876Y-148422D02*
X602817D01*
X602803Y-148426D01*
X602763Y-148430D01*
X602716Y-148444D01*
X602657Y-148462D01*
X602596Y-148495D01*
X602534Y-148535D01*
X602504Y-148564D01*
X602475Y-148593D01*
Y-148597D01*
X602468Y-148601D01*
X602461Y-148612D01*
X602454Y-148623D01*
X602428Y-148659D01*
X602403Y-148710D01*
X602373Y-148772D01*
X602348Y-148848D01*
X602333Y-148936D01*
X602326Y-149030D01*
Y-149034D01*
Y-149041D01*
Y-149052D01*
X602330Y-149070D01*
Y-149092D01*
X602333Y-149114D01*
X602344Y-149169D01*
X602362Y-149231D01*
X602384Y-149296D01*
X602421Y-149362D01*
X602468Y-149420D01*
X602475Y-149427D01*
X602494Y-149442D01*
X602526Y-149467D01*
X602566Y-149493D01*
X602621Y-149522D01*
X602683Y-149547D01*
X602752Y-149562D01*
X602828Y-149569D01*
X602850D01*
X602865Y-149565D01*
X602905Y-149562D01*
X602952Y-149551D01*
X603010Y-149533D01*
X603069Y-149507D01*
X603127Y-149471D01*
X603182Y-149420D01*
X603189Y-149413D01*
X603203Y-149391D01*
X603225Y-149358D01*
X603254Y-149311D01*
X603280Y-149252D01*
X603302Y-149183D01*
X603316Y-149100D01*
X603324Y-149005D01*
Y-149001D01*
Y-148994D01*
Y-148979D01*
X603320Y-148961D01*
Y-148936D01*
X603316Y-148910D01*
X603305Y-148852D01*
X603291Y-148783D01*
X603265Y-148710D01*
X603229Y-148641D01*
X603182Y-148579D01*
Y-148575D01*
X603174Y-148572D01*
X603156Y-148554D01*
X603127Y-148528D01*
X603087Y-148499D01*
X603036Y-148473D01*
X602978Y-148448D01*
X602912Y-148430D01*
X602876Y-148422D01*
D02*
G37*
G36*
X598555Y-148477D02*
X597973D01*
Y-150399D01*
X598570D01*
X598595Y-150395D01*
X598650Y-150392D01*
X598712Y-150388D01*
X598777Y-150381D01*
X598843Y-150370D01*
X598897Y-150355D01*
X598905Y-150352D01*
X598923Y-150348D01*
X598948Y-150337D01*
X598981Y-150322D01*
X599017Y-150301D01*
X599054Y-150279D01*
X599090Y-150253D01*
X599127Y-150224D01*
X599130Y-150217D01*
X599145Y-150202D01*
X599167Y-150177D01*
X599192Y-150141D01*
X599221Y-150093D01*
X599254Y-150039D01*
X599283Y-149977D01*
X599309Y-149908D01*
Y-149904D01*
X599312Y-149897D01*
X599316Y-149886D01*
X599320Y-149871D01*
X599323Y-149853D01*
X599330Y-149828D01*
X599338Y-149802D01*
X599345Y-149773D01*
X599356Y-149700D01*
X599367Y-149616D01*
X599374Y-149522D01*
X599378Y-149420D01*
Y-149416D01*
Y-149402D01*
Y-149383D01*
X599374Y-149354D01*
Y-149321D01*
X599370Y-149285D01*
X599367Y-149241D01*
X599363Y-149198D01*
X599345Y-149100D01*
X599323Y-148998D01*
X599290Y-148903D01*
X599268Y-148856D01*
X599247Y-148816D01*
Y-148812D01*
X599239Y-148805D01*
X599232Y-148794D01*
X599225Y-148779D01*
X599196Y-148743D01*
X599159Y-148699D01*
X599112Y-148652D01*
X599057Y-148604D01*
X598995Y-148564D01*
X598930Y-148532D01*
X598923Y-148528D01*
X598905Y-148524D01*
X598872Y-148513D01*
X598824Y-148503D01*
X598766Y-148495D01*
X598693Y-148484D01*
X598650Y-148481D01*
X598602D01*
X598555Y-148477D01*
D02*
G37*
G36*
X485502Y-263429D02*
X485480D01*
X485465Y-263433D01*
X485426Y-263440D01*
X485378Y-263451D01*
X485323Y-263473D01*
X485265Y-263506D01*
X485236Y-263528D01*
X485207Y-263549D01*
X485182Y-263579D01*
X485156Y-263611D01*
Y-263615D01*
X485149Y-263622D01*
X485142Y-263637D01*
X485131Y-263655D01*
X485120Y-263684D01*
X485105Y-263717D01*
X485094Y-263757D01*
X485080Y-263804D01*
X485065Y-263859D01*
X485051Y-263921D01*
X485036Y-263990D01*
X485025Y-264066D01*
X485014Y-264154D01*
X485007Y-264248D01*
X485003Y-264350D01*
X485000Y-264463D01*
Y-264470D01*
Y-264489D01*
Y-264521D01*
X485003Y-264565D01*
Y-264612D01*
X485007Y-264671D01*
X485010Y-264733D01*
X485018Y-264798D01*
X485036Y-264940D01*
X485047Y-265009D01*
X485062Y-265075D01*
X485076Y-265137D01*
X485098Y-265195D01*
X485120Y-265246D01*
X485145Y-265289D01*
Y-265293D01*
X485152Y-265297D01*
X485171Y-265322D01*
X485203Y-265355D01*
X485244Y-265391D01*
X485298Y-265428D01*
X485360Y-265460D01*
X485429Y-265486D01*
X485465Y-265490D01*
X485506Y-265493D01*
X485527D01*
X485542Y-265490D01*
X485578Y-265482D01*
X485629Y-265468D01*
X485684Y-265442D01*
X485746Y-265406D01*
X485775Y-265384D01*
X485804Y-265355D01*
X485833Y-265326D01*
X485862Y-265289D01*
Y-265286D01*
X485870Y-265279D01*
X485877Y-265268D01*
X485884Y-265249D01*
X485899Y-265224D01*
X485910Y-265191D01*
X485924Y-265155D01*
X485939Y-265111D01*
X485950Y-265056D01*
X485964Y-264998D01*
X485979Y-264929D01*
X485990Y-264856D01*
X485997Y-264769D01*
X486004Y-264678D01*
X486012Y-264576D01*
Y-264463D01*
Y-264459D01*
Y-264456D01*
Y-264438D01*
Y-264405D01*
X486008Y-264361D01*
Y-264314D01*
X486004Y-264256D01*
X486001Y-264194D01*
X485993Y-264125D01*
X485975Y-263986D01*
X485964Y-263917D01*
X485950Y-263852D01*
X485935Y-263790D01*
X485913Y-263732D01*
X485891Y-263681D01*
X485866Y-263637D01*
Y-263633D01*
X485859Y-263630D01*
X485851Y-263619D01*
X485840Y-263604D01*
X485808Y-263571D01*
X485768Y-263531D01*
X485713Y-263495D01*
X485651Y-263462D01*
X485618Y-263448D01*
X485582Y-263437D01*
X485542Y-263433D01*
X485502Y-263429D01*
D02*
G37*
G36*
X188786Y-34222D02*
X187657D01*
X188786Y-35016D01*
Y-34222D01*
D02*
G37*
G36*
Y-36181D02*
X187657D01*
X188786Y-36974D01*
Y-36181D01*
D02*
G37*
G36*
X533825Y-277454D02*
X533031D01*
Y-278583D01*
X533825Y-277454D01*
D02*
G37*
G36*
X351529Y-120137D02*
X351507D01*
X351492Y-120140D01*
X351448Y-120144D01*
X351397Y-120155D01*
X351339Y-120173D01*
X351277Y-120195D01*
X351219Y-120231D01*
X351161Y-120279D01*
X351154Y-120286D01*
X351139Y-120304D01*
X351114Y-120337D01*
X351088Y-120377D01*
X351063Y-120428D01*
X351037Y-120490D01*
X351023Y-120563D01*
X351015Y-120639D01*
Y-120643D01*
Y-120650D01*
Y-120661D01*
X351019Y-120675D01*
X351023Y-120715D01*
X351033Y-120770D01*
X351052Y-120825D01*
X351077Y-120887D01*
X351114Y-120948D01*
X351165Y-121007D01*
X351172Y-121014D01*
X351190Y-121028D01*
X351223Y-121054D01*
X351267Y-121083D01*
X351321Y-121108D01*
X351387Y-121134D01*
X351459Y-121149D01*
X351539Y-121156D01*
X351561D01*
X351576Y-121152D01*
X351616Y-121149D01*
X351667Y-121138D01*
X351725Y-121119D01*
X351783Y-121094D01*
X351845Y-121058D01*
X351900Y-121010D01*
X351907Y-121003D01*
X351922Y-120985D01*
X351943Y-120952D01*
X351969Y-120912D01*
X351998Y-120857D01*
X352020Y-120796D01*
X352034Y-120726D01*
X352042Y-120650D01*
Y-120643D01*
Y-120628D01*
X352038Y-120603D01*
X352034Y-120570D01*
X352027Y-120530D01*
X352016Y-120486D01*
X352002Y-120442D01*
X351984Y-120395D01*
X351980Y-120391D01*
X351973Y-120373D01*
X351958Y-120351D01*
X351936Y-120326D01*
X351911Y-120293D01*
X351878Y-120260D01*
X351842Y-120231D01*
X351798Y-120202D01*
X351791Y-120199D01*
X351776Y-120191D01*
X351751Y-120180D01*
X351718Y-120169D01*
X351678Y-120159D01*
X351630Y-120148D01*
X351579Y-120140D01*
X351529Y-120137D01*
D02*
G37*
G36*
Y-121407D02*
X351521D01*
X351500Y-121411D01*
X351467Y-121414D01*
X351423Y-121422D01*
X351376Y-121436D01*
X351328Y-121454D01*
X351277Y-121483D01*
X351234Y-121520D01*
X351230Y-121523D01*
X351216Y-121542D01*
X351197Y-121563D01*
X351175Y-121596D01*
X351154Y-121636D01*
X351135Y-121684D01*
X351121Y-121738D01*
X351117Y-121797D01*
Y-121800D01*
Y-121804D01*
Y-121826D01*
X351125Y-121858D01*
X351132Y-121898D01*
X351146Y-121942D01*
X351168Y-121989D01*
X351197Y-122037D01*
X351237Y-122084D01*
X351241Y-122088D01*
X351259Y-122102D01*
X351285Y-122120D01*
X351318Y-122142D01*
X351361Y-122164D01*
X351409Y-122182D01*
X351467Y-122197D01*
X351529Y-122201D01*
X351558D01*
X351590Y-122193D01*
X351634Y-122186D01*
X351681Y-122171D01*
X351732Y-122153D01*
X351780Y-122124D01*
X351827Y-122084D01*
X351831Y-122080D01*
X351845Y-122066D01*
X351864Y-122040D01*
X351882Y-122008D01*
X351904Y-121968D01*
X351922Y-121920D01*
X351936Y-121869D01*
X351940Y-121811D01*
Y-121807D01*
Y-121804D01*
X351936Y-121782D01*
X351933Y-121749D01*
X351925Y-121709D01*
X351911Y-121662D01*
X351893Y-121615D01*
X351864Y-121563D01*
X351827Y-121520D01*
X351823Y-121516D01*
X351805Y-121502D01*
X351780Y-121483D01*
X351747Y-121465D01*
X351703Y-121443D01*
X351652Y-121425D01*
X351594Y-121411D01*
X351529Y-121407D01*
D02*
G37*
G36*
X388739Y-108241D02*
X388736D01*
X388732D01*
X388710D01*
X388677Y-108248D01*
X388637Y-108255D01*
X388594Y-108270D01*
X388546Y-108292D01*
X388499Y-108321D01*
X388452Y-108361D01*
X388448Y-108365D01*
X388433Y-108383D01*
X388415Y-108408D01*
X388393Y-108441D01*
X388372Y-108485D01*
X388353Y-108532D01*
X388339Y-108590D01*
X388335Y-108652D01*
Y-108681D01*
X388342Y-108714D01*
X388350Y-108758D01*
X388364Y-108805D01*
X388383Y-108856D01*
X388412Y-108903D01*
X388452Y-108951D01*
X388455Y-108954D01*
X388470Y-108969D01*
X388495Y-108987D01*
X388528Y-109005D01*
X388568Y-109027D01*
X388615Y-109045D01*
X388666Y-109060D01*
X388725Y-109063D01*
X388728D01*
X388732D01*
X388754Y-109060D01*
X388787Y-109056D01*
X388827Y-109049D01*
X388874Y-109034D01*
X388921Y-109016D01*
X388972Y-108987D01*
X389016Y-108951D01*
X389019Y-108947D01*
X389034Y-108929D01*
X389052Y-108903D01*
X389070Y-108870D01*
X389092Y-108827D01*
X389110Y-108776D01*
X389125Y-108718D01*
X389129Y-108652D01*
Y-108645D01*
X389125Y-108623D01*
X389121Y-108590D01*
X389114Y-108547D01*
X389100Y-108499D01*
X389081Y-108452D01*
X389052Y-108401D01*
X389016Y-108357D01*
X389012Y-108354D01*
X388994Y-108339D01*
X388972Y-108321D01*
X388939Y-108299D01*
X388899Y-108277D01*
X388852Y-108259D01*
X388797Y-108244D01*
X388739Y-108241D01*
D02*
G37*
G36*
X389897Y-108139D02*
X389893D01*
X389886D01*
X389875D01*
X389860Y-108142D01*
X389820Y-108146D01*
X389766Y-108157D01*
X389711Y-108175D01*
X389649Y-108201D01*
X389587Y-108237D01*
X389529Y-108288D01*
X389522Y-108295D01*
X389507Y-108314D01*
X389482Y-108346D01*
X389453Y-108390D01*
X389427Y-108445D01*
X389402Y-108510D01*
X389387Y-108583D01*
X389380Y-108663D01*
Y-108685D01*
X389384Y-108699D01*
X389387Y-108739D01*
X389398Y-108790D01*
X389416Y-108849D01*
X389442Y-108907D01*
X389478Y-108969D01*
X389525Y-109023D01*
X389533Y-109031D01*
X389551Y-109045D01*
X389584Y-109067D01*
X389624Y-109093D01*
X389678Y-109122D01*
X389740Y-109143D01*
X389809Y-109158D01*
X389886Y-109165D01*
X389893D01*
X389908D01*
X389933Y-109162D01*
X389966Y-109158D01*
X390006Y-109151D01*
X390050Y-109140D01*
X390093Y-109125D01*
X390141Y-109107D01*
X390144Y-109104D01*
X390162Y-109096D01*
X390184Y-109082D01*
X390210Y-109060D01*
X390243Y-109034D01*
X390275Y-109002D01*
X390304Y-108965D01*
X390334Y-108922D01*
X390337Y-108914D01*
X390344Y-108900D01*
X390355Y-108874D01*
X390366Y-108841D01*
X390377Y-108801D01*
X390388Y-108754D01*
X390395Y-108703D01*
X390399Y-108652D01*
Y-108630D01*
X390395Y-108616D01*
X390392Y-108572D01*
X390381Y-108521D01*
X390363Y-108463D01*
X390341Y-108401D01*
X390304Y-108343D01*
X390257Y-108284D01*
X390250Y-108277D01*
X390232Y-108263D01*
X390199Y-108237D01*
X390159Y-108212D01*
X390108Y-108186D01*
X390046Y-108161D01*
X389973Y-108146D01*
X389897Y-108139D01*
D02*
G37*
G36*
X351529Y-113444D02*
X351507D01*
X351492Y-113447D01*
X351448Y-113451D01*
X351397Y-113462D01*
X351339Y-113480D01*
X351277Y-113502D01*
X351219Y-113538D01*
X351161Y-113586D01*
X351154Y-113593D01*
X351139Y-113611D01*
X351114Y-113644D01*
X351088Y-113684D01*
X351063Y-113735D01*
X351037Y-113797D01*
X351023Y-113870D01*
X351015Y-113946D01*
Y-113950D01*
Y-113957D01*
Y-113968D01*
X351019Y-113982D01*
X351023Y-114023D01*
X351033Y-114077D01*
X351052Y-114132D01*
X351077Y-114194D01*
X351114Y-114255D01*
X351165Y-114314D01*
X351172Y-114321D01*
X351190Y-114336D01*
X351223Y-114361D01*
X351267Y-114390D01*
X351321Y-114416D01*
X351387Y-114441D01*
X351459Y-114456D01*
X351539Y-114463D01*
X351561D01*
X351576Y-114459D01*
X351616Y-114456D01*
X351667Y-114445D01*
X351725Y-114427D01*
X351783Y-114401D01*
X351845Y-114365D01*
X351900Y-114317D01*
X351907Y-114310D01*
X351922Y-114292D01*
X351943Y-114259D01*
X351969Y-114219D01*
X351998Y-114164D01*
X352020Y-114103D01*
X352034Y-114033D01*
X352042Y-113957D01*
Y-113950D01*
Y-113935D01*
X352038Y-113910D01*
X352034Y-113877D01*
X352027Y-113837D01*
X352016Y-113793D01*
X352002Y-113750D01*
X351984Y-113702D01*
X351980Y-113699D01*
X351973Y-113680D01*
X351958Y-113658D01*
X351936Y-113633D01*
X351911Y-113600D01*
X351878Y-113567D01*
X351842Y-113538D01*
X351798Y-113509D01*
X351791Y-113506D01*
X351776Y-113498D01*
X351751Y-113487D01*
X351718Y-113477D01*
X351678Y-113466D01*
X351630Y-113455D01*
X351579Y-113447D01*
X351529Y-113444D01*
D02*
G37*
G36*
Y-114714D02*
X351521D01*
X351500Y-114718D01*
X351467Y-114721D01*
X351423Y-114729D01*
X351376Y-114743D01*
X351328Y-114761D01*
X351277Y-114791D01*
X351234Y-114827D01*
X351230Y-114831D01*
X351216Y-114849D01*
X351197Y-114871D01*
X351175Y-114903D01*
X351154Y-114943D01*
X351135Y-114991D01*
X351121Y-115045D01*
X351117Y-115104D01*
Y-115107D01*
Y-115111D01*
Y-115133D01*
X351125Y-115165D01*
X351132Y-115206D01*
X351146Y-115249D01*
X351168Y-115296D01*
X351197Y-115344D01*
X351237Y-115391D01*
X351241Y-115395D01*
X351259Y-115409D01*
X351285Y-115427D01*
X351318Y-115449D01*
X351361Y-115471D01*
X351409Y-115489D01*
X351467Y-115504D01*
X351529Y-115508D01*
X351558D01*
X351590Y-115500D01*
X351634Y-115493D01*
X351681Y-115479D01*
X351732Y-115460D01*
X351780Y-115431D01*
X351827Y-115391D01*
X351831Y-115387D01*
X351845Y-115373D01*
X351864Y-115348D01*
X351882Y-115315D01*
X351904Y-115275D01*
X351922Y-115227D01*
X351936Y-115176D01*
X351940Y-115118D01*
Y-115114D01*
Y-115111D01*
X351936Y-115089D01*
X351933Y-115056D01*
X351925Y-115016D01*
X351911Y-114969D01*
X351893Y-114922D01*
X351864Y-114871D01*
X351827Y-114827D01*
X351823Y-114823D01*
X351805Y-114809D01*
X351780Y-114791D01*
X351747Y-114772D01*
X351703Y-114751D01*
X351652Y-114732D01*
X351594Y-114718D01*
X351529Y-114714D01*
D02*
G37*
G36*
X382096Y-106012D02*
X381983D01*
X381979D01*
X381976D01*
X381957D01*
X381925D01*
X381881Y-106016D01*
X381834D01*
X381775Y-106020D01*
X381714Y-106024D01*
X381644Y-106031D01*
X381506Y-106049D01*
X381437Y-106060D01*
X381371Y-106074D01*
X381309Y-106089D01*
X381251Y-106111D01*
X381200Y-106133D01*
X381156Y-106158D01*
X381153D01*
X381149Y-106165D01*
X381138Y-106173D01*
X381124Y-106184D01*
X381091Y-106216D01*
X381051Y-106256D01*
X381015Y-106311D01*
X380982Y-106373D01*
X380967Y-106406D01*
X380956Y-106442D01*
X380953Y-106482D01*
X380949Y-106522D01*
Y-106544D01*
X380953Y-106559D01*
X380960Y-106599D01*
X380971Y-106646D01*
X380993Y-106701D01*
X381026Y-106759D01*
X381047Y-106788D01*
X381069Y-106817D01*
X381098Y-106843D01*
X381131Y-106868D01*
X381135D01*
X381142Y-106875D01*
X381156Y-106883D01*
X381175Y-106893D01*
X381204Y-106904D01*
X381237Y-106919D01*
X381277Y-106930D01*
X381324Y-106944D01*
X381379Y-106959D01*
X381440Y-106974D01*
X381510Y-106988D01*
X381586Y-106999D01*
X381673Y-107010D01*
X381768Y-107017D01*
X381870Y-107021D01*
X381983Y-107025D01*
X381990D01*
X382008D01*
X382041D01*
X382085Y-107021D01*
X382132D01*
X382190Y-107017D01*
X382252Y-107013D01*
X382318Y-107006D01*
X382460Y-106988D01*
X382529Y-106977D01*
X382594Y-106963D01*
X382656Y-106948D01*
X382715Y-106926D01*
X382765Y-106904D01*
X382809Y-106879D01*
X382813D01*
X382816Y-106872D01*
X382842Y-106853D01*
X382875Y-106821D01*
X382911Y-106781D01*
X382947Y-106726D01*
X382980Y-106664D01*
X383006Y-106595D01*
X383009Y-106559D01*
X383013Y-106518D01*
Y-106497D01*
X383009Y-106482D01*
X383002Y-106446D01*
X382987Y-106395D01*
X382962Y-106340D01*
X382926Y-106278D01*
X382904Y-106249D01*
X382875Y-106220D01*
X382845Y-106191D01*
X382809Y-106162D01*
X382805D01*
X382798Y-106155D01*
X382787Y-106147D01*
X382769Y-106140D01*
X382744Y-106125D01*
X382711Y-106114D01*
X382674Y-106100D01*
X382631Y-106085D01*
X382576Y-106074D01*
X382518Y-106060D01*
X382449Y-106045D01*
X382376Y-106034D01*
X382289Y-106027D01*
X382198Y-106020D01*
X382096Y-106012D01*
D02*
G37*
G36*
X381353Y-108062D02*
X381349D01*
X381346D01*
X381324D01*
X381291Y-108069D01*
X381251Y-108076D01*
X381207Y-108091D01*
X381160Y-108113D01*
X381113Y-108142D01*
X381066Y-108182D01*
X381062Y-108186D01*
X381047Y-108204D01*
X381029Y-108229D01*
X381007Y-108262D01*
X380985Y-108306D01*
X380967Y-108353D01*
X380953Y-108411D01*
X380949Y-108473D01*
Y-108502D01*
X380956Y-108535D01*
X380964Y-108579D01*
X380978Y-108626D01*
X380996Y-108677D01*
X381026Y-108724D01*
X381066Y-108772D01*
X381069Y-108775D01*
X381084Y-108790D01*
X381109Y-108808D01*
X381142Y-108826D01*
X381182Y-108848D01*
X381229Y-108866D01*
X381280Y-108881D01*
X381339Y-108885D01*
X381342D01*
X381346D01*
X381368Y-108881D01*
X381400Y-108877D01*
X381440Y-108870D01*
X381488Y-108855D01*
X381535Y-108837D01*
X381586Y-108808D01*
X381630Y-108772D01*
X381633Y-108768D01*
X381648Y-108750D01*
X381666Y-108724D01*
X381684Y-108692D01*
X381706Y-108648D01*
X381724Y-108597D01*
X381739Y-108539D01*
X381743Y-108473D01*
Y-108466D01*
X381739Y-108444D01*
X381735Y-108411D01*
X381728Y-108368D01*
X381714Y-108320D01*
X381695Y-108273D01*
X381666Y-108222D01*
X381630Y-108178D01*
X381626Y-108175D01*
X381608Y-108160D01*
X381586Y-108142D01*
X381553Y-108120D01*
X381513Y-108098D01*
X381466Y-108080D01*
X381411Y-108065D01*
X381353Y-108062D01*
D02*
G37*
G36*
X382511Y-107960D02*
X382507D01*
X382500D01*
X382489D01*
X382474Y-107964D01*
X382434Y-107967D01*
X382380Y-107978D01*
X382325Y-107996D01*
X382263Y-108022D01*
X382201Y-108058D01*
X382143Y-108109D01*
X382136Y-108116D01*
X382121Y-108135D01*
X382096Y-108167D01*
X382066Y-108211D01*
X382041Y-108266D01*
X382016Y-108331D01*
X382001Y-108404D01*
X381994Y-108484D01*
Y-108506D01*
X381997Y-108520D01*
X382001Y-108561D01*
X382012Y-108612D01*
X382030Y-108670D01*
X382056Y-108728D01*
X382092Y-108790D01*
X382139Y-108844D01*
X382147Y-108852D01*
X382165Y-108866D01*
X382198Y-108888D01*
X382238Y-108914D01*
X382292Y-108943D01*
X382354Y-108965D01*
X382423Y-108979D01*
X382500Y-108986D01*
X382507D01*
X382522D01*
X382547Y-108983D01*
X382580Y-108979D01*
X382620Y-108972D01*
X382663Y-108961D01*
X382707Y-108946D01*
X382754Y-108928D01*
X382758Y-108924D01*
X382776Y-108917D01*
X382798Y-108903D01*
X382824Y-108881D01*
X382856Y-108855D01*
X382889Y-108823D01*
X382918Y-108786D01*
X382947Y-108742D01*
X382951Y-108735D01*
X382958Y-108721D01*
X382969Y-108695D01*
X382980Y-108662D01*
X382991Y-108622D01*
X383002Y-108575D01*
X383009Y-108524D01*
X383013Y-108473D01*
Y-108451D01*
X383009Y-108437D01*
X383006Y-108393D01*
X382995Y-108342D01*
X382977Y-108284D01*
X382955Y-108222D01*
X382918Y-108164D01*
X382871Y-108106D01*
X382864Y-108098D01*
X382845Y-108084D01*
X382813Y-108058D01*
X382773Y-108033D01*
X382722Y-108007D01*
X382660Y-107982D01*
X382587Y-107967D01*
X382511Y-107960D01*
D02*
G37*
G36*
X65919Y14176D02*
X65897D01*
X65882Y14172D01*
X65842Y14165D01*
X65795Y14154D01*
X65741Y14132D01*
X65682Y14099D01*
X65653Y14078D01*
X65624Y14056D01*
X65598Y14027D01*
X65573Y13994D01*
Y13990D01*
X65566Y13983D01*
X65558Y13969D01*
X65548Y13950D01*
X65537Y13921D01*
X65522Y13888D01*
X65511Y13848D01*
X65497Y13801D01*
X65482Y13747D01*
X65468Y13685D01*
X65453Y13615D01*
X65442Y13539D01*
X65431Y13452D01*
X65424Y13357D01*
X65420Y13255D01*
X65417Y13142D01*
Y13135D01*
Y13117D01*
Y13084D01*
X65420Y13040D01*
Y12993D01*
X65424Y12935D01*
X65427Y12873D01*
X65435Y12807D01*
X65453Y12665D01*
X65464Y12596D01*
X65478Y12531D01*
X65493Y12469D01*
X65515Y12411D01*
X65537Y12360D01*
X65562Y12316D01*
Y12312D01*
X65569Y12309D01*
X65588Y12283D01*
X65620Y12250D01*
X65660Y12214D01*
X65715Y12178D01*
X65777Y12145D01*
X65846Y12119D01*
X65882Y12116D01*
X65922Y12112D01*
X65944D01*
X65959Y12116D01*
X65995Y12123D01*
X66046Y12138D01*
X66101Y12163D01*
X66163Y12200D01*
X66192Y12221D01*
X66221Y12250D01*
X66250Y12280D01*
X66279Y12316D01*
Y12320D01*
X66286Y12327D01*
X66294Y12338D01*
X66301Y12356D01*
X66316Y12382D01*
X66326Y12414D01*
X66341Y12451D01*
X66356Y12494D01*
X66367Y12549D01*
X66381Y12607D01*
X66396Y12676D01*
X66407Y12749D01*
X66414Y12836D01*
X66421Y12927D01*
X66428Y13029D01*
Y13142D01*
Y13146D01*
Y13149D01*
Y13168D01*
Y13201D01*
X66425Y13244D01*
Y13292D01*
X66421Y13350D01*
X66417Y13412D01*
X66410Y13481D01*
X66392Y13619D01*
X66381Y13688D01*
X66367Y13754D01*
X66352Y13816D01*
X66330Y13874D01*
X66308Y13925D01*
X66283Y13969D01*
Y13972D01*
X66276Y13976D01*
X66268Y13987D01*
X66257Y14001D01*
X66225Y14034D01*
X66185Y14074D01*
X66130Y14110D01*
X66068Y14143D01*
X66035Y14158D01*
X65999Y14169D01*
X65959Y14172D01*
X65919Y14176D01*
D02*
G37*
G36*
X378846Y-139200D02*
X378843D01*
X378835D01*
X378821D01*
X378803Y-139204D01*
X378777D01*
X378752Y-139207D01*
X378693Y-139218D01*
X378624Y-139233D01*
X378552Y-139258D01*
X378482Y-139295D01*
X378420Y-139342D01*
X378417D01*
X378413Y-139349D01*
X378395Y-139367D01*
X378369Y-139397D01*
X378340Y-139436D01*
X378315Y-139488D01*
X378289Y-139546D01*
X378271Y-139611D01*
X378264Y-139648D01*
Y-139706D01*
X378268Y-139720D01*
X378271Y-139760D01*
X378286Y-139808D01*
X378304Y-139866D01*
X378337Y-139928D01*
X378377Y-139990D01*
X378406Y-140019D01*
X378435Y-140048D01*
X378439D01*
X378442Y-140055D01*
X378453Y-140063D01*
X378464Y-140070D01*
X378501Y-140095D01*
X378552Y-140121D01*
X378613Y-140150D01*
X378690Y-140175D01*
X378777Y-140190D01*
X378872Y-140197D01*
X378875D01*
X378883D01*
X378894D01*
X378912Y-140194D01*
X378934D01*
X378956Y-140190D01*
X379010Y-140179D01*
X379072Y-140161D01*
X379137Y-140139D01*
X379203Y-140103D01*
X379261Y-140055D01*
X379269Y-140048D01*
X379283Y-140030D01*
X379309Y-139997D01*
X379334Y-139957D01*
X379363Y-139902D01*
X379389Y-139840D01*
X379403Y-139771D01*
X379411Y-139695D01*
Y-139673D01*
X379407Y-139658D01*
X379403Y-139619D01*
X379392Y-139571D01*
X379374Y-139513D01*
X379349Y-139455D01*
X379312Y-139397D01*
X379261Y-139342D01*
X379254Y-139335D01*
X379232Y-139320D01*
X379199Y-139298D01*
X379152Y-139269D01*
X379094Y-139244D01*
X379025Y-139222D01*
X378941Y-139207D01*
X378846Y-139200D01*
D02*
G37*
G36*
X442466Y-111517D02*
X442463D01*
X442455D01*
X442441D01*
X442423Y-111521D01*
X442401D01*
X442375Y-111524D01*
X442317Y-111535D01*
X442251Y-111550D01*
X442182Y-111575D01*
X442117Y-111612D01*
X442055Y-111659D01*
X442048Y-111666D01*
X442029Y-111685D01*
X442008Y-111714D01*
X441979Y-111754D01*
X441949Y-111805D01*
X441928Y-111863D01*
X441909Y-111932D01*
X441902Y-112009D01*
Y-112030D01*
X441906Y-112045D01*
X441909Y-112081D01*
X441920Y-112132D01*
X441938Y-112187D01*
X441968Y-112249D01*
X442004Y-112307D01*
X442055Y-112365D01*
X442062Y-112373D01*
X442080Y-112387D01*
X442113Y-112413D01*
X442161Y-112438D01*
X442215Y-112463D01*
X442284Y-112489D01*
X442361Y-112504D01*
X442448Y-112511D01*
X442455D01*
X442474D01*
X442506Y-112507D01*
X442546Y-112504D01*
X442594Y-112496D01*
X442645Y-112482D01*
X442699Y-112467D01*
X442754Y-112445D01*
X442761Y-112442D01*
X442779Y-112431D01*
X442805Y-112416D01*
X442838Y-112394D01*
X442870Y-112369D01*
X442910Y-112336D01*
X442943Y-112300D01*
X442976Y-112256D01*
X442979Y-112249D01*
X442987Y-112234D01*
X443001Y-112209D01*
X443012Y-112176D01*
X443027Y-112139D01*
X443041Y-112096D01*
X443049Y-112048D01*
X443052Y-111998D01*
Y-111979D01*
X443049Y-111965D01*
X443045Y-111928D01*
X443034Y-111881D01*
X443012Y-111830D01*
X442987Y-111772D01*
X442947Y-111714D01*
X442925Y-111685D01*
X442896Y-111659D01*
X442892D01*
X442888Y-111652D01*
X442867Y-111637D01*
X442830Y-111615D01*
X442783Y-111586D01*
X442721Y-111561D01*
X442648Y-111539D01*
X442565Y-111524D01*
X442466Y-111517D01*
D02*
G37*
G36*
X363601Y-112066D02*
X363580D01*
X363565Y-112069D01*
X363521Y-112073D01*
X363470Y-112084D01*
X363412Y-112102D01*
X363350Y-112124D01*
X363292Y-112160D01*
X363234Y-112208D01*
X363227Y-112215D01*
X363212Y-112233D01*
X363187Y-112266D01*
X363161Y-112306D01*
X363136Y-112357D01*
X363110Y-112419D01*
X363095Y-112492D01*
X363088Y-112568D01*
Y-112572D01*
Y-112579D01*
Y-112590D01*
X363092Y-112604D01*
X363095Y-112645D01*
X363106Y-112699D01*
X363125Y-112754D01*
X363150Y-112816D01*
X363187Y-112878D01*
X363238Y-112936D01*
X363245Y-112943D01*
X363263Y-112958D01*
X363296Y-112983D01*
X363339Y-113012D01*
X363394Y-113038D01*
X363459Y-113063D01*
X363532Y-113078D01*
X363612Y-113085D01*
X363634D01*
X363649Y-113081D01*
X363689Y-113078D01*
X363740Y-113067D01*
X363798Y-113049D01*
X363856Y-113023D01*
X363918Y-112987D01*
X363973Y-112939D01*
X363980Y-112932D01*
X363995Y-112914D01*
X364016Y-112881D01*
X364042Y-112841D01*
X364071Y-112786D01*
X364093Y-112725D01*
X364107Y-112655D01*
X364115Y-112579D01*
Y-112572D01*
Y-112557D01*
X364111Y-112532D01*
X364107Y-112499D01*
X364100Y-112459D01*
X364089Y-112415D01*
X364075Y-112372D01*
X364056Y-112324D01*
X364053Y-112321D01*
X364046Y-112302D01*
X364031Y-112280D01*
X364009Y-112255D01*
X363984Y-112222D01*
X363951Y-112190D01*
X363914Y-112160D01*
X363871Y-112131D01*
X363864Y-112128D01*
X363849Y-112120D01*
X363824Y-112109D01*
X363791Y-112099D01*
X363751Y-112088D01*
X363703Y-112077D01*
X363652Y-112069D01*
X363601Y-112066D01*
D02*
G37*
G36*
Y-113336D02*
X363594D01*
X363572Y-113340D01*
X363540Y-113343D01*
X363496Y-113351D01*
X363449Y-113365D01*
X363401Y-113383D01*
X363350Y-113413D01*
X363307Y-113449D01*
X363303Y-113453D01*
X363288Y-113471D01*
X363270Y-113493D01*
X363248Y-113525D01*
X363227Y-113566D01*
X363208Y-113613D01*
X363194Y-113667D01*
X363190Y-113726D01*
Y-113729D01*
Y-113733D01*
Y-113755D01*
X363197Y-113787D01*
X363205Y-113828D01*
X363219Y-113871D01*
X363241Y-113919D01*
X363270Y-113966D01*
X363310Y-114013D01*
X363314Y-114017D01*
X363332Y-114031D01*
X363358Y-114050D01*
X363390Y-114071D01*
X363434Y-114093D01*
X363481Y-114111D01*
X363540Y-114126D01*
X363601Y-114130D01*
X363631D01*
X363663Y-114122D01*
X363707Y-114115D01*
X363754Y-114101D01*
X363805Y-114082D01*
X363853Y-114053D01*
X363900Y-114013D01*
X363904Y-114009D01*
X363918Y-113995D01*
X363936Y-113970D01*
X363955Y-113937D01*
X363976Y-113897D01*
X363995Y-113849D01*
X364009Y-113798D01*
X364013Y-113740D01*
Y-113737D01*
Y-113733D01*
X364009Y-113711D01*
X364005Y-113678D01*
X363998Y-113638D01*
X363984Y-113591D01*
X363966Y-113544D01*
X363936Y-113493D01*
X363900Y-113449D01*
X363896Y-113445D01*
X363878Y-113431D01*
X363853Y-113413D01*
X363820Y-113394D01*
X363776Y-113373D01*
X363725Y-113354D01*
X363667Y-113340D01*
X363601Y-113336D01*
D02*
G37*
G36*
X349958Y-152618D02*
X349165Y-153746D01*
X349958D01*
Y-152618D01*
D02*
G37*
G36*
X351754Y-132281D02*
X351695D01*
X351681Y-132284D01*
X351641Y-132288D01*
X351593Y-132302D01*
X351535Y-132321D01*
X351473Y-132353D01*
X351411Y-132394D01*
X351382Y-132423D01*
X351353Y-132452D01*
Y-132455D01*
X351346Y-132459D01*
X351339Y-132470D01*
X351331Y-132481D01*
X351306Y-132517D01*
X351280Y-132568D01*
X351251Y-132630D01*
X351226Y-132707D01*
X351211Y-132794D01*
X351204Y-132889D01*
Y-132892D01*
Y-132899D01*
Y-132910D01*
X351208Y-132929D01*
Y-132950D01*
X351211Y-132972D01*
X351222Y-133027D01*
X351240Y-133089D01*
X351262Y-133154D01*
X351299Y-133220D01*
X351346Y-133278D01*
X351353Y-133285D01*
X351371Y-133300D01*
X351404Y-133325D01*
X351444Y-133351D01*
X351499Y-133380D01*
X351561Y-133405D01*
X351630Y-133420D01*
X351706Y-133427D01*
X351728D01*
X351743Y-133424D01*
X351783Y-133420D01*
X351830Y-133409D01*
X351888Y-133391D01*
X351946Y-133365D01*
X352005Y-133329D01*
X352059Y-133278D01*
X352067Y-133271D01*
X352081Y-133249D01*
X352103Y-133216D01*
X352132Y-133169D01*
X352158Y-133111D01*
X352179Y-133042D01*
X352194Y-132958D01*
X352201Y-132863D01*
Y-132860D01*
Y-132852D01*
Y-132838D01*
X352198Y-132819D01*
Y-132794D01*
X352194Y-132768D01*
X352183Y-132710D01*
X352168Y-132641D01*
X352143Y-132568D01*
X352107Y-132499D01*
X352059Y-132437D01*
Y-132434D01*
X352052Y-132430D01*
X352034Y-132412D01*
X352005Y-132386D01*
X351965Y-132357D01*
X351914Y-132332D01*
X351855Y-132306D01*
X351790Y-132288D01*
X351754Y-132281D01*
D02*
G37*
G36*
X91003Y-77356D02*
X90209D01*
Y-78484D01*
X91003Y-77356D01*
D02*
G37*
G36*
X455445Y-74855D02*
X454862D01*
Y-76777D01*
X455459D01*
X455485Y-76773D01*
X455540Y-76770D01*
X455601Y-76766D01*
X455667Y-76759D01*
X455732Y-76748D01*
X455787Y-76733D01*
X455794Y-76730D01*
X455813Y-76726D01*
X455838Y-76715D01*
X455871Y-76701D01*
X455907Y-76679D01*
X455943Y-76657D01*
X455980Y-76631D01*
X456016Y-76602D01*
X456020Y-76595D01*
X456035Y-76580D01*
X456056Y-76555D01*
X456082Y-76518D01*
X456111Y-76471D01*
X456144Y-76417D01*
X456173Y-76355D01*
X456198Y-76285D01*
Y-76282D01*
X456202Y-76275D01*
X456206Y-76264D01*
X456209Y-76249D01*
X456213Y-76231D01*
X456220Y-76205D01*
X456227Y-76180D01*
X456235Y-76151D01*
X456246Y-76078D01*
X456257Y-75994D01*
X456264Y-75900D01*
X456267Y-75798D01*
Y-75794D01*
Y-75780D01*
Y-75761D01*
X456264Y-75732D01*
Y-75700D01*
X456260Y-75663D01*
X456257Y-75619D01*
X456253Y-75576D01*
X456235Y-75477D01*
X456213Y-75375D01*
X456180Y-75281D01*
X456158Y-75234D01*
X456136Y-75194D01*
Y-75190D01*
X456129Y-75183D01*
X456122Y-75172D01*
X456115Y-75157D01*
X456085Y-75121D01*
X456049Y-75077D01*
X456002Y-75030D01*
X455947Y-74982D01*
X455885Y-74942D01*
X455820Y-74910D01*
X455813Y-74906D01*
X455794Y-74902D01*
X455761Y-74891D01*
X455714Y-74880D01*
X455656Y-74873D01*
X455583Y-74862D01*
X455540Y-74859D01*
X455492D01*
X455445Y-74855D01*
D02*
G37*
G36*
X459718Y-74800D02*
X459696D01*
X459682Y-74804D01*
X459642Y-74811D01*
X459594Y-74822D01*
X459540Y-74844D01*
X459482Y-74877D01*
X459452Y-74899D01*
X459423Y-74920D01*
X459398Y-74950D01*
X459372Y-74982D01*
Y-74986D01*
X459365Y-74993D01*
X459358Y-75008D01*
X459347Y-75026D01*
X459336Y-75055D01*
X459321Y-75088D01*
X459310Y-75128D01*
X459296Y-75175D01*
X459281Y-75230D01*
X459267Y-75292D01*
X459252Y-75361D01*
X459241Y-75437D01*
X459230Y-75525D01*
X459223Y-75619D01*
X459220Y-75721D01*
X459216Y-75834D01*
Y-75841D01*
Y-75860D01*
Y-75892D01*
X459220Y-75936D01*
Y-75983D01*
X459223Y-76042D01*
X459227Y-76104D01*
X459234Y-76169D01*
X459252Y-76311D01*
X459263Y-76380D01*
X459278Y-76446D01*
X459292Y-76508D01*
X459314Y-76566D01*
X459336Y-76617D01*
X459362Y-76660D01*
Y-76664D01*
X459369Y-76668D01*
X459387Y-76693D01*
X459420Y-76726D01*
X459460Y-76762D01*
X459514Y-76799D01*
X459576Y-76832D01*
X459645Y-76857D01*
X459682Y-76861D01*
X459722Y-76864D01*
X459744D01*
X459758Y-76861D01*
X459795Y-76853D01*
X459846Y-76839D01*
X459900Y-76813D01*
X459962Y-76777D01*
X459991Y-76755D01*
X460020Y-76726D01*
X460049Y-76697D01*
X460079Y-76660D01*
Y-76657D01*
X460086Y-76649D01*
X460093Y-76639D01*
X460100Y-76620D01*
X460115Y-76595D01*
X460126Y-76562D01*
X460140Y-76526D01*
X460155Y-76482D01*
X460166Y-76428D01*
X460181Y-76369D01*
X460195Y-76300D01*
X460206Y-76227D01*
X460213Y-76140D01*
X460220Y-76049D01*
X460228Y-75947D01*
Y-75834D01*
Y-75831D01*
Y-75827D01*
Y-75809D01*
Y-75776D01*
X460224Y-75732D01*
Y-75685D01*
X460220Y-75627D01*
X460217Y-75565D01*
X460210Y-75496D01*
X460191Y-75357D01*
X460181Y-75288D01*
X460166Y-75223D01*
X460151Y-75161D01*
X460129Y-75103D01*
X460108Y-75052D01*
X460082Y-75008D01*
Y-75004D01*
X460075Y-75001D01*
X460068Y-74990D01*
X460057Y-74975D01*
X460024Y-74942D01*
X459984Y-74902D01*
X459929Y-74866D01*
X459867Y-74833D01*
X459835Y-74819D01*
X459798Y-74808D01*
X459758Y-74804D01*
X459718Y-74800D01*
D02*
G37*
G36*
X94941Y-91683D02*
X94344D01*
X94318Y-91687D01*
X94264Y-91691D01*
X94202Y-91694D01*
X94136Y-91702D01*
X94071Y-91712D01*
X94016Y-91727D01*
X94009Y-91731D01*
X93991Y-91734D01*
X93965Y-91745D01*
X93932Y-91760D01*
X93896Y-91782D01*
X93860Y-91803D01*
X93823Y-91829D01*
X93787Y-91858D01*
X93783Y-91865D01*
X93769Y-91880D01*
X93747Y-91905D01*
X93721Y-91942D01*
X93692Y-91989D01*
X93659Y-92044D01*
X93630Y-92106D01*
X93605Y-92175D01*
Y-92178D01*
X93601Y-92186D01*
X93598Y-92197D01*
X93594Y-92211D01*
X93590Y-92229D01*
X93583Y-92255D01*
X93576Y-92280D01*
X93568Y-92309D01*
X93558Y-92382D01*
X93547Y-92466D01*
X93539Y-92561D01*
X93536Y-92663D01*
Y-92666D01*
Y-92681D01*
Y-92699D01*
X93539Y-92728D01*
Y-92761D01*
X93543Y-92797D01*
X93547Y-92841D01*
X93550Y-92884D01*
X93568Y-92983D01*
X93590Y-93085D01*
X93623Y-93179D01*
X93645Y-93227D01*
X93667Y-93267D01*
Y-93270D01*
X93674Y-93278D01*
X93681Y-93289D01*
X93688Y-93303D01*
X93718Y-93340D01*
X93754Y-93383D01*
X93801Y-93431D01*
X93856Y-93478D01*
X93918Y-93518D01*
X93983Y-93551D01*
X93991Y-93554D01*
X94009Y-93558D01*
X94042Y-93569D01*
X94089Y-93580D01*
X94147Y-93587D01*
X94220Y-93598D01*
X94264Y-93602D01*
X94311D01*
X94358Y-93605D01*
X94941D01*
Y-91683D01*
D02*
G37*
G36*
X92666Y-92273D02*
X91872D01*
Y-93401D01*
X92666Y-92273D01*
D02*
G37*
G36*
X96404Y-97368D02*
X95610D01*
Y-98201D01*
X96360D01*
X96404Y-98198D01*
X96455Y-98194D01*
X96513Y-98190D01*
X96571Y-98183D01*
X96630Y-98172D01*
X96681Y-98158D01*
X96688Y-98154D01*
X96702Y-98147D01*
X96724Y-98136D01*
X96753Y-98121D01*
X96786Y-98099D01*
X96819Y-98074D01*
X96852Y-98041D01*
X96877Y-98005D01*
X96881Y-98001D01*
X96888Y-97987D01*
X96899Y-97965D01*
X96913Y-97936D01*
X96924Y-97903D01*
X96935Y-97866D01*
X96943Y-97823D01*
X96946Y-97779D01*
Y-97775D01*
Y-97772D01*
X96943Y-97750D01*
X96939Y-97717D01*
X96932Y-97673D01*
X96913Y-97630D01*
X96892Y-97579D01*
X96859Y-97532D01*
X96815Y-97484D01*
X96808Y-97481D01*
X96790Y-97466D01*
X96761Y-97448D01*
X96713Y-97426D01*
X96659Y-97404D01*
X96586Y-97386D01*
X96502Y-97371D01*
X96404Y-97368D01*
D02*
G37*
G36*
X469350Y-77783D02*
X468600D01*
X468557Y-77787D01*
X468506Y-77790D01*
X468447Y-77794D01*
X468389Y-77801D01*
X468331Y-77812D01*
X468280Y-77827D01*
X468273Y-77830D01*
X468258Y-77838D01*
X468236Y-77849D01*
X468207Y-77863D01*
X468175Y-77885D01*
X468142Y-77910D01*
X468109Y-77943D01*
X468083Y-77979D01*
X468080Y-77983D01*
X468073Y-77998D01*
X468062Y-78019D01*
X468047Y-78049D01*
X468036Y-78081D01*
X468025Y-78118D01*
X468018Y-78162D01*
X468014Y-78205D01*
Y-78209D01*
Y-78212D01*
X468018Y-78234D01*
X468022Y-78267D01*
X468029Y-78311D01*
X468047Y-78354D01*
X468069Y-78405D01*
X468102Y-78453D01*
X468145Y-78500D01*
X468153Y-78504D01*
X468171Y-78518D01*
X468200Y-78536D01*
X468247Y-78558D01*
X468302Y-78580D01*
X468375Y-78598D01*
X468458Y-78613D01*
X468557Y-78616D01*
X469350D01*
Y-77783D01*
D02*
G37*
G36*
X606149Y-219197D02*
X605356Y-220325D01*
X606149D01*
Y-219197D01*
D02*
G37*
G36*
X601705Y-218993D02*
X601122D01*
Y-220915D01*
X601719D01*
X601745Y-220911D01*
X601799Y-220908D01*
X601861Y-220904D01*
X601927Y-220897D01*
X601992Y-220886D01*
X602047Y-220871D01*
X602054Y-220868D01*
X602072Y-220864D01*
X602098Y-220853D01*
X602131Y-220839D01*
X602167Y-220817D01*
X602203Y-220795D01*
X602240Y-220770D01*
X602276Y-220740D01*
X602280Y-220733D01*
X602294Y-220719D01*
X602316Y-220693D01*
X602342Y-220657D01*
X602371Y-220609D01*
X602404Y-220555D01*
X602433Y-220493D01*
X602458Y-220424D01*
Y-220420D01*
X602462Y-220413D01*
X602465Y-220402D01*
X602469Y-220387D01*
X602473Y-220369D01*
X602480Y-220344D01*
X602487Y-220318D01*
X602495Y-220289D01*
X602505Y-220216D01*
X602516Y-220132D01*
X602524Y-220038D01*
X602527Y-219936D01*
Y-219932D01*
Y-219918D01*
Y-219900D01*
X602524Y-219870D01*
Y-219838D01*
X602520Y-219801D01*
X602516Y-219758D01*
X602513Y-219714D01*
X602495Y-219616D01*
X602473Y-219514D01*
X602440Y-219419D01*
X602418Y-219372D01*
X602396Y-219332D01*
Y-219328D01*
X602389Y-219321D01*
X602382Y-219310D01*
X602374Y-219295D01*
X602345Y-219259D01*
X602309Y-219215D01*
X602262Y-219168D01*
X602207Y-219121D01*
X602145Y-219080D01*
X602080Y-219048D01*
X602072Y-219044D01*
X602054Y-219040D01*
X602021Y-219030D01*
X601974Y-219019D01*
X601916Y-219011D01*
X601843Y-219000D01*
X601799Y-218997D01*
X601752D01*
X601705Y-218993D01*
D02*
G37*
G36*
Y-225292D02*
X601122D01*
Y-227214D01*
X601719D01*
X601745Y-227211D01*
X601799Y-227207D01*
X601861Y-227203D01*
X601927Y-227196D01*
X601992Y-227185D01*
X602047Y-227171D01*
X602054Y-227167D01*
X602072Y-227163D01*
X602098Y-227152D01*
X602131Y-227138D01*
X602167Y-227116D01*
X602203Y-227094D01*
X602240Y-227069D01*
X602276Y-227040D01*
X602280Y-227032D01*
X602294Y-227018D01*
X602316Y-226992D01*
X602342Y-226956D01*
X602371Y-226908D01*
X602404Y-226854D01*
X602433Y-226792D01*
X602458Y-226723D01*
Y-226719D01*
X602462Y-226712D01*
X602465Y-226701D01*
X602469Y-226687D01*
X602473Y-226668D01*
X602480Y-226643D01*
X602487Y-226617D01*
X602495Y-226588D01*
X602505Y-226515D01*
X602516Y-226432D01*
X602524Y-226337D01*
X602527Y-226235D01*
Y-226232D01*
Y-226217D01*
Y-226199D01*
X602524Y-226170D01*
Y-226137D01*
X602520Y-226100D01*
X602516Y-226057D01*
X602513Y-226013D01*
X602495Y-225915D01*
X602473Y-225813D01*
X602440Y-225718D01*
X602418Y-225671D01*
X602396Y-225631D01*
Y-225627D01*
X602389Y-225620D01*
X602382Y-225609D01*
X602374Y-225594D01*
X602345Y-225558D01*
X602309Y-225514D01*
X602262Y-225467D01*
X602207Y-225420D01*
X602145Y-225380D01*
X602080Y-225347D01*
X602072Y-225343D01*
X602054Y-225340D01*
X602021Y-225329D01*
X601974Y-225318D01*
X601916Y-225311D01*
X601843Y-225300D01*
X601799Y-225296D01*
X601752D01*
X601705Y-225292D01*
D02*
G37*
G36*
X4554Y-238967D02*
X4532D01*
X4517Y-238971D01*
X4477Y-238975D01*
X4430Y-238985D01*
X4372Y-239004D01*
X4313Y-239029D01*
X4255Y-239066D01*
X4201Y-239117D01*
X4193Y-239124D01*
X4179Y-239146D01*
X4157Y-239178D01*
X4128Y-239226D01*
X4102Y-239284D01*
X4080Y-239353D01*
X4066Y-239437D01*
X4059Y-239531D01*
Y-239535D01*
Y-239543D01*
Y-239557D01*
X4062Y-239575D01*
Y-239601D01*
X4066Y-239626D01*
X4077Y-239684D01*
X4091Y-239754D01*
X4117Y-239826D01*
X4153Y-239896D01*
X4201Y-239957D01*
Y-239961D01*
X4208Y-239965D01*
X4226Y-239983D01*
X4255Y-240008D01*
X4295Y-240037D01*
X4346Y-240063D01*
X4404Y-240089D01*
X4470Y-240107D01*
X4506Y-240114D01*
X4565D01*
X4579Y-240110D01*
X4619Y-240107D01*
X4667Y-240092D01*
X4725Y-240074D01*
X4787Y-240041D01*
X4848Y-240001D01*
X4878Y-239972D01*
X4907Y-239943D01*
Y-239939D01*
X4914Y-239936D01*
X4921Y-239925D01*
X4929Y-239914D01*
X4954Y-239877D01*
X4980Y-239826D01*
X5009Y-239764D01*
X5034Y-239688D01*
X5049Y-239601D01*
X5056Y-239506D01*
Y-239502D01*
Y-239495D01*
Y-239484D01*
X5052Y-239466D01*
Y-239444D01*
X5049Y-239422D01*
X5038Y-239368D01*
X5020Y-239306D01*
X4998Y-239240D01*
X4961Y-239175D01*
X4914Y-239117D01*
X4907Y-239109D01*
X4888Y-239095D01*
X4856Y-239069D01*
X4816Y-239044D01*
X4761Y-239015D01*
X4699Y-238989D01*
X4630Y-238975D01*
X4554Y-238967D01*
D02*
G37*
G36*
X1790Y-349467D02*
X1769D01*
X1754Y-349471D01*
X1710Y-349475D01*
X1659Y-349486D01*
X1601Y-349504D01*
X1539Y-349526D01*
X1481Y-349562D01*
X1423Y-349609D01*
X1416Y-349617D01*
X1401Y-349635D01*
X1376Y-349668D01*
X1350Y-349708D01*
X1324Y-349759D01*
X1299Y-349820D01*
X1285Y-349893D01*
X1277Y-349970D01*
Y-349973D01*
Y-349981D01*
Y-349991D01*
X1281Y-350006D01*
X1285Y-350046D01*
X1295Y-350101D01*
X1314Y-350155D01*
X1339Y-350217D01*
X1376Y-350279D01*
X1426Y-350337D01*
X1434Y-350345D01*
X1452Y-350359D01*
X1485Y-350385D01*
X1528Y-350414D01*
X1583Y-350439D01*
X1649Y-350465D01*
X1721Y-350479D01*
X1801Y-350487D01*
X1823D01*
X1838Y-350483D01*
X1878Y-350479D01*
X1929Y-350468D01*
X1987Y-350450D01*
X2045Y-350425D01*
X2107Y-350388D01*
X2162Y-350341D01*
X2169Y-350334D01*
X2184Y-350315D01*
X2205Y-350283D01*
X2231Y-350243D01*
X2260Y-350188D01*
X2282Y-350126D01*
X2296Y-350057D01*
X2304Y-349981D01*
Y-349973D01*
Y-349959D01*
X2300Y-349933D01*
X2296Y-349901D01*
X2289Y-349861D01*
X2278Y-349817D01*
X2264Y-349773D01*
X2245Y-349726D01*
X2242Y-349722D01*
X2235Y-349704D01*
X2220Y-349682D01*
X2198Y-349657D01*
X2173Y-349624D01*
X2140Y-349591D01*
X2104Y-349562D01*
X2060Y-349533D01*
X2052Y-349529D01*
X2038Y-349522D01*
X2012Y-349511D01*
X1980Y-349500D01*
X1940Y-349489D01*
X1892Y-349478D01*
X1841Y-349471D01*
X1790Y-349467D01*
D02*
G37*
G36*
Y-350738D02*
X1783D01*
X1761Y-350741D01*
X1729Y-350745D01*
X1685Y-350752D01*
X1638Y-350767D01*
X1590Y-350785D01*
X1539Y-350814D01*
X1496Y-350851D01*
X1492Y-350854D01*
X1477Y-350872D01*
X1459Y-350894D01*
X1437Y-350927D01*
X1416Y-350967D01*
X1397Y-351014D01*
X1383Y-351069D01*
X1379Y-351127D01*
Y-351131D01*
Y-351134D01*
Y-351156D01*
X1386Y-351189D01*
X1394Y-351229D01*
X1408Y-351273D01*
X1430Y-351320D01*
X1459Y-351367D01*
X1499Y-351415D01*
X1503Y-351418D01*
X1521Y-351433D01*
X1547Y-351451D01*
X1579Y-351473D01*
X1623Y-351495D01*
X1670Y-351513D01*
X1729Y-351528D01*
X1790Y-351531D01*
X1820D01*
X1852Y-351524D01*
X1896Y-351517D01*
X1943Y-351502D01*
X1994Y-351484D01*
X2042Y-351455D01*
X2089Y-351415D01*
X2093Y-351411D01*
X2107Y-351397D01*
X2125Y-351371D01*
X2144Y-351338D01*
X2165Y-351298D01*
X2184Y-351251D01*
X2198Y-351200D01*
X2202Y-351142D01*
Y-351138D01*
Y-351134D01*
X2198Y-351113D01*
X2194Y-351080D01*
X2187Y-351040D01*
X2173Y-350992D01*
X2154Y-350945D01*
X2125Y-350894D01*
X2089Y-350851D01*
X2085Y-350847D01*
X2067Y-350832D01*
X2042Y-350814D01*
X2009Y-350796D01*
X1965Y-350774D01*
X1914Y-350756D01*
X1856Y-350741D01*
X1790Y-350738D01*
D02*
G37*
G36*
X6486Y-193562D02*
X6468D01*
X6453Y-193565D01*
X6417Y-193569D01*
X6369Y-193580D01*
X6318Y-193602D01*
X6260Y-193627D01*
X6202Y-193667D01*
X6173Y-193689D01*
X6147Y-193718D01*
Y-193722D01*
X6140Y-193726D01*
X6125Y-193747D01*
X6103Y-193784D01*
X6074Y-193831D01*
X6049Y-193893D01*
X6027Y-193966D01*
X6013Y-194050D01*
X6005Y-194148D01*
Y-194151D01*
Y-194159D01*
Y-194173D01*
X6009Y-194192D01*
Y-194213D01*
X6013Y-194239D01*
X6024Y-194297D01*
X6038Y-194363D01*
X6064Y-194432D01*
X6100Y-194497D01*
X6147Y-194559D01*
X6154Y-194567D01*
X6173Y-194585D01*
X6202Y-194606D01*
X6242Y-194636D01*
X6293Y-194665D01*
X6351Y-194687D01*
X6420Y-194705D01*
X6497Y-194712D01*
X6519D01*
X6533Y-194708D01*
X6570Y-194705D01*
X6620Y-194694D01*
X6675Y-194676D01*
X6737Y-194647D01*
X6795Y-194610D01*
X6853Y-194559D01*
X6861Y-194552D01*
X6875Y-194534D01*
X6901Y-194501D01*
X6926Y-194454D01*
X6952Y-194399D01*
X6977Y-194330D01*
X6992Y-194253D01*
X6999Y-194166D01*
Y-194159D01*
Y-194141D01*
X6995Y-194108D01*
X6992Y-194068D01*
X6984Y-194020D01*
X6970Y-193970D01*
X6955Y-193915D01*
X6933Y-193860D01*
X6930Y-193853D01*
X6919Y-193835D01*
X6904Y-193809D01*
X6882Y-193777D01*
X6857Y-193744D01*
X6824Y-193704D01*
X6788Y-193671D01*
X6744Y-193638D01*
X6737Y-193635D01*
X6722Y-193627D01*
X6697Y-193613D01*
X6664Y-193602D01*
X6628Y-193587D01*
X6584Y-193573D01*
X6537Y-193565D01*
X6486Y-193562D01*
D02*
G37*
G36*
X330803Y-238359D02*
X330781D01*
X330767Y-238362D01*
X330730Y-238366D01*
X330679Y-238377D01*
X330625Y-238395D01*
X330563Y-238424D01*
X330504Y-238461D01*
X330446Y-238512D01*
X330439Y-238519D01*
X330424Y-238537D01*
X330399Y-238570D01*
X330374Y-238617D01*
X330348Y-238672D01*
X330323Y-238741D01*
X330308Y-238817D01*
X330301Y-238905D01*
Y-238912D01*
Y-238930D01*
X330304Y-238963D01*
X330308Y-239003D01*
X330315Y-239050D01*
X330330Y-239101D01*
X330344Y-239156D01*
X330366Y-239211D01*
X330370Y-239218D01*
X330381Y-239236D01*
X330395Y-239262D01*
X330417Y-239294D01*
X330443Y-239327D01*
X330475Y-239367D01*
X330512Y-239400D01*
X330556Y-239433D01*
X330563Y-239436D01*
X330577Y-239443D01*
X330603Y-239458D01*
X330635Y-239469D01*
X330672Y-239484D01*
X330716Y-239498D01*
X330763Y-239505D01*
X330814Y-239509D01*
X330832D01*
X330847Y-239505D01*
X330883Y-239502D01*
X330930Y-239491D01*
X330981Y-239469D01*
X331040Y-239443D01*
X331098Y-239404D01*
X331127Y-239382D01*
X331152Y-239352D01*
Y-239349D01*
X331160Y-239345D01*
X331174Y-239323D01*
X331196Y-239287D01*
X331225Y-239240D01*
X331251Y-239178D01*
X331273Y-239105D01*
X331287Y-239021D01*
X331294Y-238923D01*
Y-238919D01*
Y-238912D01*
Y-238897D01*
X331291Y-238879D01*
Y-238858D01*
X331287Y-238832D01*
X331276Y-238774D01*
X331262Y-238708D01*
X331236Y-238639D01*
X331200Y-238574D01*
X331152Y-238512D01*
X331145Y-238504D01*
X331127Y-238486D01*
X331098Y-238464D01*
X331058Y-238435D01*
X331007Y-238406D01*
X330949Y-238384D01*
X330879Y-238366D01*
X330803Y-238359D01*
D02*
G37*
G36*
X29657Y-489D02*
X29075D01*
Y-2411D01*
X29672D01*
X29697Y-2407D01*
X29752Y-2404D01*
X29814Y-2400D01*
X29880Y-2393D01*
X29945Y-2382D01*
X30000Y-2368D01*
X30007Y-2364D01*
X30025Y-2360D01*
X30051Y-2349D01*
X30083Y-2335D01*
X30120Y-2313D01*
X30156Y-2291D01*
X30193Y-2266D01*
X30229Y-2236D01*
X30233Y-2229D01*
X30247Y-2215D01*
X30269Y-2189D01*
X30294Y-2153D01*
X30324Y-2105D01*
X30356Y-2051D01*
X30385Y-1989D01*
X30411Y-1920D01*
Y-1916D01*
X30415Y-1909D01*
X30418Y-1898D01*
X30422Y-1883D01*
X30426Y-1865D01*
X30433Y-1840D01*
X30440Y-1814D01*
X30447Y-1785D01*
X30458Y-1712D01*
X30469Y-1629D01*
X30476Y-1534D01*
X30480Y-1432D01*
Y-1428D01*
Y-1414D01*
Y-1396D01*
X30476Y-1366D01*
Y-1334D01*
X30473Y-1297D01*
X30469Y-1254D01*
X30465Y-1210D01*
X30447Y-1112D01*
X30426Y-1010D01*
X30393Y-915D01*
X30371Y-868D01*
X30349Y-828D01*
Y-824D01*
X30342Y-817D01*
X30334Y-806D01*
X30327Y-791D01*
X30298Y-755D01*
X30262Y-711D01*
X30214Y-664D01*
X30160Y-617D01*
X30098Y-577D01*
X30032Y-544D01*
X30025Y-540D01*
X30007Y-537D01*
X29974Y-526D01*
X29927Y-515D01*
X29869Y-507D01*
X29796Y-496D01*
X29752Y-493D01*
X29705D01*
X29657Y-489D01*
D02*
G37*
G36*
Y6444D02*
X29075D01*
Y4522D01*
X29672D01*
X29697Y4526D01*
X29752Y4530D01*
X29814Y4533D01*
X29880Y4541D01*
X29945Y4551D01*
X30000Y4566D01*
X30007Y4570D01*
X30025Y4573D01*
X30051Y4584D01*
X30083Y4599D01*
X30120Y4621D01*
X30156Y4642D01*
X30193Y4668D01*
X30229Y4697D01*
X30233Y4704D01*
X30247Y4719D01*
X30269Y4744D01*
X30294Y4781D01*
X30324Y4828D01*
X30356Y4883D01*
X30385Y4944D01*
X30411Y5014D01*
Y5017D01*
X30415Y5025D01*
X30418Y5035D01*
X30422Y5050D01*
X30426Y5068D01*
X30433Y5094D01*
X30440Y5119D01*
X30447Y5148D01*
X30458Y5221D01*
X30469Y5305D01*
X30476Y5399D01*
X30480Y5502D01*
Y5505D01*
Y5520D01*
Y5538D01*
X30476Y5567D01*
Y5600D01*
X30473Y5636D01*
X30469Y5680D01*
X30465Y5723D01*
X30447Y5822D01*
X30426Y5924D01*
X30393Y6018D01*
X30371Y6066D01*
X30349Y6106D01*
Y6109D01*
X30342Y6117D01*
X30334Y6128D01*
X30327Y6142D01*
X30298Y6179D01*
X30262Y6222D01*
X30214Y6269D01*
X30160Y6317D01*
X30098Y6357D01*
X30032Y6390D01*
X30025Y6393D01*
X30007Y6397D01*
X29974Y6408D01*
X29927Y6419D01*
X29869Y6426D01*
X29796Y6437D01*
X29752Y6441D01*
X29705D01*
X29657Y6444D01*
D02*
G37*
G36*
X33931Y6499D02*
X33909D01*
X33894Y6495D01*
X33854Y6488D01*
X33807Y6477D01*
X33752Y6455D01*
X33694Y6422D01*
X33665Y6401D01*
X33636Y6379D01*
X33610Y6350D01*
X33585Y6317D01*
Y6313D01*
X33578Y6306D01*
X33570Y6291D01*
X33560Y6273D01*
X33549Y6244D01*
X33534Y6211D01*
X33523Y6171D01*
X33509Y6124D01*
X33494Y6069D01*
X33479Y6007D01*
X33465Y5938D01*
X33454Y5862D01*
X33443Y5774D01*
X33436Y5680D01*
X33432Y5578D01*
X33428Y5465D01*
Y5458D01*
Y5440D01*
Y5407D01*
X33432Y5363D01*
Y5316D01*
X33436Y5258D01*
X33439Y5196D01*
X33447Y5130D01*
X33465Y4988D01*
X33476Y4919D01*
X33490Y4854D01*
X33505Y4792D01*
X33527Y4733D01*
X33549Y4682D01*
X33574Y4639D01*
Y4635D01*
X33581Y4631D01*
X33600Y4606D01*
X33632Y4573D01*
X33672Y4537D01*
X33727Y4501D01*
X33789Y4468D01*
X33858Y4442D01*
X33894Y4439D01*
X33934Y4435D01*
X33956D01*
X33971Y4439D01*
X34007Y4446D01*
X34058Y4460D01*
X34113Y4486D01*
X34175Y4522D01*
X34204Y4544D01*
X34233Y4573D01*
X34262Y4602D01*
X34291Y4639D01*
Y4642D01*
X34298Y4650D01*
X34306Y4661D01*
X34313Y4679D01*
X34328Y4704D01*
X34339Y4737D01*
X34353Y4773D01*
X34368Y4817D01*
X34378Y4872D01*
X34393Y4930D01*
X34408Y4999D01*
X34419Y5072D01*
X34426Y5159D01*
X34433Y5250D01*
X34440Y5352D01*
Y5465D01*
Y5469D01*
Y5472D01*
Y5491D01*
Y5523D01*
X34437Y5567D01*
Y5614D01*
X34433Y5672D01*
X34429Y5734D01*
X34422Y5804D01*
X34404Y5942D01*
X34393Y6011D01*
X34378Y6077D01*
X34364Y6138D01*
X34342Y6197D01*
X34320Y6248D01*
X34295Y6291D01*
Y6295D01*
X34288Y6299D01*
X34280Y6310D01*
X34269Y6324D01*
X34237Y6357D01*
X34196Y6397D01*
X34142Y6433D01*
X34080Y6466D01*
X34047Y6481D01*
X34011Y6492D01*
X33971Y6495D01*
X33931Y6499D01*
D02*
G37*
G36*
X32020Y13389D02*
X31962D01*
X31947Y13385D01*
X31907Y13381D01*
X31860Y13367D01*
X31801Y13349D01*
X31740Y13316D01*
X31678Y13276D01*
X31648Y13247D01*
X31619Y13217D01*
Y13214D01*
X31612Y13210D01*
X31605Y13199D01*
X31598Y13188D01*
X31572Y13152D01*
X31547Y13101D01*
X31517Y13039D01*
X31492Y12963D01*
X31477Y12875D01*
X31470Y12781D01*
Y12777D01*
Y12770D01*
Y12759D01*
X31474Y12741D01*
Y12719D01*
X31477Y12697D01*
X31488Y12642D01*
X31507Y12581D01*
X31528Y12515D01*
X31565Y12449D01*
X31612Y12391D01*
X31619Y12384D01*
X31638Y12369D01*
X31670Y12344D01*
X31710Y12318D01*
X31765Y12289D01*
X31827Y12264D01*
X31896Y12249D01*
X31973Y12242D01*
X31994D01*
X32009Y12246D01*
X32049Y12249D01*
X32096Y12260D01*
X32155Y12278D01*
X32213Y12304D01*
X32271Y12340D01*
X32326Y12391D01*
X32333Y12398D01*
X32347Y12420D01*
X32369Y12453D01*
X32398Y12500D01*
X32424Y12559D01*
X32446Y12628D01*
X32460Y12711D01*
X32467Y12806D01*
Y12810D01*
Y12817D01*
Y12832D01*
X32464Y12850D01*
Y12875D01*
X32460Y12901D01*
X32449Y12959D01*
X32435Y13028D01*
X32409Y13101D01*
X32373Y13170D01*
X32326Y13232D01*
Y13236D01*
X32318Y13239D01*
X32300Y13258D01*
X32271Y13283D01*
X32231Y13312D01*
X32180Y13338D01*
X32122Y13363D01*
X32056Y13381D01*
X32020Y13389D01*
D02*
G37*
G36*
X29657Y13334D02*
X29075D01*
Y11412D01*
X29672D01*
X29697Y11416D01*
X29752Y11419D01*
X29814Y11423D01*
X29880Y11430D01*
X29945Y11441D01*
X30000Y11456D01*
X30007Y11459D01*
X30025Y11463D01*
X30051Y11474D01*
X30083Y11489D01*
X30120Y11510D01*
X30156Y11532D01*
X30193Y11558D01*
X30229Y11587D01*
X30233Y11594D01*
X30247Y11609D01*
X30269Y11634D01*
X30294Y11671D01*
X30324Y11718D01*
X30356Y11772D01*
X30385Y11834D01*
X30411Y11903D01*
Y11907D01*
X30415Y11914D01*
X30418Y11925D01*
X30422Y11940D01*
X30426Y11958D01*
X30433Y11983D01*
X30440Y12009D01*
X30447Y12038D01*
X30458Y12111D01*
X30469Y12195D01*
X30476Y12289D01*
X30480Y12391D01*
Y12395D01*
Y12409D01*
Y12428D01*
X30476Y12457D01*
Y12489D01*
X30473Y12526D01*
X30469Y12570D01*
X30465Y12613D01*
X30447Y12711D01*
X30426Y12813D01*
X30393Y12908D01*
X30371Y12955D01*
X30349Y12995D01*
Y12999D01*
X30342Y13006D01*
X30334Y13017D01*
X30327Y13032D01*
X30298Y13068D01*
X30262Y13112D01*
X30214Y13159D01*
X30160Y13207D01*
X30098Y13247D01*
X30032Y13279D01*
X30025Y13283D01*
X30007Y13287D01*
X29974Y13298D01*
X29927Y13308D01*
X29869Y13316D01*
X29796Y13327D01*
X29752Y13330D01*
X29705D01*
X29657Y13334D01*
D02*
G37*
G36*
Y20224D02*
X29075D01*
Y18302D01*
X29672D01*
X29697Y18305D01*
X29752Y18309D01*
X29814Y18313D01*
X29880Y18320D01*
X29945Y18331D01*
X30000Y18346D01*
X30007Y18349D01*
X30025Y18353D01*
X30051Y18364D01*
X30083Y18378D01*
X30120Y18400D01*
X30156Y18422D01*
X30193Y18447D01*
X30229Y18477D01*
X30233Y18484D01*
X30247Y18498D01*
X30269Y18524D01*
X30294Y18560D01*
X30324Y18608D01*
X30356Y18662D01*
X30385Y18724D01*
X30411Y18793D01*
Y18797D01*
X30415Y18804D01*
X30418Y18815D01*
X30422Y18830D01*
X30426Y18848D01*
X30433Y18873D01*
X30440Y18899D01*
X30447Y18928D01*
X30458Y19001D01*
X30469Y19084D01*
X30476Y19179D01*
X30480Y19281D01*
Y19285D01*
Y19299D01*
Y19317D01*
X30476Y19346D01*
Y19379D01*
X30473Y19416D01*
X30469Y19459D01*
X30465Y19503D01*
X30447Y19601D01*
X30426Y19703D01*
X30393Y19798D01*
X30371Y19845D01*
X30349Y19885D01*
Y19889D01*
X30342Y19896D01*
X30334Y19907D01*
X30327Y19922D01*
X30298Y19958D01*
X30262Y20002D01*
X30214Y20049D01*
X30160Y20096D01*
X30098Y20136D01*
X30032Y20169D01*
X30025Y20173D01*
X30007Y20176D01*
X29974Y20187D01*
X29927Y20198D01*
X29869Y20206D01*
X29796Y20216D01*
X29752Y20220D01*
X29705D01*
X29657Y20224D01*
D02*
G37*
G36*
X150354Y-104506D02*
X150351D01*
X150347D01*
X150325Y-104510D01*
X150293Y-104514D01*
X150252Y-104521D01*
X150205Y-104535D01*
X150158Y-104554D01*
X150107Y-104583D01*
X150063Y-104619D01*
X150059Y-104623D01*
X150045Y-104641D01*
X150027Y-104666D01*
X150008Y-104699D01*
X149987Y-104743D01*
X149969Y-104794D01*
X149954Y-104852D01*
X149950Y-104918D01*
Y-104925D01*
X149954Y-104947D01*
X149958Y-104980D01*
X149965Y-105023D01*
X149979Y-105071D01*
X149998Y-105118D01*
X150027Y-105169D01*
X150063Y-105212D01*
X150067Y-105216D01*
X150085Y-105231D01*
X150107Y-105249D01*
X150140Y-105271D01*
X150180Y-105293D01*
X150227Y-105311D01*
X150282Y-105325D01*
X150340Y-105329D01*
X150343D01*
X150347D01*
X150369D01*
X150402Y-105322D01*
X150442Y-105314D01*
X150485Y-105300D01*
X150533Y-105278D01*
X150580Y-105249D01*
X150627Y-105209D01*
X150631Y-105205D01*
X150645Y-105187D01*
X150664Y-105162D01*
X150686Y-105129D01*
X150707Y-105085D01*
X150726Y-105038D01*
X150740Y-104980D01*
X150744Y-104918D01*
Y-104889D01*
X150736Y-104856D01*
X150729Y-104812D01*
X150715Y-104765D01*
X150697Y-104714D01*
X150667Y-104666D01*
X150627Y-104619D01*
X150624Y-104616D01*
X150609Y-104601D01*
X150584Y-104583D01*
X150551Y-104565D01*
X150511Y-104543D01*
X150463Y-104525D01*
X150413Y-104510D01*
X150354Y-104506D01*
D02*
G37*
G36*
X149193Y-104404D02*
X149186D01*
X149171D01*
X149146Y-104408D01*
X149113Y-104412D01*
X149073Y-104419D01*
X149029Y-104430D01*
X148986Y-104445D01*
X148938Y-104463D01*
X148935Y-104466D01*
X148916Y-104474D01*
X148895Y-104488D01*
X148869Y-104510D01*
X148837Y-104535D01*
X148804Y-104568D01*
X148775Y-104605D01*
X148746Y-104648D01*
X148742Y-104656D01*
X148734Y-104670D01*
X148724Y-104696D01*
X148713Y-104728D01*
X148702Y-104768D01*
X148691Y-104816D01*
X148684Y-104867D01*
X148680Y-104918D01*
Y-104939D01*
X148684Y-104954D01*
X148687Y-104998D01*
X148698Y-105049D01*
X148716Y-105107D01*
X148738Y-105169D01*
X148775Y-105227D01*
X148822Y-105285D01*
X148829Y-105293D01*
X148847Y-105307D01*
X148880Y-105333D01*
X148920Y-105358D01*
X148971Y-105384D01*
X149033Y-105409D01*
X149106Y-105424D01*
X149182Y-105431D01*
X149186D01*
X149193D01*
X149204D01*
X149219Y-105427D01*
X149259Y-105424D01*
X149313Y-105413D01*
X149368Y-105394D01*
X149430Y-105369D01*
X149492Y-105333D01*
X149550Y-105282D01*
X149557Y-105274D01*
X149572Y-105256D01*
X149597Y-105223D01*
X149626Y-105180D01*
X149652Y-105125D01*
X149677Y-105060D01*
X149692Y-104987D01*
X149699Y-104907D01*
Y-104885D01*
X149696Y-104870D01*
X149692Y-104830D01*
X149681Y-104779D01*
X149663Y-104721D01*
X149637Y-104663D01*
X149601Y-104601D01*
X149554Y-104546D01*
X149546Y-104539D01*
X149528Y-104525D01*
X149495Y-104503D01*
X149455Y-104477D01*
X149401Y-104448D01*
X149339Y-104426D01*
X149270Y-104412D01*
X149193Y-104404D01*
D02*
G37*
G36*
X611758Y-254411D02*
X610965D01*
Y-255244D01*
X611715D01*
X611758Y-255241D01*
X611809Y-255237D01*
X611868Y-255233D01*
X611926Y-255226D01*
X611984Y-255215D01*
X612035Y-255201D01*
X612042Y-255197D01*
X612057Y-255190D01*
X612079Y-255179D01*
X612108Y-255164D01*
X612141Y-255142D01*
X612173Y-255117D01*
X612206Y-255084D01*
X612231Y-255048D01*
X612235Y-255044D01*
X612242Y-255030D01*
X612253Y-255008D01*
X612268Y-254978D01*
X612279Y-254946D01*
X612290Y-254909D01*
X612297Y-254866D01*
X612301Y-254822D01*
Y-254818D01*
Y-254815D01*
X612297Y-254793D01*
X612293Y-254760D01*
X612286Y-254716D01*
X612268Y-254673D01*
X612246Y-254622D01*
X612213Y-254574D01*
X612170Y-254527D01*
X612162Y-254523D01*
X612144Y-254509D01*
X612115Y-254491D01*
X612068Y-254469D01*
X612013Y-254447D01*
X611940Y-254429D01*
X611857Y-254414D01*
X611758Y-254411D01*
D02*
G37*
G36*
X613866Y-254374D02*
X613837D01*
X613804Y-254382D01*
X613760Y-254389D01*
X613713Y-254403D01*
X613662Y-254422D01*
X613615Y-254451D01*
X613567Y-254491D01*
X613564Y-254494D01*
X613549Y-254509D01*
X613531Y-254534D01*
X613513Y-254567D01*
X613491Y-254607D01*
X613473Y-254655D01*
X613458Y-254706D01*
X613454Y-254764D01*
Y-254767D01*
Y-254771D01*
X613458Y-254793D01*
X613462Y-254826D01*
X613469Y-254866D01*
X613484Y-254913D01*
X613502Y-254960D01*
X613531Y-255011D01*
X613567Y-255055D01*
X613571Y-255059D01*
X613589Y-255073D01*
X613615Y-255091D01*
X613647Y-255110D01*
X613691Y-255131D01*
X613742Y-255150D01*
X613800Y-255164D01*
X613866Y-255168D01*
X613873D01*
X613895Y-255164D01*
X613928Y-255160D01*
X613971Y-255153D01*
X614019Y-255139D01*
X614066Y-255120D01*
X614117Y-255091D01*
X614161Y-255055D01*
X614164Y-255051D01*
X614179Y-255033D01*
X614197Y-255011D01*
X614219Y-254978D01*
X614241Y-254939D01*
X614259Y-254891D01*
X614274Y-254837D01*
X614277Y-254778D01*
Y-254775D01*
Y-254771D01*
Y-254749D01*
X614270Y-254716D01*
X614263Y-254676D01*
X614248Y-254633D01*
X614226Y-254585D01*
X614197Y-254538D01*
X614157Y-254491D01*
X614153Y-254487D01*
X614135Y-254473D01*
X614110Y-254454D01*
X614077Y-254433D01*
X614033Y-254411D01*
X613986Y-254393D01*
X613928Y-254378D01*
X613866Y-254374D01*
D02*
G37*
G36*
X613855Y-255419D02*
X613833D01*
X613819Y-255423D01*
X613778Y-255426D01*
X613728Y-255437D01*
X613669Y-255455D01*
X613611Y-255481D01*
X613549Y-255517D01*
X613494Y-255565D01*
X613487Y-255572D01*
X613473Y-255590D01*
X613451Y-255623D01*
X613425Y-255663D01*
X613396Y-255717D01*
X613374Y-255779D01*
X613360Y-255849D01*
X613353Y-255925D01*
Y-255932D01*
Y-255947D01*
X613356Y-255972D01*
X613360Y-256005D01*
X613367Y-256045D01*
X613378Y-256089D01*
X613393Y-256132D01*
X613411Y-256180D01*
X613414Y-256183D01*
X613422Y-256202D01*
X613436Y-256223D01*
X613458Y-256249D01*
X613484Y-256282D01*
X613516Y-256314D01*
X613553Y-256344D01*
X613596Y-256373D01*
X613604Y-256376D01*
X613618Y-256384D01*
X613644Y-256395D01*
X613677Y-256405D01*
X613717Y-256416D01*
X613764Y-256427D01*
X613815Y-256434D01*
X613866Y-256438D01*
X613888D01*
X613902Y-256434D01*
X613946Y-256431D01*
X613997Y-256420D01*
X614055Y-256402D01*
X614117Y-256380D01*
X614175Y-256344D01*
X614233Y-256296D01*
X614241Y-256289D01*
X614255Y-256271D01*
X614281Y-256238D01*
X614306Y-256198D01*
X614332Y-256147D01*
X614357Y-256085D01*
X614372Y-256012D01*
X614379Y-255936D01*
Y-255932D01*
Y-255925D01*
Y-255914D01*
X614375Y-255899D01*
X614372Y-255859D01*
X614361Y-255805D01*
X614343Y-255750D01*
X614317Y-255688D01*
X614281Y-255626D01*
X614230Y-255568D01*
X614222Y-255561D01*
X614204Y-255546D01*
X614172Y-255521D01*
X614128Y-255492D01*
X614073Y-255466D01*
X614008Y-255441D01*
X613935Y-255426D01*
X613855Y-255419D01*
D02*
G37*
G36*
X614825Y-235309D02*
X614712D01*
X614709D01*
X614705D01*
X614687D01*
X614654D01*
X614610Y-235313D01*
X614563D01*
X614505Y-235317D01*
X614443Y-235320D01*
X614374Y-235328D01*
X614235Y-235346D01*
X614166Y-235357D01*
X614101Y-235371D01*
X614039Y-235386D01*
X613980Y-235408D01*
X613930Y-235429D01*
X613886Y-235455D01*
X613882D01*
X613878Y-235462D01*
X613868Y-235470D01*
X613853Y-235480D01*
X613820Y-235513D01*
X613780Y-235553D01*
X613744Y-235608D01*
X613711Y-235670D01*
X613696Y-235702D01*
X613686Y-235739D01*
X613682Y-235779D01*
X613678Y-235819D01*
Y-235841D01*
X613682Y-235855D01*
X613689Y-235895D01*
X613700Y-235943D01*
X613722Y-235997D01*
X613755Y-236055D01*
X613777Y-236085D01*
X613799Y-236114D01*
X613828Y-236139D01*
X613860Y-236165D01*
X613864D01*
X613871Y-236172D01*
X613886Y-236179D01*
X613904Y-236190D01*
X613933Y-236201D01*
X613966Y-236216D01*
X614006Y-236227D01*
X614053Y-236241D01*
X614108Y-236256D01*
X614170Y-236270D01*
X614239Y-236285D01*
X614315Y-236296D01*
X614403Y-236307D01*
X614497Y-236314D01*
X614599Y-236318D01*
X614712Y-236321D01*
X614719D01*
X614738D01*
X614770D01*
X614814Y-236318D01*
X614861D01*
X614920Y-236314D01*
X614982Y-236310D01*
X615047Y-236303D01*
X615189Y-236285D01*
X615258Y-236274D01*
X615324Y-236259D01*
X615385Y-236245D01*
X615444Y-236223D01*
X615495Y-236201D01*
X615538Y-236176D01*
X615542D01*
X615546Y-236168D01*
X615571Y-236150D01*
X615604Y-236117D01*
X615640Y-236077D01*
X615677Y-236023D01*
X615709Y-235961D01*
X615735Y-235892D01*
X615739Y-235855D01*
X615742Y-235815D01*
Y-235793D01*
X615739Y-235779D01*
X615731Y-235742D01*
X615717Y-235691D01*
X615691Y-235637D01*
X615655Y-235575D01*
X615633Y-235546D01*
X615604Y-235517D01*
X615575Y-235488D01*
X615538Y-235458D01*
X615535D01*
X615527Y-235451D01*
X615517Y-235444D01*
X615498Y-235437D01*
X615473Y-235422D01*
X615440Y-235411D01*
X615404Y-235397D01*
X615360Y-235382D01*
X615305Y-235371D01*
X615247Y-235357D01*
X615178Y-235342D01*
X615105Y-235331D01*
X615018Y-235324D01*
X614927Y-235317D01*
X614825Y-235309D01*
D02*
G37*
G36*
X605416Y-297780D02*
X604819D01*
Y-298537D01*
X605438D01*
X605485Y-298533D01*
X605536Y-298530D01*
X605587Y-298526D01*
X605638Y-298519D01*
X605678Y-298511D01*
X605686Y-298508D01*
X605700Y-298504D01*
X605722Y-298493D01*
X605751Y-298479D01*
X605780Y-298464D01*
X605813Y-298442D01*
X605846Y-298413D01*
X605871Y-298384D01*
X605875Y-298380D01*
X605882Y-298369D01*
X605893Y-298347D01*
X605904Y-298322D01*
X605915Y-298293D01*
X605926Y-298256D01*
X605933Y-298213D01*
X605937Y-298165D01*
Y-298158D01*
Y-298144D01*
X605933Y-298122D01*
X605929Y-298093D01*
X605922Y-298056D01*
X605911Y-298020D01*
X605897Y-297984D01*
X605875Y-297947D01*
X605871Y-297943D01*
X605864Y-297933D01*
X605849Y-297914D01*
X605831Y-297896D01*
X605806Y-297874D01*
X605777Y-297852D01*
X605740Y-297831D01*
X605700Y-297816D01*
X605696D01*
X605678Y-297809D01*
X605653Y-297805D01*
X605613Y-297798D01*
X605558Y-297791D01*
X605496Y-297787D01*
X605416Y-297780D01*
D02*
G37*
G36*
X605482Y-298835D02*
X604819D01*
Y-299702D01*
X605536D01*
X605613Y-299698D01*
X605645Y-299694D01*
X605675Y-299691D01*
X605678D01*
X605693Y-299687D01*
X605715Y-299683D01*
X605740Y-299676D01*
X605802Y-299654D01*
X605864Y-299625D01*
X605867Y-299622D01*
X605878Y-299614D01*
X605893Y-299603D01*
X605911Y-299589D01*
X605929Y-299567D01*
X605955Y-299545D01*
X605973Y-299516D01*
X605995Y-299483D01*
X605999Y-299480D01*
X606002Y-299469D01*
X606009Y-299447D01*
X606020Y-299421D01*
X606031Y-299392D01*
X606039Y-299356D01*
X606042Y-299312D01*
X606046Y-299268D01*
Y-299261D01*
Y-299247D01*
X606042Y-299218D01*
X606035Y-299185D01*
X606028Y-299148D01*
X606013Y-299108D01*
X605995Y-299068D01*
X605969Y-299028D01*
X605966Y-299025D01*
X605955Y-299010D01*
X605940Y-298992D01*
X605918Y-298970D01*
X605889Y-298944D01*
X605853Y-298919D01*
X605813Y-298897D01*
X605765Y-298879D01*
X605758Y-298875D01*
X605744Y-298872D01*
X605711Y-298864D01*
X605671Y-298857D01*
X605620Y-298850D01*
X605558Y-298843D01*
X605482Y-298835D01*
D02*
G37*
G36*
X619903Y-300437D02*
X619845D01*
X619830Y-300441D01*
X619790Y-300445D01*
X619743Y-300459D01*
X619685Y-300477D01*
X619623Y-300510D01*
X619561Y-300550D01*
X619532Y-300579D01*
X619503Y-300608D01*
Y-300612D01*
X619495Y-300616D01*
X619488Y-300627D01*
X619481Y-300638D01*
X619455Y-300674D01*
X619430Y-300725D01*
X619401Y-300787D01*
X619375Y-300863D01*
X619361Y-300951D01*
X619353Y-301045D01*
Y-301049D01*
Y-301056D01*
Y-301067D01*
X619357Y-301085D01*
Y-301107D01*
X619361Y-301129D01*
X619372Y-301184D01*
X619390Y-301245D01*
X619412Y-301311D01*
X619448Y-301376D01*
X619495Y-301435D01*
X619503Y-301442D01*
X619521Y-301456D01*
X619554Y-301482D01*
X619594Y-301507D01*
X619648Y-301537D01*
X619710Y-301562D01*
X619779Y-301577D01*
X619856Y-301584D01*
X619878D01*
X619892Y-301580D01*
X619932Y-301577D01*
X619980Y-301566D01*
X620038Y-301548D01*
X620096Y-301522D01*
X620154Y-301486D01*
X620209Y-301435D01*
X620216Y-301427D01*
X620231Y-301406D01*
X620253Y-301373D01*
X620282Y-301325D01*
X620307Y-301267D01*
X620329Y-301198D01*
X620344Y-301114D01*
X620351Y-301020D01*
Y-301016D01*
Y-301009D01*
Y-300994D01*
X620347Y-300976D01*
Y-300951D01*
X620344Y-300925D01*
X620333Y-300867D01*
X620318Y-300798D01*
X620293Y-300725D01*
X620256Y-300656D01*
X620209Y-300594D01*
Y-300590D01*
X620202Y-300587D01*
X620183Y-300568D01*
X620154Y-300543D01*
X620114Y-300514D01*
X620063Y-300488D01*
X620005Y-300463D01*
X619940Y-300445D01*
X619903Y-300437D01*
D02*
G37*
G36*
X617905D02*
X617876D01*
X617843Y-300445D01*
X617799Y-300452D01*
X617752Y-300466D01*
X617701Y-300485D01*
X617654Y-300514D01*
X617606Y-300554D01*
X617603Y-300557D01*
X617588Y-300572D01*
X617570Y-300597D01*
X617552Y-300630D01*
X617530Y-300670D01*
X617512Y-300718D01*
X617497Y-300768D01*
X617493Y-300827D01*
Y-300830D01*
Y-300834D01*
X617497Y-300856D01*
X617501Y-300889D01*
X617508Y-300929D01*
X617523Y-300976D01*
X617541Y-301023D01*
X617570Y-301074D01*
X617606Y-301118D01*
X617610Y-301122D01*
X617628Y-301136D01*
X617654Y-301154D01*
X617686Y-301173D01*
X617730Y-301194D01*
X617781Y-301213D01*
X617839Y-301227D01*
X617905Y-301231D01*
X617912D01*
X617934Y-301227D01*
X617967Y-301223D01*
X618010Y-301216D01*
X618058Y-301202D01*
X618105Y-301184D01*
X618156Y-301154D01*
X618200Y-301118D01*
X618203Y-301114D01*
X618218Y-301096D01*
X618236Y-301074D01*
X618258Y-301042D01*
X618280Y-301002D01*
X618298Y-300954D01*
X618312Y-300900D01*
X618316Y-300841D01*
Y-300838D01*
Y-300834D01*
Y-300812D01*
X618309Y-300779D01*
X618301Y-300739D01*
X618287Y-300696D01*
X618265Y-300648D01*
X618236Y-300601D01*
X618196Y-300554D01*
X618192Y-300550D01*
X618174Y-300536D01*
X618149Y-300517D01*
X618116Y-300496D01*
X618072Y-300474D01*
X618025Y-300455D01*
X617967Y-300441D01*
X617905Y-300437D01*
D02*
G37*
G36*
X617894Y-301482D02*
X617872D01*
X617857Y-301486D01*
X617817Y-301489D01*
X617766Y-301500D01*
X617708Y-301518D01*
X617650Y-301544D01*
X617588Y-301580D01*
X617533Y-301628D01*
X617526Y-301635D01*
X617512Y-301653D01*
X617490Y-301686D01*
X617464Y-301726D01*
X617435Y-301780D01*
X617413Y-301842D01*
X617399Y-301911D01*
X617391Y-301988D01*
Y-301995D01*
Y-302010D01*
X617395Y-302035D01*
X617399Y-302068D01*
X617406Y-302108D01*
X617417Y-302152D01*
X617432Y-302195D01*
X617450Y-302243D01*
X617453Y-302246D01*
X617461Y-302265D01*
X617475Y-302286D01*
X617497Y-302312D01*
X617523Y-302345D01*
X617555Y-302377D01*
X617592Y-302407D01*
X617635Y-302436D01*
X617643Y-302439D01*
X617657Y-302447D01*
X617683Y-302457D01*
X617716Y-302468D01*
X617756Y-302479D01*
X617803Y-302490D01*
X617854Y-302498D01*
X617905Y-302501D01*
X617927D01*
X617941Y-302498D01*
X617985Y-302494D01*
X618036Y-302483D01*
X618094Y-302465D01*
X618156Y-302443D01*
X618214Y-302407D01*
X618272Y-302359D01*
X618280Y-302352D01*
X618294Y-302334D01*
X618320Y-302301D01*
X618345Y-302261D01*
X618371Y-302210D01*
X618396Y-302148D01*
X618411Y-302075D01*
X618418Y-301999D01*
Y-301995D01*
Y-301988D01*
Y-301977D01*
X618414Y-301962D01*
X618411Y-301922D01*
X618400Y-301868D01*
X618382Y-301813D01*
X618356Y-301751D01*
X618320Y-301689D01*
X618269Y-301631D01*
X618261Y-301624D01*
X618243Y-301609D01*
X618211Y-301584D01*
X618167Y-301555D01*
X618112Y-301529D01*
X618047Y-301504D01*
X617974Y-301489D01*
X617894Y-301482D01*
D02*
G37*
G36*
X592706Y-292381D02*
X592688D01*
X592673Y-292384D01*
X592637Y-292388D01*
X592590Y-292399D01*
X592539Y-292421D01*
X592481Y-292446D01*
X592422Y-292486D01*
X592393Y-292508D01*
X592368Y-292537D01*
Y-292541D01*
X592360Y-292545D01*
X592346Y-292566D01*
X592324Y-292603D01*
X592295Y-292650D01*
X592269Y-292712D01*
X592248Y-292785D01*
X592233Y-292868D01*
X592226Y-292967D01*
Y-292970D01*
Y-292978D01*
Y-292992D01*
X592229Y-293010D01*
Y-293032D01*
X592233Y-293058D01*
X592244Y-293116D01*
X592259Y-293182D01*
X592284Y-293251D01*
X592320Y-293316D01*
X592368Y-293378D01*
X592375Y-293385D01*
X592393Y-293404D01*
X592422Y-293425D01*
X592462Y-293455D01*
X592513Y-293484D01*
X592572Y-293506D01*
X592641Y-293524D01*
X592717Y-293531D01*
X592739D01*
X592754Y-293527D01*
X592790Y-293524D01*
X592841Y-293513D01*
X592896Y-293495D01*
X592957Y-293465D01*
X593016Y-293429D01*
X593074Y-293378D01*
X593081Y-293371D01*
X593096Y-293353D01*
X593121Y-293320D01*
X593147Y-293273D01*
X593172Y-293218D01*
X593198Y-293149D01*
X593212Y-293072D01*
X593220Y-292985D01*
Y-292978D01*
Y-292959D01*
X593216Y-292927D01*
X593212Y-292887D01*
X593205Y-292839D01*
X593190Y-292788D01*
X593176Y-292734D01*
X593154Y-292679D01*
X593150Y-292672D01*
X593139Y-292654D01*
X593125Y-292628D01*
X593103Y-292596D01*
X593078Y-292563D01*
X593045Y-292523D01*
X593008Y-292490D01*
X592965Y-292457D01*
X592957Y-292454D01*
X592943Y-292446D01*
X592917Y-292432D01*
X592885Y-292421D01*
X592848Y-292406D01*
X592804Y-292392D01*
X592757Y-292384D01*
X592706Y-292381D01*
D02*
G37*
G36*
X594694D02*
X594672D01*
X594657Y-292384D01*
X594614Y-292388D01*
X594563Y-292399D01*
X594504Y-292417D01*
X594443Y-292439D01*
X594384Y-292475D01*
X594326Y-292523D01*
X594319Y-292530D01*
X594304Y-292548D01*
X594279Y-292581D01*
X594253Y-292621D01*
X594228Y-292672D01*
X594202Y-292734D01*
X594188Y-292807D01*
X594180Y-292883D01*
Y-292887D01*
Y-292894D01*
Y-292905D01*
X594184Y-292919D01*
X594188Y-292959D01*
X594199Y-293014D01*
X594217Y-293069D01*
X594242Y-293131D01*
X594279Y-293193D01*
X594330Y-293251D01*
X594337Y-293258D01*
X594355Y-293273D01*
X594388Y-293298D01*
X594432Y-293327D01*
X594486Y-293353D01*
X594552Y-293378D01*
X594625Y-293393D01*
X594705Y-293400D01*
X594726D01*
X594741Y-293396D01*
X594781Y-293393D01*
X594832Y-293382D01*
X594890Y-293363D01*
X594948Y-293338D01*
X595010Y-293302D01*
X595065Y-293254D01*
X595072Y-293247D01*
X595087Y-293229D01*
X595109Y-293196D01*
X595134Y-293156D01*
X595163Y-293102D01*
X595185Y-293040D01*
X595200Y-292970D01*
X595207Y-292894D01*
Y-292887D01*
Y-292872D01*
X595203Y-292847D01*
X595200Y-292814D01*
X595192Y-292774D01*
X595181Y-292730D01*
X595167Y-292687D01*
X595149Y-292639D01*
X595145Y-292636D01*
X595138Y-292617D01*
X595123Y-292596D01*
X595101Y-292570D01*
X595076Y-292537D01*
X595043Y-292505D01*
X595007Y-292475D01*
X594963Y-292446D01*
X594956Y-292443D01*
X594941Y-292435D01*
X594916Y-292424D01*
X594883Y-292413D01*
X594843Y-292403D01*
X594796Y-292392D01*
X594745Y-292384D01*
X594694Y-292381D01*
D02*
G37*
G36*
Y-293651D02*
X594686D01*
X594664Y-293655D01*
X594632Y-293658D01*
X594588Y-293666D01*
X594541Y-293680D01*
X594493Y-293698D01*
X594443Y-293728D01*
X594399Y-293764D01*
X594395Y-293768D01*
X594381Y-293786D01*
X594362Y-293808D01*
X594341Y-293840D01*
X594319Y-293880D01*
X594301Y-293928D01*
X594286Y-293982D01*
X594282Y-294041D01*
Y-294044D01*
Y-294048D01*
Y-294070D01*
X594290Y-294103D01*
X594297Y-294143D01*
X594312Y-294186D01*
X594333Y-294233D01*
X594362Y-294281D01*
X594403Y-294328D01*
X594406Y-294332D01*
X594424Y-294346D01*
X594450Y-294365D01*
X594483Y-294386D01*
X594526Y-294408D01*
X594573Y-294426D01*
X594632Y-294441D01*
X594694Y-294445D01*
X594723D01*
X594756Y-294437D01*
X594799Y-294430D01*
X594847Y-294415D01*
X594898Y-294397D01*
X594945Y-294368D01*
X594992Y-294328D01*
X594996Y-294324D01*
X595010Y-294310D01*
X595028Y-294285D01*
X595047Y-294252D01*
X595069Y-294212D01*
X595087Y-294164D01*
X595101Y-294113D01*
X595105Y-294055D01*
Y-294052D01*
Y-294048D01*
X595101Y-294026D01*
X595098Y-293993D01*
X595090Y-293953D01*
X595076Y-293906D01*
X595058Y-293859D01*
X595028Y-293808D01*
X594992Y-293764D01*
X594988Y-293760D01*
X594970Y-293746D01*
X594945Y-293728D01*
X594912Y-293709D01*
X594868Y-293688D01*
X594817Y-293669D01*
X594759Y-293655D01*
X594694Y-293651D01*
D02*
G37*
G36*
X607299Y-262196D02*
X607277D01*
X607263Y-262199D01*
X607223Y-262203D01*
X607176Y-262214D01*
X607117Y-262232D01*
X607059Y-262258D01*
X607001Y-262294D01*
X606946Y-262345D01*
X606939Y-262352D01*
X606924Y-262374D01*
X606903Y-262407D01*
X606874Y-262454D01*
X606848Y-262512D01*
X606826Y-262581D01*
X606812Y-262665D01*
X606804Y-262760D01*
Y-262764D01*
Y-262771D01*
Y-262785D01*
X606808Y-262804D01*
Y-262829D01*
X606812Y-262855D01*
X606822Y-262913D01*
X606837Y-262982D01*
X606863Y-263055D01*
X606899Y-263124D01*
X606946Y-263186D01*
Y-263189D01*
X606954Y-263193D01*
X606972Y-263211D01*
X607001Y-263237D01*
X607041Y-263266D01*
X607092Y-263291D01*
X607150Y-263317D01*
X607216Y-263335D01*
X607252Y-263342D01*
X607310D01*
X607325Y-263339D01*
X607365Y-263335D01*
X607412Y-263320D01*
X607470Y-263302D01*
X607532Y-263269D01*
X607594Y-263229D01*
X607623Y-263200D01*
X607653Y-263171D01*
Y-263168D01*
X607660Y-263164D01*
X607667Y-263153D01*
X607674Y-263142D01*
X607700Y-263106D01*
X607725Y-263055D01*
X607754Y-262993D01*
X607780Y-262916D01*
X607794Y-262829D01*
X607802Y-262734D01*
Y-262731D01*
Y-262723D01*
Y-262713D01*
X607798Y-262694D01*
Y-262672D01*
X607794Y-262651D01*
X607784Y-262596D01*
X607765Y-262534D01*
X607744Y-262469D01*
X607707Y-262403D01*
X607660Y-262345D01*
X607653Y-262338D01*
X607634Y-262323D01*
X607601Y-262298D01*
X607561Y-262272D01*
X607507Y-262243D01*
X607445Y-262217D01*
X607376Y-262203D01*
X607299Y-262196D01*
D02*
G37*
G36*
X563445Y-64909D02*
X562848D01*
X562822Y-64913D01*
X562768Y-64916D01*
X562706Y-64920D01*
X562640Y-64927D01*
X562575Y-64938D01*
X562520Y-64953D01*
X562513Y-64956D01*
X562495Y-64960D01*
X562469Y-64971D01*
X562436Y-64986D01*
X562400Y-65007D01*
X562364Y-65029D01*
X562327Y-65055D01*
X562291Y-65084D01*
X562287Y-65091D01*
X562273Y-65106D01*
X562251Y-65131D01*
X562225Y-65167D01*
X562196Y-65215D01*
X562163Y-65269D01*
X562134Y-65331D01*
X562109Y-65400D01*
Y-65404D01*
X562105Y-65411D01*
X562102Y-65422D01*
X562098Y-65437D01*
X562094Y-65455D01*
X562087Y-65481D01*
X562080Y-65506D01*
X562072Y-65535D01*
X562062Y-65608D01*
X562051Y-65692D01*
X562043Y-65786D01*
X562040Y-65888D01*
Y-65892D01*
Y-65906D01*
Y-65925D01*
X562043Y-65954D01*
Y-65987D01*
X562047Y-66023D01*
X562051Y-66067D01*
X562054Y-66110D01*
X562072Y-66208D01*
X562094Y-66310D01*
X562127Y-66405D01*
X562149Y-66452D01*
X562171Y-66492D01*
Y-66496D01*
X562178Y-66503D01*
X562185Y-66514D01*
X562192Y-66529D01*
X562222Y-66565D01*
X562258Y-66609D01*
X562305Y-66656D01*
X562360Y-66704D01*
X562422Y-66744D01*
X562487Y-66776D01*
X562495Y-66780D01*
X562513Y-66784D01*
X562546Y-66795D01*
X562593Y-66805D01*
X562651Y-66813D01*
X562724Y-66824D01*
X562768Y-66827D01*
X562815D01*
X562862Y-66831D01*
X563445D01*
Y-64909D01*
D02*
G37*
G36*
X132010Y-132914D02*
Y-133708D01*
X133138D01*
X132010Y-132914D01*
D02*
G37*
%LPD*%
D15*
X59785Y-127943D02*
Y-118494D01*
X55060Y-127943D02*
X59785D01*
X55060D02*
Y-118494D01*
X59785D01*
X56044Y-105896D02*
X67068D01*
Y-110226D02*
Y-105896D01*
X56044Y-110226D02*
X67068D01*
X56044D02*
Y-105896D01*
X546902Y-20949D02*
Y19339D01*
X631003D01*
Y-20949D02*
Y19339D01*
X546902Y-20949D02*
X631003D01*
X442815Y-165847D02*
Y-131791D01*
X402854Y-165847D02*
X442815D01*
X402854D02*
Y-131791D01*
X442815D01*
X158268Y-98710D02*
X164567D01*
Y-104419D02*
Y-98710D01*
X158268Y-104419D02*
X164567D01*
X158268D02*
Y-98710D01*
X80984Y2677D02*
X113504D01*
X80984D02*
Y21732D01*
X113504D01*
Y2677D02*
Y21732D01*
X595866Y-230906D02*
X605709D01*
Y-235236D02*
Y-230906D01*
X595866Y-235236D02*
X605709D01*
X595866D02*
Y-230906D01*
X598032Y-188273D02*
Y-183942D01*
Y-188273D02*
X607874D01*
Y-183942D01*
X598032D02*
X607874D01*
X592143Y-217456D02*
X627812D01*
Y-190251D01*
X592143D02*
X627812D01*
X592143Y-217456D02*
Y-190251D01*
X592717Y-152165D02*
Y-147835D01*
Y-152165D02*
X602559D01*
Y-147835D01*
X592717D02*
X602559D01*
X476181Y-270472D02*
Y-261024D01*
Y-270472D02*
X484449D01*
Y-261024D01*
X476181D02*
X484449D01*
X185039Y-98622D02*
X194488D01*
Y-90354D01*
X185039D02*
X194488D01*
X185039Y-98622D02*
Y-90354D01*
X170669Y-82677D02*
X207283D01*
Y4724D01*
X170669D02*
X207283D01*
X170669Y-82677D02*
Y4724D01*
X579528Y-295571D02*
Y-258957D01*
X492126D02*
X579528D01*
X492126Y-295571D02*
Y-258957D01*
Y-295571D02*
X579528D01*
X153579Y-138976D02*
Y-114173D01*
Y-138976D02*
X172871D01*
Y-114173D01*
X153579D02*
X172871D01*
X444410Y-164291D02*
X463465D01*
Y-131772D01*
X444410D02*
X463465D01*
X444410Y-164291D02*
Y-131772D01*
X466929Y-118130D02*
Y-85807D01*
X448032Y-118130D02*
X466929D01*
X448032D02*
Y-85807D01*
X466929D01*
X350787Y-121993D02*
X358946D01*
X350787D02*
Y-117771D01*
X358946D01*
Y-121993D02*
Y-117771D01*
X389079Y-114967D02*
Y-109013D01*
X392229D01*
Y-114967D02*
Y-109013D01*
X389079Y-114967D02*
X392229D01*
X358946Y-115300D02*
Y-111078D01*
X350787D02*
X358946D01*
X350787Y-115300D02*
Y-111078D01*
Y-115300D02*
X358946D01*
X380906Y-116339D02*
Y-107283D01*
X385630D01*
Y-116339D02*
Y-107283D01*
X380906Y-116339D02*
X385630D01*
X434403Y-203486D02*
Y-190215D01*
X422198Y-203486D02*
X434403D01*
X422198D02*
Y-190215D01*
X434403D01*
X44469Y3150D02*
Y22047D01*
Y3150D02*
X76791D01*
Y22047D01*
X44469D02*
X76791D01*
X369756Y-158957D02*
Y-130807D01*
X391409D01*
Y-158957D02*
Y-130807D01*
X369756Y-158957D02*
X391409D01*
X41398Y-61682D02*
Y-40029D01*
Y-61682D02*
X69547D01*
Y-40029D01*
X41398D02*
X69547D01*
X38398Y-22835D02*
Y-14961D01*
X23019D02*
X38398D01*
X23019Y-22835D02*
Y-14961D01*
Y-22835D02*
X38398D01*
X439370Y-125012D02*
X447244D01*
Y-109634D01*
X439370D02*
X447244D01*
X439370Y-125012D02*
Y-109634D01*
X452248Y-129134D02*
Y-121260D01*
Y-129134D02*
X467627D01*
Y-121260D01*
X452248D02*
X467627D01*
X377953Y-115748D02*
Y-107874D01*
X359842D02*
X377953D01*
X359842Y-115748D02*
Y-107874D01*
Y-115748D02*
X377953D01*
X330315Y-144685D02*
X362598D01*
Y-163189D02*
Y-144685D01*
X330315Y-163189D02*
X362598D01*
X330315D02*
Y-144685D01*
X330256Y-124409D02*
X362579D01*
Y-143307D02*
Y-124409D01*
X330256Y-143307D02*
X362579D01*
X330256D02*
Y-124409D01*
X41437Y-33563D02*
Y492D01*
X81398D01*
Y-33563D02*
Y492D01*
X41437Y-33563D02*
X81398D01*
X111831Y-86614D02*
Y-67716D01*
X79508D02*
X111831D01*
X79508Y-86614D02*
Y-67716D01*
Y-86614D02*
X111831D01*
X94291Y-66142D02*
Y-33858D01*
X112795D01*
Y-66142D02*
Y-33858D01*
X94291Y-66142D02*
X112795D01*
X90167Y-65660D02*
Y-57786D01*
X72056D02*
X90167D01*
X72056Y-65660D02*
Y-57786D01*
Y-65660D02*
X90167D01*
X449606Y-78543D02*
Y-74213D01*
Y-78543D02*
X459449D01*
Y-74213D01*
X449606D02*
X459449D01*
X100197Y-94291D02*
Y-89961D01*
X90354D02*
X100197D01*
X90354Y-94291D02*
Y-89961D01*
Y-94291D02*
X100197D01*
X91196Y-97495D02*
X99355D01*
Y-101717D02*
Y-97495D01*
X91196Y-101717D02*
X99355D01*
X91196D02*
Y-97495D01*
X465605Y-78489D02*
X473765D01*
X465605D02*
Y-74267D01*
X473765D01*
Y-78489D02*
Y-74267D01*
X38398Y-13780D02*
Y-5906D01*
X23019D02*
X38398D01*
X23019Y-13780D02*
Y-5906D01*
Y-13780D02*
X38398D01*
X595866Y-218307D02*
X605709D01*
Y-222638D02*
Y-218307D01*
X595866Y-222638D02*
X605709D01*
X595866D02*
Y-218307D01*
X277165Y-199409D02*
Y-191142D01*
X286614D01*
Y-199409D02*
Y-191142D01*
X277165Y-199409D02*
X286614D01*
X178382Y-130905D02*
Y-115945D01*
X186650D01*
Y-130905D02*
Y-115945D01*
X178382Y-130905D02*
X186650D01*
X170221Y-106048D02*
Y-97889D01*
X165999Y-106048D02*
X170221D01*
X165999D02*
Y-97889D01*
X170221D01*
X595866Y-224606D02*
X605709D01*
Y-228937D02*
Y-224606D01*
X595866Y-228937D02*
X605709D01*
X595866D02*
Y-224606D01*
X12819Y-239370D02*
Y-236221D01*
X6866D02*
X12819D01*
X6866Y-239370D02*
Y-236221D01*
Y-239370D02*
X12819D01*
X10063Y-350787D02*
Y-347638D01*
X4110D02*
X10063D01*
X4110Y-350787D02*
Y-347638D01*
Y-350787D02*
X10063D01*
X12598Y-295449D02*
X15748D01*
X12598Y-301402D02*
Y-295449D01*
Y-301402D02*
X15748D01*
Y-295449D01*
X14788Y-194882D02*
Y-191732D01*
X8834D02*
X14788D01*
X8834Y-194882D02*
Y-191732D01*
Y-194882D02*
X14788D01*
X321457Y-244488D02*
Y-235039D01*
Y-244488D02*
X329724D01*
Y-235039D01*
X321457D02*
X329724D01*
X23819Y-4134D02*
Y197D01*
Y-4134D02*
X33661D01*
Y197D01*
X23819D02*
X33661D01*
X23819Y2756D02*
Y7087D01*
Y2756D02*
X33661D01*
Y7087D01*
X23819D02*
X33661D01*
X23819Y9646D02*
Y13976D01*
Y9646D02*
X33661D01*
Y13976D01*
X23819D02*
X33661D01*
X23819Y16535D02*
Y20866D01*
Y16535D02*
X33661D01*
Y20866D01*
X23819D02*
X33661D01*
X146063Y-97052D02*
X150787D01*
X146063Y-106107D02*
Y-97052D01*
Y-106107D02*
X150787D01*
Y-97052D01*
X151038Y-97495D02*
X155261D01*
X151038Y-105655D02*
Y-97495D01*
Y-105655D02*
X155261D01*
Y-97495D01*
X607283Y-258169D02*
Y-255217D01*
Y-258169D02*
X613976D01*
Y-255217D01*
X607283D02*
X613976D01*
X608366Y-249216D02*
X622146D01*
Y-232796D01*
X608366D02*
X622146D01*
X608366Y-249216D02*
Y-232796D01*
X594767Y-304052D02*
Y-295948D01*
Y-304052D02*
X609957D01*
Y-295948D01*
X594767D02*
X609957D01*
X611590Y-304331D02*
Y-301181D01*
Y-304331D02*
X617544D01*
Y-301181D01*
X611590D02*
X617544D01*
X601476Y-293996D02*
Y-290256D01*
X594587D02*
X601476D01*
X594587Y-293996D02*
Y-290256D01*
Y-293996D02*
X601476D01*
X614075Y-262894D02*
Y-259154D01*
X607185D02*
X614075D01*
X607185Y-262894D02*
Y-259154D01*
Y-262894D02*
X614075D01*
X335236Y-297638D02*
Y-288189D01*
Y-297638D02*
X343504D01*
Y-288189D01*
X335236D02*
X343504D01*
X316339Y-298425D02*
Y-288976D01*
Y-298425D02*
X324606D01*
Y-288976D01*
X316339D02*
X324606D01*
X581890Y-77205D02*
Y-51929D01*
X545669D02*
X581890D01*
X545669Y-77205D02*
Y-51929D01*
Y-77205D02*
X581890D01*
X595079Y-86910D02*
X616732D01*
Y-58760D01*
X595079D02*
X616732D01*
X595079Y-86910D02*
Y-58760D01*
X138906Y-135436D02*
Y-121263D01*
X124733Y-135436D02*
X138906D01*
X124733D02*
Y-121263D01*
X138906D01*
M02*
